-- pcdb file, Rev:1.0 written by Allegro Design Entry HDL 17.2-2016 S081 (4005846) 1/11/2022 on Wed May 03 09:18:59 2023
#ISCELL
  pure_quanta quanta_title_block_c *
  *
#ISCELL
  pure_quanta quanta_title_block_c *
  *
#ISCELL
  pure_quanta quanta_title_block_c *
  *
#ISCELL
  pure_quanta quanta_title_block_c *
  *
#ISCELL
  pure_quanta quanta_title_block_c *
  *
#ISCELL
  pure_quanta quanta_title_block_c *
  *
#ISCELL
  pure_quanta quanta_title_block_c *
  *
#ISCELL
  pure_quanta quanta_title_block_c *
  *
#ISCELL
  pure_quanta quanta_title_block_c *
  *
#ISCELL
  pure_quanta quanta_title_block_c *
  *
#ISCELL
  pure_quanta quanta_title_block_c *
  *
#ISCELL
  pure_quanta quanta_title_block_c *
  *
#ISCELL
  pure_quanta quanta_title_block_c *
  *
#ISCELL
  standard offpage *
  page13_i10
#ISCELL
  standard offpage *
  page13_i11
#ISCELL
  standard offpage *
  page13_i12
#ISCELL
  standard offpage *
  page13_i13
#ISCELL
  standard offpage *
  page13_i14
#ISCELL
  standard offpage *
  page13_i15
#CELL
  pure_quanta q_res *
  page13_i16
#ISCELL
  standard offpage *
  page13_i17
#CELL
  pure_quanta q_res *
  page13_i18
#ISCELL
  standard offpage *
  page13_i19
#ISCELL
  standard offpage *
  page13_i2
#CELL
  pure_quanta q_res *
  page13_i21
#ISCELL
  standard offpage *
  page13_i22
#ISCELL
  standard offpage *
  page13_i23
#CELL
  pure_quanta q_res *
  page13_i24
#CELL
  pure_quanta q_res *
  page13_i25
#ISCELL
  standard offpage *
  page13_i26
#ISCELL
  standard offpage *
  page13_i28
#CELL
  pure_quanta q_res *
  page13_i29
#ISCELL
  standard offpage *
  page13_i3
#ISCELL
  standard offpage *
  page13_i30
#ISCELL
  standard offpage *
  page13_i31
#ISCELL
  standard offpage *
  page13_i32
#ISCELL
  standard offpage *
  page13_i33
#ISCELL
  standard offpage *
  page13_i34
#ISCELL
  standard offpage *
  page13_i35
#ISCELL
  standard offpage *
  page13_i36
#ISCELL
  standard offpage *
  page13_i37
#ISCELL
  standard offpage *
  page13_i38
#ISCELL
  standard offpage *
  page13_i39
#ISCELL
  standard offpage *
  page13_i4
#ISCELL
  standard offpage *
  page13_i40
#ISCELL
  standard offpage *
  page13_i41
#ISCELL
  standard offpage *
  page13_i42
#ISCELL
  standard offpage *
  page13_i43
#ISCELL
  standard offpage *
  page13_i44
#ISCELL
  standard offpage *
  page13_i45
#ISCELL
  standard offpage *
  page13_i5
#ISCELL
  standard offpage *
  page13_i51
#ISCELL
  standard offpage *
  page13_i53
#ISCELL
  standard offpage *
  page13_i54
#ISCELL
  standard offpage *
  page13_i55
#ISCELL
  standard offpage *
  page13_i56
#CELL
  pure_quanta socket4677_azif0045p001c01cs *
  page13_i57
#ISCELL
  standard offpage *
  page13_i58
#ISCELL
  standard offpage *
  page13_i59
#ISCELL
  standard offpage *
  page13_i6
#ISCELL
  standard offpage *
  page13_i60
#ISCELL
  standard offpage *
  page13_i7
#ISCELL
  standard offpage *
  page13_i8
#ISCELL
  standard offpage *
  page13_i9
#ISCELL
  logical_power cad_note *
  *
#ISCELL
  pure_quanta quanta_title_block_c *
  *
#CELL
  pure_quanta socket4677_azif0045p001c01cs *
  page14_i1
#CELL
  pure_quanta q_res *
  page14_i100
#ISCELL
  standard offpage *
  page14_i106
#ISCELL
  standard offpage *
  page14_i108
#CELL
  pure_quanta q_res *
  page14_i109
#ISCELL
  standard offpage *
  page14_i11
#CELL
  pure_quanta q_res *
  page14_i110
#ISCELL
  standard offpage *
  page14_i111
#ISCELL
  standard offpage *
  page14_i112
#ISCELL
  standard offpage *
  page14_i114
#CELL
  pure_quanta q_res *
  page14_i115
#ISCELL
  standard offpage *
  page14_i116
#CELL
  pure_quanta q_res *
  page14_i117
#ISCELL
  standard offpage *
  page14_i118
#ISCELL
  standard offpage *
  page14_i12
#CELL
  pure_quanta q_res *
  page14_i122
#ISCELL
  standard offpage *
  page14_i123
#ISCELL
  standard offpage *
  page14_i124
#ISCELL
  standard offpage *
  page14_i125
#ISCELL
  standard offpage *
  page14_i126
#ISCELL
  standard offpage *
  page14_i127
#CELL
  pure_quanta q_res *
  page14_i128
#ISCELL
  standard offpage *
  page14_i129
#ISCELL
  standard offpage *
  page14_i13
#ISCELL
  standard offpage *
  page14_i14
#ISCELL
  standard offpage *
  page14_i15
#ISCELL
  standard offpage *
  page14_i16
#ISCELL
  standard offpage *
  page14_i17
#ISCELL
  standard offpage *
  page14_i18
#ISCELL
  standard offpage *
  page14_i19
#ISCELL
  standard offpage *
  page14_i20
#ISCELL
  standard offpage *
  page14_i21
#ISCELL
  standard offpage *
  page14_i22
#ISCELL
  standard offpage *
  page14_i23
#ISCELL
  standard offpage *
  page14_i24
#ISCELL
  standard offpage *
  page14_i25
#ISCELL
  standard offpage *
  page14_i26
#ISCELL
  standard offpage *
  page14_i27
#ISCELL
  standard offpage *
  page14_i28
#ISCELL
  standard offpage *
  page14_i32
#ISCELL
  standard offpage *
  page14_i33
#ISCELL
  standard offpage *
  page14_i34
#ISCELL
  standard offpage *
  page14_i39
#ISCELL
  standard offpage *
  page14_i40
#ISCELL
  standard offpage *
  page14_i41
#ISCELL
  standard offpage *
  page14_i42
#ISCELL
  standard offpage *
  page14_i43
#ISCELL
  standard offpage *
  page14_i44
#ISCELL
  standard offpage *
  page14_i46
#ISCELL
  standard offpage *
  page14_i5
#ISCELL
  standard offpage *
  page14_i51
#ISCELL
  standard offpage *
  page14_i52
#ISCELL
  standard offpage *
  page14_i53
#ISCELL
  standard offpage *
  page14_i54
#ISCELL
  standard offpage *
  page14_i55
#CELL
  pure_quanta q_res *
  page14_i59
#ISCELL
  standard offpage *
  page14_i6
#CELL
  pure_quanta q_res *
  page14_i60
#CELL
  pure_quanta q_res *
  page14_i61
#CELL
  pure_quanta q_res *
  page14_i62
#CELL
  pure_quanta q_res *
  page14_i63
#CELL
  pure_quanta q_res *
  page14_i64
#ISCELL
  standard offpage *
  page14_i65
#CELL
  pure_quanta q_res *
  page14_i66
#ISCELL
  standard offpage *
  page14_i67
#ISCELL
  standard offpage *
  page14_i7
#ISCELL
  standard offpage *
  page14_i76
#CELL
  pure_quanta q_res *
  page14_i78
#CELL
  pure_quanta q_res *
  page14_i79
#ISCELL
  standard offpage *
  page14_i8
#ISCELL
  standard offpage *
  page14_i80
#ISCELL
  standard offpage *
  page14_i9
#CELL
  pure_quanta q_res *
  page14_i90
#ISCELL
  standard offpage *
  page14_i91
#ISCELL
  standard offpage *
  page14_i92
#CELL
  pure_quanta q_res *
  page14_i93
#CELL
  pure_quanta q_res *
  page14_i94
#ISCELL
  logical_power universal_power *
  page14_i95
#ISCELL
  standard offpage *
  page14_i96
#ISCELL
  standard offpage *
  page14_i97
#CELL
  pure_quanta q_res *
  page14_i98
#ISCELL
  standard offpage *
  page14_i99
#ISCELL
  pure_quanta quanta_title_block_c *
  *
#CELL
  pure_quanta socket4677_azif0045p001c01cs *
  page15_i1
#ISCELL
  standard offpage *
  page15_i10
#ISCELL
  standard offpage *
  page15_i11
#ISCELL
  standard offpage *
  page15_i13
#ISCELL
  standard offpage *
  page15_i14
#ISCELL
  standard offpage *
  page15_i15
#ISCELL
  standard offpage *
  page15_i25
#ISCELL
  standard offpage *
  page15_i3
#ISCELL
  standard offpage *
  page15_i31
#ISCELL
  standard offpage *
  page15_i4
#ISCELL
  standard offpage *
  page15_i5
#ISCELL
  standard offpage *
  page15_i6
#ISCELL
  standard offpage *
  page15_i7
#ISCELL
  standard offpage *
  page15_i8
#ISCELL
  standard offpage *
  page15_i9
#ISCELL
  pure_quanta quanta_title_block_c *
  *
#CELL
  pure_quanta socket4677_azif0045p001c01cs *
  page16_i1
#ISCELL
  standard offpage *
  page16_i10
#ISCELL
  standard offpage *
  page16_i11
#ISCELL
  standard offpage *
  page16_i12
#ISCELL
  standard offpage *
  page16_i16
#ISCELL
  standard offpage *
  page16_i18
#CELL
  pure_quanta q_res *
  page16_i19
#ISCELL
  standard offpage *
  page16_i2
#CELL
  pure_quanta q_res *
  page16_i20
#ISCELL
  standard offpage *
  page16_i21
#ISCELL
  standard offpage *
  page16_i23
#ISCELL
  standard offpage *
  page16_i24
#CELL
  pure_quanta q_res *
  page16_i25
#CELL
  pure_quanta q_res *
  page16_i26
#ISCELL
  logical_power universal_power *
  page16_i28
#ISCELL
  standard offpage *
  page16_i29
#ISCELL
  standard offpage *
  page16_i3
#ISCELL
  standard offpage *
  page16_i30
#CELL
  pure_quanta q_res *
  page16_i31
#CELL
  pure_quanta q_res *
  page16_i32
#ISCELL
  standard offpage *
  page16_i33
#ISCELL
  standard offpage *
  page16_i34
#CELL
  pure_quanta q_res *
  page16_i35
#CELL
  pure_quanta q_res *
  page16_i36
#ISCELL
  standard offpage *
  page16_i4
#ISCELL
  standard offpage *
  page16_i5
#ISCELL
  standard offpage *
  page16_i6
#ISCELL
  standard offpage *
  page16_i7
#ISCELL
  standard offpage *
  page16_i8
#ISCELL
  standard offpage *
  page16_i9
#ISCELL
  pure_quanta quanta_title_block_c *
  *
#CELL
  pure_quanta socket4677_azif0045p001c01cs *
  page17_i1
#ISCELL
  pure_quanta quanta_title_block_c *
  *
#CELL
  pure_quanta socket4677_azif0045p001c01cs *
  page18_i1
#ISCELL
  pure_quanta quanta_title_block_c *
  *
#CELL
  pure_quanta socket4677_azif0045p001c01cs *
  page19_i1
#ISCELL
  standard offpage *
  page19_i2
#ISCELL
  standard offpage *
  page19_i3
#ISCELL
  standard offpage *
  page19_i4
#ISCELL
  standard offpage *
  page19_i5
#ISCELL
  pure_quanta quanta_title_block_c *
  *
#CELL
  pure_quanta socket4677_azif0045p001c01cs *
  page20_i1
#ISCELL
  standard tap *
  page20_i10
#ISCELL
  standard tap *
  page20_i100
#ISCELL
  standard tap *
  page20_i101
#ISCELL
  standard tap *
  page20_i102
#ISCELL
  standard tap *
  page20_i103
#ISCELL
  standard tap *
  page20_i104
#ISCELL
  standard offpage *
  page20_i105
#ISCELL
  standard tap *
  page20_i106
#ISCELL
  standard tap *
  page20_i107
#ISCELL
  standard tap *
  page20_i108
#ISCELL
  standard offpage *
  page20_i109
#ISCELL
  standard tap *
  page20_i11
#ISCELL
  standard tap *
  page20_i110
#ISCELL
  standard tap *
  page20_i111
#ISCELL
  standard tap *
  page20_i112
#ISCELL
  standard tap *
  page20_i113
#ISCELL
  standard tap *
  page20_i114
#ISCELL
  standard tap *
  page20_i115
#ISCELL
  standard tap *
  page20_i116
#ISCELL
  standard tap *
  page20_i117
#ISCELL
  standard tap *
  page20_i118
#ISCELL
  standard tap *
  page20_i119
#ISCELL
  standard tap *
  page20_i12
#ISCELL
  standard tap *
  page20_i120
#ISCELL
  standard tap *
  page20_i121
#ISCELL
  standard tap *
  page20_i122
#ISCELL
  standard tap *
  page20_i123
#ISCELL
  standard tap *
  page20_i124
#ISCELL
  standard tap *
  page20_i125
#ISCELL
  standard tap *
  page20_i126
#ISCELL
  standard tap *
  page20_i127
#ISCELL
  standard tap *
  page20_i128
#ISCELL
  standard tap *
  page20_i129
#ISCELL
  standard tap *
  page20_i13
#ISCELL
  standard tap *
  page20_i130
#ISCELL
  standard tap *
  page20_i131
#ISCELL
  standard tap *
  page20_i132
#ISCELL
  standard tap *
  page20_i133
#ISCELL
  standard offpage *
  page20_i134
#ISCELL
  standard offpage *
  page20_i135
#ISCELL
  standard offpage *
  page20_i136
#ISCELL
  standard offpage *
  page20_i137
#ISCELL
  standard tap *
  page20_i138
#ISCELL
  standard tap *
  page20_i139
#ISCELL
  standard tap *
  page20_i14
#ISCELL
  standard tap *
  page20_i140
#ISCELL
  standard tap *
  page20_i141
#ISCELL
  standard tap *
  page20_i142
#ISCELL
  standard tap *
  page20_i143
#ISCELL
  standard tap *
  page20_i144
#ISCELL
  standard tap *
  page20_i147
#ISCELL
  standard tap *
  page20_i148
#ISCELL
  standard tap *
  page20_i149
#ISCELL
  standard tap *
  page20_i15
#ISCELL
  standard tap *
  page20_i150
#ISCELL
  standard offpage *
  page20_i151
#ISCELL
  standard offpage *
  page20_i152
#ISCELL
  standard tap *
  page20_i153
#ISCELL
  standard tap *
  page20_i154
#ISCELL
  standard tap *
  page20_i155
#ISCELL
  standard tap *
  page20_i156
#ISCELL
  standard offpage *
  page20_i157
#ISCELL
  standard offpage *
  page20_i158
#ISCELL
  standard offpage *
  page20_i159
#ISCELL
  standard tap *
  page20_i16
#ISCELL
  standard offpage *
  page20_i160
#ISCELL
  standard offpage *
  page20_i161
#ISCELL
  standard tap *
  page20_i162
#ISCELL
  standard tap *
  page20_i163
#ISCELL
  standard tap *
  page20_i164
#ISCELL
  standard tap *
  page20_i165
#ISCELL
  standard tap *
  page20_i166
#ISCELL
  standard tap *
  page20_i167
#ISCELL
  standard tap *
  page20_i168
#ISCELL
  standard tap *
  page20_i169
#ISCELL
  standard tap *
  page20_i17
#ISCELL
  standard offpage *
  page20_i170
#ISCELL
  standard tap *
  page20_i171
#ISCELL
  standard tap *
  page20_i172
#ISCELL
  standard tap *
  page20_i175
#ISCELL
  standard tap *
  page20_i176
#ISCELL
  standard offpage *
  page20_i177
#ISCELL
  standard offpage *
  page20_i178
#ISCELL
  standard tap *
  page20_i18
#ISCELL
  standard tap *
  page20_i19
#ISCELL
  standard offpage *
  page20_i2
#ISCELL
  standard tap *
  page20_i20
#ISCELL
  standard tap *
  page20_i21
#ISCELL
  standard tap *
  page20_i22
#ISCELL
  standard tap *
  page20_i23
#ISCELL
  standard tap *
  page20_i24
#ISCELL
  standard tap *
  page20_i25
#ISCELL
  standard tap *
  page20_i26
#ISCELL
  standard tap *
  page20_i27
#ISCELL
  standard tap *
  page20_i28
#ISCELL
  standard tap *
  page20_i29
#ISCELL
  standard tap *
  page20_i3
#ISCELL
  standard tap *
  page20_i30
#ISCELL
  standard tap *
  page20_i31
#ISCELL
  standard tap *
  page20_i32
#ISCELL
  standard tap *
  page20_i33
#ISCELL
  standard tap *
  page20_i34
#ISCELL
  standard tap *
  page20_i35
#ISCELL
  standard tap *
  page20_i36
#ISCELL
  standard tap *
  page20_i37
#ISCELL
  standard offpage *
  page20_i38
#ISCELL
  standard tap *
  page20_i39
#ISCELL
  standard tap *
  page20_i4
#ISCELL
  standard tap *
  page20_i40
#ISCELL
  standard tap *
  page20_i41
#ISCELL
  standard tap *
  page20_i42
#ISCELL
  standard tap *
  page20_i43
#ISCELL
  standard tap *
  page20_i44
#ISCELL
  standard tap *
  page20_i45
#ISCELL
  standard tap *
  page20_i46
#ISCELL
  standard tap *
  page20_i47
#ISCELL
  standard tap *
  page20_i48
#ISCELL
  standard tap *
  page20_i49
#ISCELL
  standard tap *
  page20_i5
#ISCELL
  standard tap *
  page20_i50
#ISCELL
  standard tap *
  page20_i51
#ISCELL
  standard tap *
  page20_i52
#ISCELL
  standard tap *
  page20_i53
#ISCELL
  standard tap *
  page20_i54
#ISCELL
  standard tap *
  page20_i55
#ISCELL
  standard tap *
  page20_i56
#ISCELL
  standard tap *
  page20_i57
#ISCELL
  standard tap *
  page20_i58
#ISCELL
  standard tap *
  page20_i59
#ISCELL
  standard tap *
  page20_i6
#ISCELL
  standard tap *
  page20_i60
#ISCELL
  standard tap *
  page20_i61
#ISCELL
  standard tap *
  page20_i62
#ISCELL
  standard tap *
  page20_i63
#ISCELL
  standard tap *
  page20_i64
#ISCELL
  standard tap *
  page20_i65
#ISCELL
  standard tap *
  page20_i66
#ISCELL
  standard tap *
  page20_i67
#ISCELL
  standard tap *
  page20_i68
#ISCELL
  standard tap *
  page20_i69
#ISCELL
  standard tap *
  page20_i7
#ISCELL
  standard tap *
  page20_i70
#ISCELL
  standard tap *
  page20_i71
#ISCELL
  standard tap *
  page20_i72
#ISCELL
  standard tap *
  page20_i73
#ISCELL
  standard offpage *
  page20_i74
#ISCELL
  standard tap *
  page20_i75
#ISCELL
  standard tap *
  page20_i76
#ISCELL
  standard tap *
  page20_i8
#ISCELL
  standard tap *
  page20_i82
#ISCELL
  standard tap *
  page20_i84
#ISCELL
  standard tap *
  page20_i85
#ISCELL
  standard tap *
  page20_i86
#ISCELL
  standard tap *
  page20_i87
#ISCELL
  standard tap *
  page20_i88
#ISCELL
  standard tap *
  page20_i89
#ISCELL
  standard tap *
  page20_i9
#ISCELL
  standard tap *
  page20_i90
#ISCELL
  standard tap *
  page20_i91
#ISCELL
  standard tap *
  page20_i92
#ISCELL
  standard offpage *
  page20_i93
#ISCELL
  standard tap *
  page20_i94
#ISCELL
  standard offpage *
  page20_i95
#ISCELL
  standard tap *
  page20_i96
#ISCELL
  standard tap *
  page20_i97
#ISCELL
  standard tap *
  page20_i98
#ISCELL
  standard tap *
  page20_i99
#ISCELL
  pure_quanta quanta_title_block_c *
  *
#ISCELL
  standard tap *
  page21_i10
#ISCELL
  standard tap *
  page21_i100
#ISCELL
  standard tap *
  page21_i101
#ISCELL
  standard tap *
  page21_i102
#ISCELL
  standard tap *
  page21_i103
#ISCELL
  standard tap *
  page21_i104
#ISCELL
  standard tap *
  page21_i105
#ISCELL
  standard tap *
  page21_i106
#ISCELL
  standard tap *
  page21_i107
#ISCELL
  standard tap *
  page21_i108
#ISCELL
  standard tap *
  page21_i109
#ISCELL
  standard tap *
  page21_i11
#ISCELL
  standard tap *
  page21_i110
#ISCELL
  standard tap *
  page21_i111
#ISCELL
  standard tap *
  page21_i112
#ISCELL
  standard tap *
  page21_i113
#ISCELL
  standard tap *
  page21_i114
#ISCELL
  standard offpage *
  page21_i115
#ISCELL
  standard offpage *
  page21_i116
#ISCELL
  standard offpage *
  page21_i117
#ISCELL
  standard offpage *
  page21_i118
#ISCELL
  standard offpage *
  page21_i119
#ISCELL
  standard tap *
  page21_i12
#ISCELL
  standard offpage *
  page21_i120
#ISCELL
  standard offpage *
  page21_i121
#ISCELL
  standard offpage *
  page21_i122
#ISCELL
  standard offpage *
  page21_i123
#ISCELL
  standard offpage *
  page21_i124
#ISCELL
  standard tap *
  page21_i125
#ISCELL
  standard tap *
  page21_i126
#ISCELL
  standard tap *
  page21_i127
#ISCELL
  standard tap *
  page21_i128
#ISCELL
  standard tap *
  page21_i129
#ISCELL
  standard tap *
  page21_i13
#ISCELL
  standard tap *
  page21_i130
#ISCELL
  standard tap *
  page21_i131
#ISCELL
  standard tap *
  page21_i132
#ISCELL
  standard tap *
  page21_i133
#ISCELL
  standard tap *
  page21_i134
#ISCELL
  standard tap *
  page21_i135
#ISCELL
  standard tap *
  page21_i136
#ISCELL
  standard tap *
  page21_i137
#ISCELL
  standard tap *
  page21_i138
#ISCELL
  standard tap *
  page21_i139
#ISCELL
  standard tap *
  page21_i14
#ISCELL
  standard tap *
  page21_i140
#ISCELL
  standard tap *
  page21_i141
#ISCELL
  standard tap *
  page21_i142
#ISCELL
  standard tap *
  page21_i143
#ISCELL
  standard tap *
  page21_i144
#ISCELL
  standard tap *
  page21_i145
#ISCELL
  standard tap *
  page21_i146
#ISCELL
  standard tap *
  page21_i147
#ISCELL
  standard tap *
  page21_i148
#ISCELL
  standard tap *
  page21_i149
#ISCELL
  standard tap *
  page21_i15
#ISCELL
  standard tap *
  page21_i150
#ISCELL
  standard tap *
  page21_i151
#ISCELL
  standard tap *
  page21_i152
#ISCELL
  standard tap *
  page21_i153
#ISCELL
  standard tap *
  page21_i154
#ISCELL
  standard tap *
  page21_i155
#ISCELL
  standard tap *
  page21_i156
#ISCELL
  standard tap *
  page21_i157
#ISCELL
  standard tap *
  page21_i158
#ISCELL
  standard tap *
  page21_i159
#ISCELL
  standard tap *
  page21_i16
#ISCELL
  standard tap *
  page21_i160
#ISCELL
  standard tap *
  page21_i161
#ISCELL
  standard offpage *
  page21_i162
#ISCELL
  standard offpage *
  page21_i163
#ISCELL
  standard offpage *
  page21_i164
#ISCELL
  standard tap *
  page21_i165
#ISCELL
  standard tap *
  page21_i166
#ISCELL
  standard tap *
  page21_i167
#ISCELL
  standard offpage *
  page21_i168
#CELL
  pure_quanta socket4677_azif0045p001c01cs *
  page21_i169
#ISCELL
  standard tap *
  page21_i17
#ISCELL
  standard tap *
  page21_i18
#ISCELL
  standard tap *
  page21_i19
#ISCELL
  standard tap *
  page21_i2
#ISCELL
  standard tap *
  page21_i20
#ISCELL
  standard tap *
  page21_i21
#ISCELL
  standard tap *
  page21_i22
#ISCELL
  standard tap *
  page21_i23
#ISCELL
  standard tap *
  page21_i24
#ISCELL
  standard tap *
  page21_i25
#ISCELL
  standard tap *
  page21_i26
#ISCELL
  standard tap *
  page21_i27
#ISCELL
  standard tap *
  page21_i28
#ISCELL
  standard tap *
  page21_i29
#ISCELL
  standard offpage *
  page21_i3
#ISCELL
  standard tap *
  page21_i30
#ISCELL
  standard tap *
  page21_i31
#ISCELL
  standard tap *
  page21_i32
#ISCELL
  standard tap *
  page21_i33
#ISCELL
  standard tap *
  page21_i34
#ISCELL
  standard tap *
  page21_i35
#ISCELL
  standard tap *
  page21_i36
#ISCELL
  standard tap *
  page21_i37
#ISCELL
  standard tap *
  page21_i38
#ISCELL
  standard tap *
  page21_i39
#ISCELL
  standard offpage *
  page21_i4
#ISCELL
  standard tap *
  page21_i40
#ISCELL
  standard tap *
  page21_i41
#ISCELL
  standard tap *
  page21_i42
#ISCELL
  standard tap *
  page21_i43
#ISCELL
  standard tap *
  page21_i44
#ISCELL
  standard offpage *
  page21_i45
#ISCELL
  standard offpage *
  page21_i46
#ISCELL
  standard tap *
  page21_i47
#ISCELL
  standard tap *
  page21_i48
#ISCELL
  standard tap *
  page21_i49
#ISCELL
  standard offpage *
  page21_i5
#ISCELL
  standard tap *
  page21_i50
#ISCELL
  standard tap *
  page21_i51
#ISCELL
  standard tap *
  page21_i52
#ISCELL
  standard tap *
  page21_i53
#ISCELL
  standard tap *
  page21_i54
#ISCELL
  standard tap *
  page21_i55
#ISCELL
  standard tap *
  page21_i56
#ISCELL
  standard tap *
  page21_i57
#ISCELL
  standard tap *
  page21_i58
#ISCELL
  standard tap *
  page21_i59
#ISCELL
  standard tap *
  page21_i6
#ISCELL
  standard tap *
  page21_i60
#ISCELL
  standard tap *
  page21_i61
#ISCELL
  standard tap *
  page21_i62
#ISCELL
  standard tap *
  page21_i63
#ISCELL
  standard tap *
  page21_i64
#ISCELL
  standard tap *
  page21_i65
#ISCELL
  standard tap *
  page21_i66
#ISCELL
  standard tap *
  page21_i67
#ISCELL
  standard tap *
  page21_i68
#ISCELL
  standard tap *
  page21_i69
#ISCELL
  standard tap *
  page21_i7
#ISCELL
  standard tap *
  page21_i70
#ISCELL
  standard tap *
  page21_i71
#ISCELL
  standard tap *
  page21_i72
#ISCELL
  standard tap *
  page21_i73
#ISCELL
  standard tap *
  page21_i74
#ISCELL
  standard tap *
  page21_i75
#ISCELL
  standard tap *
  page21_i76
#ISCELL
  standard tap *
  page21_i77
#ISCELL
  standard tap *
  page21_i78
#ISCELL
  standard tap *
  page21_i79
#ISCELL
  standard tap *
  page21_i8
#ISCELL
  standard tap *
  page21_i80
#ISCELL
  standard tap *
  page21_i81
#ISCELL
  standard tap *
  page21_i82
#ISCELL
  standard tap *
  page21_i83
#ISCELL
  standard tap *
  page21_i84
#ISCELL
  standard tap *
  page21_i85
#ISCELL
  standard tap *
  page21_i86
#ISCELL
  standard tap *
  page21_i87
#ISCELL
  standard offpage *
  page21_i88
#ISCELL
  standard tap *
  page21_i89
#ISCELL
  standard tap *
  page21_i9
#ISCELL
  standard tap *
  page21_i90
#ISCELL
  standard tap *
  page21_i91
#ISCELL
  standard offpage *
  page21_i92
#ISCELL
  standard tap *
  page21_i93
#ISCELL
  standard tap *
  page21_i94
#ISCELL
  standard tap *
  page21_i95
#ISCELL
  standard tap *
  page21_i96
#ISCELL
  standard tap *
  page21_i97
#ISCELL
  standard tap *
  page21_i98
#ISCELL
  standard tap *
  page21_i99
#ISCELL
  pure_quanta quanta_title_block_c *
  *
#ISCELL
  standard offpage *
  page22_i1
#ISCELL
  standard tap *
  page22_i10
#ISCELL
  standard tap *
  page22_i100
#ISCELL
  standard tap *
  page22_i101
#ISCELL
  standard tap *
  page22_i102
#ISCELL
  standard tap *
  page22_i103
#ISCELL
  standard tap *
  page22_i104
#ISCELL
  standard tap *
  page22_i105
#ISCELL
  standard tap *
  page22_i106
#ISCELL
  standard tap *
  page22_i107
#ISCELL
  standard tap *
  page22_i108
#ISCELL
  standard tap *
  page22_i109
#ISCELL
  standard tap *
  page22_i11
#ISCELL
  standard tap *
  page22_i110
#ISCELL
  standard tap *
  page22_i111
#ISCELL
  standard tap *
  page22_i112
#ISCELL
  standard tap *
  page22_i113
#ISCELL
  standard tap *
  page22_i114
#ISCELL
  standard tap *
  page22_i115
#ISCELL
  standard tap *
  page22_i116
#ISCELL
  standard tap *
  page22_i117
#ISCELL
  standard tap *
  page22_i118
#ISCELL
  standard tap *
  page22_i119
#ISCELL
  standard tap *
  page22_i12
#ISCELL
  standard tap *
  page22_i120
#ISCELL
  standard tap *
  page22_i121
#ISCELL
  standard tap *
  page22_i122
#ISCELL
  standard tap *
  page22_i123
#ISCELL
  standard tap *
  page22_i124
#ISCELL
  standard tap *
  page22_i125
#ISCELL
  standard tap *
  page22_i126
#ISCELL
  standard tap *
  page22_i127
#ISCELL
  standard tap *
  page22_i128
#ISCELL
  standard tap *
  page22_i129
#ISCELL
  standard tap *
  page22_i13
#ISCELL
  standard tap *
  page22_i130
#ISCELL
  standard tap *
  page22_i131
#ISCELL
  standard tap *
  page22_i132
#ISCELL
  standard tap *
  page22_i133
#ISCELL
  standard tap *
  page22_i134
#ISCELL
  standard tap *
  page22_i135
#ISCELL
  standard tap *
  page22_i136
#ISCELL
  standard tap *
  page22_i137
#ISCELL
  standard tap *
  page22_i138
#ISCELL
  standard tap *
  page22_i139
#ISCELL
  standard tap *
  page22_i14
#ISCELL
  standard tap *
  page22_i140
#ISCELL
  standard tap *
  page22_i141
#ISCELL
  standard tap *
  page22_i142
#ISCELL
  standard tap *
  page22_i143
#ISCELL
  standard tap *
  page22_i144
#ISCELL
  standard tap *
  page22_i145
#ISCELL
  standard tap *
  page22_i146
#ISCELL
  standard tap *
  page22_i147
#ISCELL
  standard tap *
  page22_i148
#ISCELL
  standard tap *
  page22_i149
#ISCELL
  standard tap *
  page22_i15
#ISCELL
  standard tap *
  page22_i150
#ISCELL
  standard tap *
  page22_i151
#ISCELL
  standard tap *
  page22_i152
#ISCELL
  standard tap *
  page22_i153
#ISCELL
  standard tap *
  page22_i154
#ISCELL
  standard tap *
  page22_i155
#ISCELL
  standard tap *
  page22_i156
#ISCELL
  standard tap *
  page22_i157
#ISCELL
  standard offpage *
  page22_i158
#ISCELL
  standard offpage *
  page22_i159
#ISCELL
  standard tap *
  page22_i16
#ISCELL
  standard offpage *
  page22_i160
#ISCELL
  standard offpage *
  page22_i161
#ISCELL
  standard offpage *
  page22_i162
#ISCELL
  standard offpage *
  page22_i163
#ISCELL
  standard offpage *
  page22_i164
#ISCELL
  standard offpage *
  page22_i165
#ISCELL
  standard offpage *
  page22_i166
#ISCELL
  standard offpage *
  page22_i167
#ISCELL
  standard offpage *
  page22_i168
#CELL
  pure_quanta socket4677_azif0045p001c01cs *
  page22_i169
#ISCELL
  standard tap *
  page22_i17
#ISCELL
  standard tap *
  page22_i18
#ISCELL
  standard tap *
  page22_i19
#ISCELL
  standard offpage *
  page22_i2
#ISCELL
  standard tap *
  page22_i20
#ISCELL
  standard tap *
  page22_i21
#ISCELL
  standard tap *
  page22_i22
#ISCELL
  standard tap *
  page22_i23
#ISCELL
  standard tap *
  page22_i24
#ISCELL
  standard tap *
  page22_i25
#ISCELL
  standard tap *
  page22_i26
#ISCELL
  standard tap *
  page22_i27
#ISCELL
  standard tap *
  page22_i28
#ISCELL
  standard tap *
  page22_i29
#ISCELL
  standard tap *
  page22_i3
#ISCELL
  standard tap *
  page22_i30
#ISCELL
  standard tap *
  page22_i31
#ISCELL
  standard tap *
  page22_i32
#ISCELL
  standard tap *
  page22_i33
#ISCELL
  standard tap *
  page22_i34
#ISCELL
  standard tap *
  page22_i35
#ISCELL
  standard tap *
  page22_i36
#ISCELL
  standard tap *
  page22_i37
#ISCELL
  standard tap *
  page22_i38
#ISCELL
  standard tap *
  page22_i39
#ISCELL
  standard tap *
  page22_i4
#ISCELL
  standard tap *
  page22_i40
#ISCELL
  standard tap *
  page22_i41
#ISCELL
  standard tap *
  page22_i42
#ISCELL
  standard tap *
  page22_i43
#ISCELL
  standard tap *
  page22_i44
#ISCELL
  standard tap *
  page22_i45
#ISCELL
  standard tap *
  page22_i46
#ISCELL
  standard tap *
  page22_i47
#ISCELL
  standard tap *
  page22_i48
#ISCELL
  standard tap *
  page22_i49
#ISCELL
  standard tap *
  page22_i5
#ISCELL
  standard offpage *
  page22_i50
#ISCELL
  standard offpage *
  page22_i51
#ISCELL
  standard tap *
  page22_i52
#ISCELL
  standard tap *
  page22_i53
#ISCELL
  standard tap *
  page22_i54
#ISCELL
  standard tap *
  page22_i55
#ISCELL
  standard tap *
  page22_i56
#ISCELL
  standard tap *
  page22_i57
#ISCELL
  standard tap *
  page22_i58
#ISCELL
  standard tap *
  page22_i59
#ISCELL
  standard tap *
  page22_i6
#ISCELL
  standard tap *
  page22_i60
#ISCELL
  standard tap *
  page22_i61
#ISCELL
  standard tap *
  page22_i62
#ISCELL
  standard tap *
  page22_i63
#ISCELL
  standard tap *
  page22_i64
#ISCELL
  standard tap *
  page22_i65
#ISCELL
  standard tap *
  page22_i66
#ISCELL
  standard tap *
  page22_i67
#ISCELL
  standard tap *
  page22_i68
#ISCELL
  standard tap *
  page22_i69
#ISCELL
  standard offpage *
  page22_i7
#ISCELL
  standard tap *
  page22_i70
#ISCELL
  standard tap *
  page22_i71
#ISCELL
  standard tap *
  page22_i72
#ISCELL
  standard tap *
  page22_i73
#ISCELL
  standard tap *
  page22_i74
#ISCELL
  standard tap *
  page22_i75
#ISCELL
  standard tap *
  page22_i76
#ISCELL
  standard tap *
  page22_i77
#ISCELL
  standard tap *
  page22_i78
#ISCELL
  standard tap *
  page22_i79
#ISCELL
  standard offpage *
  page22_i8
#ISCELL
  standard tap *
  page22_i80
#ISCELL
  standard tap *
  page22_i81
#ISCELL
  standard tap *
  page22_i82
#ISCELL
  standard tap *
  page22_i83
#ISCELL
  standard tap *
  page22_i84
#ISCELL
  standard tap *
  page22_i85
#ISCELL
  standard tap *
  page22_i86
#ISCELL
  standard tap *
  page22_i87
#ISCELL
  standard tap *
  page22_i88
#ISCELL
  standard tap *
  page22_i89
#ISCELL
  standard tap *
  page22_i9
#ISCELL
  standard tap *
  page22_i90
#ISCELL
  standard offpage *
  page22_i92
#ISCELL
  standard offpage *
  page22_i93
#ISCELL
  standard offpage *
  page22_i94
#ISCELL
  standard offpage *
  page22_i95
#ISCELL
  standard tap *
  page22_i96
#ISCELL
  standard tap *
  page22_i97
#ISCELL
  standard tap *
  page22_i98
#ISCELL
  standard tap *
  page22_i99
#ISCELL
  pure_quanta quanta_title_block_c *
  *
#ISCELL
  standard offpage *
  page23_i1
#ISCELL
  standard tap *
  page23_i10
#ISCELL
  standard tap *
  page23_i100
#ISCELL
  standard tap *
  page23_i101
#ISCELL
  standard tap *
  page23_i102
#ISCELL
  standard tap *
  page23_i103
#ISCELL
  standard tap *
  page23_i104
#ISCELL
  standard tap *
  page23_i105
#ISCELL
  standard tap *
  page23_i106
#ISCELL
  standard tap *
  page23_i107
#ISCELL
  standard tap *
  page23_i108
#ISCELL
  standard tap *
  page23_i109
#ISCELL
  standard tap *
  page23_i11
#ISCELL
  standard tap *
  page23_i110
#ISCELL
  standard tap *
  page23_i111
#ISCELL
  standard tap *
  page23_i112
#ISCELL
  standard tap *
  page23_i113
#ISCELL
  standard tap *
  page23_i114
#ISCELL
  standard tap *
  page23_i115
#ISCELL
  standard tap *
  page23_i116
#ISCELL
  standard tap *
  page23_i117
#ISCELL
  standard tap *
  page23_i118
#ISCELL
  standard tap *
  page23_i119
#ISCELL
  standard tap *
  page23_i12
#ISCELL
  standard tap *
  page23_i120
#ISCELL
  standard tap *
  page23_i121
#ISCELL
  standard tap *
  page23_i122
#ISCELL
  standard tap *
  page23_i123
#ISCELL
  standard tap *
  page23_i124
#ISCELL
  standard tap *
  page23_i125
#ISCELL
  standard tap *
  page23_i126
#ISCELL
  standard tap *
  page23_i127
#ISCELL
  standard tap *
  page23_i128
#ISCELL
  standard tap *
  page23_i129
#ISCELL
  standard tap *
  page23_i13
#ISCELL
  standard tap *
  page23_i130
#ISCELL
  standard tap *
  page23_i131
#ISCELL
  standard tap *
  page23_i132
#ISCELL
  standard tap *
  page23_i133
#ISCELL
  standard tap *
  page23_i134
#ISCELL
  standard tap *
  page23_i135
#ISCELL
  standard tap *
  page23_i136
#ISCELL
  standard tap *
  page23_i137
#ISCELL
  standard tap *
  page23_i138
#ISCELL
  standard tap *
  page23_i139
#ISCELL
  standard offpage *
  page23_i14
#ISCELL
  standard tap *
  page23_i140
#ISCELL
  standard tap *
  page23_i141
#ISCELL
  standard tap *
  page23_i142
#ISCELL
  standard tap *
  page23_i143
#ISCELL
  standard tap *
  page23_i144
#ISCELL
  standard tap *
  page23_i145
#ISCELL
  standard tap *
  page23_i146
#ISCELL
  standard tap *
  page23_i147
#ISCELL
  standard tap *
  page23_i148
#ISCELL
  standard tap *
  page23_i149
#ISCELL
  standard offpage *
  page23_i15
#ISCELL
  standard tap *
  page23_i150
#ISCELL
  standard tap *
  page23_i151
#ISCELL
  standard tap *
  page23_i152
#ISCELL
  standard tap *
  page23_i153
#ISCELL
  standard tap *
  page23_i154
#ISCELL
  standard tap *
  page23_i155
#ISCELL
  standard tap *
  page23_i156
#ISCELL
  standard tap *
  page23_i157
#ISCELL
  standard tap *
  page23_i158
#ISCELL
  standard offpage *
  page23_i159
#ISCELL
  standard offpage *
  page23_i16
#ISCELL
  standard offpage *
  page23_i160
#ISCELL
  standard offpage *
  page23_i161
#ISCELL
  standard offpage *
  page23_i162
#ISCELL
  standard offpage *
  page23_i163
#ISCELL
  standard offpage *
  page23_i164
#ISCELL
  standard offpage *
  page23_i165
#ISCELL
  standard offpage *
  page23_i166
#ISCELL
  standard offpage *
  page23_i167
#ISCELL
  standard offpage *
  page23_i168
#CELL
  pure_quanta socket4677_azif0045p001c01cs *
  page23_i169
#ISCELL
  standard tap *
  page23_i17
#ISCELL
  standard tap *
  page23_i18
#ISCELL
  standard tap *
  page23_i19
#ISCELL
  standard offpage *
  page23_i2
#ISCELL
  standard tap *
  page23_i20
#ISCELL
  standard tap *
  page23_i21
#ISCELL
  standard tap *
  page23_i22
#ISCELL
  standard tap *
  page23_i23
#ISCELL
  standard tap *
  page23_i24
#ISCELL
  standard tap *
  page23_i25
#ISCELL
  standard tap *
  page23_i26
#ISCELL
  standard tap *
  page23_i27
#ISCELL
  standard tap *
  page23_i28
#ISCELL
  standard tap *
  page23_i29
#ISCELL
  standard tap *
  page23_i3
#ISCELL
  standard tap *
  page23_i30
#ISCELL
  standard tap *
  page23_i31
#ISCELL
  standard tap *
  page23_i32
#ISCELL
  standard tap *
  page23_i33
#ISCELL
  standard tap *
  page23_i34
#ISCELL
  standard tap *
  page23_i35
#ISCELL
  standard tap *
  page23_i36
#ISCELL
  standard tap *
  page23_i37
#ISCELL
  standard tap *
  page23_i38
#ISCELL
  standard tap *
  page23_i39
#ISCELL
  standard tap *
  page23_i4
#ISCELL
  standard tap *
  page23_i40
#ISCELL
  standard tap *
  page23_i41
#ISCELL
  standard tap *
  page23_i42
#ISCELL
  standard tap *
  page23_i43
#ISCELL
  standard tap *
  page23_i44
#ISCELL
  standard tap *
  page23_i45
#ISCELL
  standard tap *
  page23_i46
#ISCELL
  standard tap *
  page23_i47
#ISCELL
  standard tap *
  page23_i48
#ISCELL
  standard tap *
  page23_i49
#ISCELL
  standard tap *
  page23_i5
#ISCELL
  standard tap *
  page23_i50
#ISCELL
  standard tap *
  page23_i51
#ISCELL
  standard tap *
  page23_i52
#ISCELL
  standard tap *
  page23_i53
#ISCELL
  standard tap *
  page23_i54
#ISCELL
  standard tap *
  page23_i55
#ISCELL
  standard tap *
  page23_i56
#ISCELL
  standard offpage *
  page23_i57
#ISCELL
  standard tap *
  page23_i58
#ISCELL
  standard tap *
  page23_i59
#ISCELL
  standard tap *
  page23_i6
#ISCELL
  standard tap *
  page23_i60
#ISCELL
  standard tap *
  page23_i61
#ISCELL
  standard tap *
  page23_i62
#ISCELL
  standard tap *
  page23_i63
#ISCELL
  standard tap *
  page23_i64
#ISCELL
  standard tap *
  page23_i65
#ISCELL
  standard tap *
  page23_i66
#ISCELL
  standard tap *
  page23_i67
#ISCELL
  standard tap *
  page23_i68
#ISCELL
  standard tap *
  page23_i69
#ISCELL
  standard tap *
  page23_i7
#ISCELL
  standard tap *
  page23_i70
#ISCELL
  standard tap *
  page23_i71
#ISCELL
  standard tap *
  page23_i72
#ISCELL
  standard tap *
  page23_i73
#ISCELL
  standard tap *
  page23_i74
#ISCELL
  standard tap *
  page23_i75
#ISCELL
  standard tap *
  page23_i76
#ISCELL
  standard tap *
  page23_i77
#ISCELL
  standard tap *
  page23_i78
#ISCELL
  standard tap *
  page23_i79
#ISCELL
  standard tap *
  page23_i8
#ISCELL
  standard tap *
  page23_i80
#ISCELL
  standard tap *
  page23_i81
#ISCELL
  standard tap *
  page23_i82
#ISCELL
  standard tap *
  page23_i83
#ISCELL
  standard tap *
  page23_i84
#ISCELL
  standard tap *
  page23_i85
#ISCELL
  standard tap *
  page23_i86
#ISCELL
  standard tap *
  page23_i87
#ISCELL
  standard tap *
  page23_i88
#ISCELL
  standard tap *
  page23_i89
#ISCELL
  standard tap *
  page23_i9
#ISCELL
  standard tap *
  page23_i90
#ISCELL
  standard tap *
  page23_i92
#ISCELL
  standard tap *
  page23_i93
#ISCELL
  standard tap *
  page23_i94
#ISCELL
  standard offpage *
  page23_i95
#ISCELL
  standard offpage *
  page23_i96
#ISCELL
  standard offpage *
  page23_i97
#ISCELL
  standard offpage *
  page23_i98
#ISCELL
  standard offpage *
  page23_i99
#ISCELL
  pure_quanta quanta_title_block_c *
  *
#ISCELL
  standard offpage *
  page24_i1
#ISCELL
  standard offpage *
  page24_i10
#ISCELL
  standard tap *
  page24_i100
#ISCELL
  standard tap *
  page24_i101
#ISCELL
  standard tap *
  page24_i102
#ISCELL
  standard tap *
  page24_i103
#ISCELL
  standard tap *
  page24_i104
#ISCELL
  standard tap *
  page24_i105
#ISCELL
  standard tap *
  page24_i106
#ISCELL
  standard tap *
  page24_i107
#ISCELL
  standard tap *
  page24_i108
#ISCELL
  standard tap *
  page24_i109
#ISCELL
  standard tap *
  page24_i11
#ISCELL
  standard tap *
  page24_i110
#ISCELL
  standard tap *
  page24_i111
#ISCELL
  standard tap *
  page24_i112
#ISCELL
  standard tap *
  page24_i113
#ISCELL
  standard tap *
  page24_i114
#ISCELL
  standard tap *
  page24_i115
#ISCELL
  standard tap *
  page24_i116
#ISCELL
  standard tap *
  page24_i117
#ISCELL
  standard tap *
  page24_i118
#ISCELL
  standard tap *
  page24_i119
#ISCELL
  standard tap *
  page24_i12
#ISCELL
  standard tap *
  page24_i120
#ISCELL
  standard tap *
  page24_i121
#ISCELL
  standard tap *
  page24_i122
#ISCELL
  standard tap *
  page24_i123
#ISCELL
  standard tap *
  page24_i124
#ISCELL
  standard tap *
  page24_i125
#ISCELL
  standard tap *
  page24_i126
#ISCELL
  standard tap *
  page24_i127
#ISCELL
  standard tap *
  page24_i128
#ISCELL
  standard tap *
  page24_i129
#ISCELL
  standard tap *
  page24_i13
#ISCELL
  standard tap *
  page24_i130
#ISCELL
  standard tap *
  page24_i131
#ISCELL
  standard tap *
  page24_i132
#ISCELL
  standard tap *
  page24_i133
#ISCELL
  standard tap *
  page24_i134
#ISCELL
  standard tap *
  page24_i135
#ISCELL
  standard tap *
  page24_i136
#ISCELL
  standard tap *
  page24_i137
#ISCELL
  standard tap *
  page24_i138
#ISCELL
  standard tap *
  page24_i139
#ISCELL
  standard tap *
  page24_i14
#ISCELL
  standard tap *
  page24_i140
#ISCELL
  standard tap *
  page24_i141
#ISCELL
  standard tap *
  page24_i142
#ISCELL
  standard tap *
  page24_i143
#ISCELL
  standard tap *
  page24_i144
#ISCELL
  standard tap *
  page24_i145
#ISCELL
  standard tap *
  page24_i146
#ISCELL
  standard tap *
  page24_i147
#ISCELL
  standard tap *
  page24_i148
#ISCELL
  standard tap *
  page24_i149
#ISCELL
  standard tap *
  page24_i15
#ISCELL
  standard tap *
  page24_i150
#ISCELL
  standard tap *
  page24_i151
#ISCELL
  standard tap *
  page24_i152
#ISCELL
  standard tap *
  page24_i153
#ISCELL
  standard tap *
  page24_i154
#ISCELL
  standard tap *
  page24_i155
#ISCELL
  standard tap *
  page24_i156
#ISCELL
  standard tap *
  page24_i157
#ISCELL
  standard tap *
  page24_i158
#ISCELL
  standard offpage *
  page24_i159
#ISCELL
  standard tap *
  page24_i16
#ISCELL
  standard offpage *
  page24_i160
#ISCELL
  standard offpage *
  page24_i161
#ISCELL
  standard offpage *
  page24_i162
#ISCELL
  standard offpage *
  page24_i163
#ISCELL
  standard offpage *
  page24_i164
#ISCELL
  standard offpage *
  page24_i165
#ISCELL
  standard offpage *
  page24_i166
#ISCELL
  standard offpage *
  page24_i167
#ISCELL
  standard offpage *
  page24_i168
#CELL
  pure_quanta socket4677_azif0045p001c01cs *
  page24_i169
#ISCELL
  standard tap *
  page24_i17
#ISCELL
  standard tap *
  page24_i18
#ISCELL
  standard tap *
  page24_i19
#ISCELL
  standard offpage *
  page24_i2
#ISCELL
  standard tap *
  page24_i20
#ISCELL
  standard tap *
  page24_i21
#ISCELL
  standard tap *
  page24_i22
#ISCELL
  standard tap *
  page24_i23
#ISCELL
  standard tap *
  page24_i24
#ISCELL
  standard tap *
  page24_i25
#ISCELL
  standard tap *
  page24_i26
#ISCELL
  standard tap *
  page24_i27
#ISCELL
  standard tap *
  page24_i28
#ISCELL
  standard tap *
  page24_i29
#ISCELL
  standard tap *
  page24_i3
#ISCELL
  standard tap *
  page24_i30
#ISCELL
  standard tap *
  page24_i31
#ISCELL
  standard tap *
  page24_i32
#ISCELL
  standard tap *
  page24_i33
#ISCELL
  standard tap *
  page24_i34
#ISCELL
  standard tap *
  page24_i35
#ISCELL
  standard tap *
  page24_i36
#ISCELL
  standard tap *
  page24_i37
#ISCELL
  standard tap *
  page24_i38
#ISCELL
  standard tap *
  page24_i39
#ISCELL
  standard tap *
  page24_i4
#ISCELL
  standard tap *
  page24_i40
#ISCELL
  standard tap *
  page24_i41
#ISCELL
  standard tap *
  page24_i42
#ISCELL
  standard tap *
  page24_i43
#ISCELL
  standard tap *
  page24_i44
#ISCELL
  standard tap *
  page24_i45
#ISCELL
  standard tap *
  page24_i46
#ISCELL
  standard tap *
  page24_i47
#ISCELL
  standard tap *
  page24_i48
#ISCELL
  standard tap *
  page24_i49
#ISCELL
  standard tap *
  page24_i5
#ISCELL
  standard tap *
  page24_i50
#ISCELL
  standard offpage *
  page24_i51
#ISCELL
  standard offpage *
  page24_i52
#ISCELL
  standard tap *
  page24_i53
#ISCELL
  standard tap *
  page24_i54
#ISCELL
  standard tap *
  page24_i55
#ISCELL
  standard tap *
  page24_i56
#ISCELL
  standard tap *
  page24_i57
#ISCELL
  standard tap *
  page24_i58
#ISCELL
  standard tap *
  page24_i59
#ISCELL
  standard tap *
  page24_i6
#ISCELL
  standard tap *
  page24_i60
#ISCELL
  standard tap *
  page24_i61
#ISCELL
  standard tap *
  page24_i62
#ISCELL
  standard tap *
  page24_i63
#ISCELL
  standard tap *
  page24_i64
#ISCELL
  standard tap *
  page24_i65
#ISCELL
  standard tap *
  page24_i66
#ISCELL
  standard tap *
  page24_i67
#ISCELL
  standard tap *
  page24_i68
#ISCELL
  standard tap *
  page24_i69
#ISCELL
  standard tap *
  page24_i7
#ISCELL
  standard tap *
  page24_i70
#ISCELL
  standard tap *
  page24_i71
#ISCELL
  standard tap *
  page24_i72
#ISCELL
  standard tap *
  page24_i73
#ISCELL
  standard tap *
  page24_i74
#ISCELL
  standard tap *
  page24_i75
#ISCELL
  standard tap *
  page24_i76
#ISCELL
  standard tap *
  page24_i77
#ISCELL
  standard tap *
  page24_i78
#ISCELL
  standard tap *
  page24_i79
#ISCELL
  standard tap *
  page24_i8
#ISCELL
  standard tap *
  page24_i80
#ISCELL
  standard tap *
  page24_i81
#ISCELL
  standard tap *
  page24_i82
#ISCELL
  standard tap *
  page24_i83
#ISCELL
  standard tap *
  page24_i84
#ISCELL
  standard tap *
  page24_i85
#ISCELL
  standard tap *
  page24_i86
#ISCELL
  standard tap *
  page24_i87
#ISCELL
  standard tap *
  page24_i88
#ISCELL
  standard tap *
  page24_i89
#ISCELL
  standard offpage *
  page24_i9
#ISCELL
  standard tap *
  page24_i90
#ISCELL
  standard offpage *
  page24_i92
#ISCELL
  standard offpage *
  page24_i93
#ISCELL
  standard offpage *
  page24_i94
#ISCELL
  standard offpage *
  page24_i95
#ISCELL
  standard offpage *
  page24_i96
#ISCELL
  standard tap *
  page24_i97
#ISCELL
  standard tap *
  page24_i98
#ISCELL
  standard tap *
  page24_i99
#ISCELL
  pure_quanta quanta_title_block_c *
  *
#ISCELL
  standard offpage *
  page25_i1
#ISCELL
  standard tap *
  page25_i10
#ISCELL
  standard tap *
  page25_i100
#ISCELL
  standard tap *
  page25_i101
#ISCELL
  standard tap *
  page25_i102
#ISCELL
  standard tap *
  page25_i103
#ISCELL
  standard tap *
  page25_i104
#ISCELL
  standard tap *
  page25_i105
#ISCELL
  standard tap *
  page25_i106
#ISCELL
  standard tap *
  page25_i107
#ISCELL
  standard tap *
  page25_i108
#ISCELL
  standard tap *
  page25_i109
#ISCELL
  standard tap *
  page25_i11
#ISCELL
  standard tap *
  page25_i110
#ISCELL
  standard tap *
  page25_i111
#ISCELL
  standard tap *
  page25_i112
#ISCELL
  standard tap *
  page25_i113
#ISCELL
  standard tap *
  page25_i114
#ISCELL
  standard tap *
  page25_i115
#ISCELL
  standard tap *
  page25_i116
#ISCELL
  standard tap *
  page25_i117
#ISCELL
  standard tap *
  page25_i118
#ISCELL
  standard tap *
  page25_i119
#ISCELL
  standard tap *
  page25_i12
#ISCELL
  standard tap *
  page25_i120
#ISCELL
  standard offpage *
  page25_i121
#ISCELL
  standard offpage *
  page25_i122
#ISCELL
  standard offpage *
  page25_i123
#ISCELL
  standard offpage *
  page25_i124
#ISCELL
  standard offpage *
  page25_i125
#ISCELL
  standard offpage *
  page25_i126
#ISCELL
  standard offpage *
  page25_i127
#ISCELL
  standard offpage *
  page25_i128
#ISCELL
  standard tap *
  page25_i129
#ISCELL
  standard tap *
  page25_i13
#ISCELL
  standard tap *
  page25_i130
#ISCELL
  standard tap *
  page25_i131
#ISCELL
  standard tap *
  page25_i132
#ISCELL
  standard tap *
  page25_i133
#ISCELL
  standard tap *
  page25_i134
#ISCELL
  standard tap *
  page25_i135
#ISCELL
  standard tap *
  page25_i136
#ISCELL
  standard tap *
  page25_i137
#ISCELL
  standard tap *
  page25_i138
#ISCELL
  standard tap *
  page25_i139
#ISCELL
  standard tap *
  page25_i14
#ISCELL
  standard tap *
  page25_i140
#ISCELL
  standard tap *
  page25_i141
#ISCELL
  standard tap *
  page25_i142
#ISCELL
  standard tap *
  page25_i143
#ISCELL
  standard tap *
  page25_i144
#ISCELL
  standard tap *
  page25_i145
#ISCELL
  standard tap *
  page25_i146
#ISCELL
  standard tap *
  page25_i147
#ISCELL
  standard tap *
  page25_i148
#ISCELL
  standard tap *
  page25_i149
#ISCELL
  standard tap *
  page25_i15
#ISCELL
  standard tap *
  page25_i150
#ISCELL
  standard tap *
  page25_i151
#ISCELL
  standard tap *
  page25_i152
#ISCELL
  standard tap *
  page25_i153
#ISCELL
  standard tap *
  page25_i154
#ISCELL
  standard tap *
  page25_i155
#ISCELL
  standard tap *
  page25_i156
#ISCELL
  standard tap *
  page25_i157
#ISCELL
  standard tap *
  page25_i158
#ISCELL
  standard tap *
  page25_i159
#ISCELL
  standard tap *
  page25_i16
#ISCELL
  standard tap *
  page25_i160
#ISCELL
  standard tap *
  page25_i161
#ISCELL
  standard tap *
  page25_i162
#ISCELL
  standard tap *
  page25_i163
#ISCELL
  standard tap *
  page25_i164
#ISCELL
  standard offpage *
  page25_i165
#ISCELL
  standard offpage *
  page25_i166
#ISCELL
  standard offpage *
  page25_i167
#ISCELL
  standard offpage *
  page25_i168
#CELL
  pure_quanta socket4677_azif0045p001c01cs *
  page25_i169
#ISCELL
  standard tap *
  page25_i17
#ISCELL
  standard tap *
  page25_i18
#ISCELL
  standard tap *
  page25_i19
#ISCELL
  standard offpage *
  page25_i2
#ISCELL
  standard tap *
  page25_i20
#ISCELL
  standard tap *
  page25_i21
#ISCELL
  standard tap *
  page25_i22
#ISCELL
  standard tap *
  page25_i23
#ISCELL
  standard tap *
  page25_i24
#ISCELL
  standard tap *
  page25_i25
#ISCELL
  standard tap *
  page25_i26
#ISCELL
  standard tap *
  page25_i27
#ISCELL
  standard tap *
  page25_i28
#ISCELL
  standard tap *
  page25_i29
#ISCELL
  standard tap *
  page25_i3
#ISCELL
  standard tap *
  page25_i30
#ISCELL
  standard tap *
  page25_i31
#ISCELL
  standard tap *
  page25_i32
#ISCELL
  standard tap *
  page25_i33
#ISCELL
  standard tap *
  page25_i34
#ISCELL
  standard tap *
  page25_i35
#ISCELL
  standard tap *
  page25_i36
#ISCELL
  standard tap *
  page25_i37
#ISCELL
  standard tap *
  page25_i38
#ISCELL
  standard tap *
  page25_i39
#ISCELL
  standard tap *
  page25_i4
#ISCELL
  standard tap *
  page25_i40
#ISCELL
  standard tap *
  page25_i41
#ISCELL
  standard tap *
  page25_i42
#ISCELL
  standard tap *
  page25_i43
#ISCELL
  standard tap *
  page25_i44
#ISCELL
  standard tap *
  page25_i45
#ISCELL
  standard tap *
  page25_i46
#ISCELL
  standard tap *
  page25_i47
#ISCELL
  standard tap *
  page25_i48
#ISCELL
  standard tap *
  page25_i49
#ISCELL
  standard tap *
  page25_i5
#ISCELL
  standard offpage *
  page25_i50
#ISCELL
  standard offpage *
  page25_i51
#ISCELL
  standard tap *
  page25_i52
#ISCELL
  standard tap *
  page25_i53
#ISCELL
  standard tap *
  page25_i54
#ISCELL
  standard tap *
  page25_i55
#ISCELL
  standard tap *
  page25_i56
#ISCELL
  standard tap *
  page25_i57
#ISCELL
  standard tap *
  page25_i58
#ISCELL
  standard tap *
  page25_i59
#ISCELL
  standard tap *
  page25_i6
#ISCELL
  standard tap *
  page25_i60
#ISCELL
  standard tap *
  page25_i61
#ISCELL
  standard tap *
  page25_i62
#ISCELL
  standard tap *
  page25_i63
#ISCELL
  standard tap *
  page25_i64
#ISCELL
  standard tap *
  page25_i65
#ISCELL
  standard tap *
  page25_i66
#ISCELL
  standard tap *
  page25_i67
#ISCELL
  standard tap *
  page25_i68
#ISCELL
  standard tap *
  page25_i69
#ISCELL
  standard tap *
  page25_i70
#ISCELL
  standard tap *
  page25_i71
#ISCELL
  standard tap *
  page25_i72
#ISCELL
  standard tap *
  page25_i73
#ISCELL
  standard tap *
  page25_i74
#ISCELL
  standard tap *
  page25_i75
#ISCELL
  standard tap *
  page25_i76
#ISCELL
  standard tap *
  page25_i77
#ISCELL
  standard tap *
  page25_i78
#ISCELL
  standard tap *
  page25_i79
#ISCELL
  standard offpage *
  page25_i8
#ISCELL
  standard tap *
  page25_i80
#ISCELL
  standard tap *
  page25_i81
#ISCELL
  standard tap *
  page25_i82
#ISCELL
  standard tap *
  page25_i83
#ISCELL
  standard tap *
  page25_i84
#ISCELL
  standard tap *
  page25_i85
#ISCELL
  standard tap *
  page25_i86
#ISCELL
  standard tap *
  page25_i87
#ISCELL
  standard tap *
  page25_i88
#ISCELL
  standard tap *
  page25_i89
#ISCELL
  standard offpage *
  page25_i9
#ISCELL
  standard tap *
  page25_i90
#ISCELL
  standard tap *
  page25_i91
#ISCELL
  standard offpage *
  page25_i92
#ISCELL
  standard offpage *
  page25_i93
#ISCELL
  standard offpage *
  page25_i94
#ISCELL
  standard tap *
  page25_i95
#ISCELL
  standard tap *
  page25_i96
#ISCELL
  standard tap *
  page25_i97
#ISCELL
  standard tap *
  page25_i98
#ISCELL
  standard tap *
  page25_i99
#ISCELL
  pure_quanta quanta_title_block_c *
  *
#ISCELL
  standard offpage *
  page26_i1
#ISCELL
  standard offpage *
  page26_i10
#ISCELL
  standard tap *
  page26_i100
#ISCELL
  standard tap *
  page26_i101
#ISCELL
  standard tap *
  page26_i102
#ISCELL
  standard tap *
  page26_i103
#ISCELL
  standard tap *
  page26_i104
#ISCELL
  standard tap *
  page26_i105
#ISCELL
  standard tap *
  page26_i106
#ISCELL
  standard tap *
  page26_i107
#ISCELL
  standard tap *
  page26_i108
#ISCELL
  standard tap *
  page26_i109
#ISCELL
  standard offpage *
  page26_i11
#ISCELL
  standard tap *
  page26_i110
#ISCELL
  standard tap *
  page26_i111
#ISCELL
  standard tap *
  page26_i112
#ISCELL
  standard tap *
  page26_i113
#ISCELL
  standard tap *
  page26_i114
#ISCELL
  standard tap *
  page26_i115
#ISCELL
  standard tap *
  page26_i116
#ISCELL
  standard tap *
  page26_i117
#ISCELL
  standard tap *
  page26_i118
#ISCELL
  standard tap *
  page26_i119
#ISCELL
  standard tap *
  page26_i12
#ISCELL
  standard tap *
  page26_i120
#ISCELL
  standard tap *
  page26_i121
#ISCELL
  standard tap *
  page26_i122
#ISCELL
  standard tap *
  page26_i123
#ISCELL
  standard tap *
  page26_i124
#ISCELL
  standard tap *
  page26_i125
#ISCELL
  standard tap *
  page26_i126
#ISCELL
  standard tap *
  page26_i127
#ISCELL
  standard tap *
  page26_i128
#ISCELL
  standard tap *
  page26_i129
#ISCELL
  standard tap *
  page26_i13
#ISCELL
  standard tap *
  page26_i130
#ISCELL
  standard tap *
  page26_i131
#ISCELL
  standard tap *
  page26_i132
#ISCELL
  standard tap *
  page26_i133
#ISCELL
  standard tap *
  page26_i134
#ISCELL
  standard tap *
  page26_i135
#ISCELL
  standard tap *
  page26_i136
#ISCELL
  standard tap *
  page26_i137
#ISCELL
  standard tap *
  page26_i138
#ISCELL
  standard tap *
  page26_i139
#ISCELL
  standard tap *
  page26_i14
#ISCELL
  standard tap *
  page26_i140
#ISCELL
  standard tap *
  page26_i141
#ISCELL
  standard tap *
  page26_i142
#ISCELL
  standard tap *
  page26_i143
#ISCELL
  standard tap *
  page26_i144
#ISCELL
  standard tap *
  page26_i145
#ISCELL
  standard tap *
  page26_i146
#ISCELL
  standard tap *
  page26_i147
#ISCELL
  standard tap *
  page26_i148
#ISCELL
  standard tap *
  page26_i149
#ISCELL
  standard tap *
  page26_i15
#ISCELL
  standard tap *
  page26_i150
#ISCELL
  standard tap *
  page26_i151
#ISCELL
  standard tap *
  page26_i152
#ISCELL
  standard tap *
  page26_i153
#ISCELL
  standard tap *
  page26_i154
#ISCELL
  standard tap *
  page26_i155
#ISCELL
  standard tap *
  page26_i156
#ISCELL
  standard tap *
  page26_i157
#ISCELL
  standard tap *
  page26_i158
#ISCELL
  standard offpage *
  page26_i159
#ISCELL
  standard tap *
  page26_i16
#ISCELL
  standard offpage *
  page26_i160
#ISCELL
  standard offpage *
  page26_i161
#ISCELL
  standard offpage *
  page26_i162
#ISCELL
  standard offpage *
  page26_i163
#ISCELL
  standard offpage *
  page26_i164
#ISCELL
  standard offpage *
  page26_i165
#ISCELL
  standard offpage *
  page26_i166
#ISCELL
  standard offpage *
  page26_i167
#ISCELL
  standard offpage *
  page26_i168
#CELL
  pure_quanta socket4677_azif0045p001c01cs *
  page26_i169
#ISCELL
  standard tap *
  page26_i17
#ISCELL
  standard tap *
  page26_i18
#ISCELL
  standard tap *
  page26_i19
#ISCELL
  standard offpage *
  page26_i2
#ISCELL
  standard tap *
  page26_i20
#ISCELL
  standard tap *
  page26_i21
#ISCELL
  standard tap *
  page26_i22
#ISCELL
  standard tap *
  page26_i23
#ISCELL
  standard tap *
  page26_i24
#ISCELL
  standard tap *
  page26_i25
#ISCELL
  standard tap *
  page26_i26
#ISCELL
  standard tap *
  page26_i27
#ISCELL
  standard tap *
  page26_i28
#ISCELL
  standard tap *
  page26_i29
#ISCELL
  standard tap *
  page26_i3
#ISCELL
  standard tap *
  page26_i30
#ISCELL
  standard tap *
  page26_i31
#ISCELL
  standard tap *
  page26_i32
#ISCELL
  standard tap *
  page26_i33
#ISCELL
  standard tap *
  page26_i34
#ISCELL
  standard tap *
  page26_i35
#ISCELL
  standard tap *
  page26_i36
#ISCELL
  standard tap *
  page26_i37
#ISCELL
  standard tap *
  page26_i38
#ISCELL
  standard tap *
  page26_i39
#ISCELL
  standard tap *
  page26_i4
#ISCELL
  standard tap *
  page26_i40
#ISCELL
  standard tap *
  page26_i41
#ISCELL
  standard tap *
  page26_i42
#ISCELL
  standard tap *
  page26_i43
#ISCELL
  standard tap *
  page26_i44
#ISCELL
  standard tap *
  page26_i45
#ISCELL
  standard tap *
  page26_i46
#ISCELL
  standard tap *
  page26_i47
#ISCELL
  standard tap *
  page26_i48
#ISCELL
  standard tap *
  page26_i49
#ISCELL
  standard tap *
  page26_i5
#ISCELL
  standard tap *
  page26_i50
#ISCELL
  standard tap *
  page26_i51
#ISCELL
  standard offpage *
  page26_i52
#ISCELL
  standard offpage *
  page26_i53
#ISCELL
  standard tap *
  page26_i54
#ISCELL
  standard tap *
  page26_i55
#ISCELL
  standard tap *
  page26_i56
#ISCELL
  standard tap *
  page26_i57
#ISCELL
  standard tap *
  page26_i58
#ISCELL
  standard tap *
  page26_i59
#ISCELL
  standard tap *
  page26_i6
#ISCELL
  standard tap *
  page26_i60
#ISCELL
  standard tap *
  page26_i61
#ISCELL
  standard tap *
  page26_i62
#ISCELL
  standard tap *
  page26_i63
#ISCELL
  standard tap *
  page26_i64
#ISCELL
  standard tap *
  page26_i65
#ISCELL
  standard tap *
  page26_i66
#ISCELL
  standard tap *
  page26_i67
#ISCELL
  standard tap *
  page26_i68
#ISCELL
  standard tap *
  page26_i69
#ISCELL
  standard tap *
  page26_i7
#ISCELL
  standard tap *
  page26_i70
#ISCELL
  standard tap *
  page26_i71
#ISCELL
  standard tap *
  page26_i72
#ISCELL
  standard tap *
  page26_i73
#ISCELL
  standard tap *
  page26_i74
#ISCELL
  standard tap *
  page26_i75
#ISCELL
  standard tap *
  page26_i76
#ISCELL
  standard tap *
  page26_i77
#ISCELL
  standard tap *
  page26_i78
#ISCELL
  standard tap *
  page26_i79
#ISCELL
  standard tap *
  page26_i8
#ISCELL
  standard tap *
  page26_i80
#ISCELL
  standard tap *
  page26_i81
#ISCELL
  standard tap *
  page26_i82
#ISCELL
  standard tap *
  page26_i83
#ISCELL
  standard tap *
  page26_i84
#ISCELL
  standard tap *
  page26_i85
#ISCELL
  standard tap *
  page26_i86
#ISCELL
  standard tap *
  page26_i87
#ISCELL
  standard tap *
  page26_i88
#ISCELL
  standard tap *
  page26_i89
#ISCELL
  standard tap *
  page26_i9
#ISCELL
  standard tap *
  page26_i90
#ISCELL
  standard offpage *
  page26_i92
#ISCELL
  standard offpage *
  page26_i93
#ISCELL
  standard offpage *
  page26_i94
#ISCELL
  standard offpage *
  page26_i95
#ISCELL
  standard offpage *
  page26_i96
#ISCELL
  standard tap *
  page26_i97
#ISCELL
  standard tap *
  page26_i98
#ISCELL
  standard tap *
  page26_i99
#ISCELL
  pure_quanta quanta_title_block_c *
  *
#ISCELL
  standard offpage *
  page27_i1
#ISCELL
  standard offpage *
  page27_i10
#ISCELL
  standard tap *
  page27_i100
#ISCELL
  standard tap *
  page27_i101
#ISCELL
  standard tap *
  page27_i102
#ISCELL
  standard tap *
  page27_i103
#ISCELL
  standard tap *
  page27_i104
#ISCELL
  standard tap *
  page27_i105
#ISCELL
  standard tap *
  page27_i106
#ISCELL
  standard tap *
  page27_i107
#ISCELL
  standard tap *
  page27_i108
#ISCELL
  standard tap *
  page27_i109
#ISCELL
  standard offpage *
  page27_i11
#ISCELL
  standard tap *
  page27_i110
#ISCELL
  standard tap *
  page27_i111
#ISCELL
  standard tap *
  page27_i112
#ISCELL
  standard tap *
  page27_i113
#ISCELL
  standard tap *
  page27_i114
#ISCELL
  standard tap *
  page27_i115
#ISCELL
  standard tap *
  page27_i116
#ISCELL
  standard tap *
  page27_i117
#ISCELL
  standard tap *
  page27_i118
#ISCELL
  standard tap *
  page27_i119
#ISCELL
  standard tap *
  page27_i12
#ISCELL
  standard tap *
  page27_i120
#ISCELL
  standard tap *
  page27_i121
#ISCELL
  standard tap *
  page27_i122
#ISCELL
  standard tap *
  page27_i123
#ISCELL
  standard tap *
  page27_i124
#ISCELL
  standard tap *
  page27_i125
#ISCELL
  standard tap *
  page27_i126
#ISCELL
  standard tap *
  page27_i127
#ISCELL
  standard tap *
  page27_i128
#ISCELL
  standard tap *
  page27_i129
#ISCELL
  standard tap *
  page27_i13
#ISCELL
  standard tap *
  page27_i130
#ISCELL
  standard tap *
  page27_i131
#ISCELL
  standard tap *
  page27_i132
#ISCELL
  standard tap *
  page27_i133
#ISCELL
  standard tap *
  page27_i134
#ISCELL
  standard tap *
  page27_i135
#ISCELL
  standard tap *
  page27_i136
#ISCELL
  standard tap *
  page27_i137
#ISCELL
  standard tap *
  page27_i138
#ISCELL
  standard tap *
  page27_i139
#ISCELL
  standard tap *
  page27_i14
#ISCELL
  standard tap *
  page27_i140
#ISCELL
  standard tap *
  page27_i141
#ISCELL
  standard tap *
  page27_i142
#ISCELL
  standard tap *
  page27_i143
#ISCELL
  standard tap *
  page27_i144
#ISCELL
  standard tap *
  page27_i145
#ISCELL
  standard tap *
  page27_i146
#ISCELL
  standard tap *
  page27_i147
#ISCELL
  standard tap *
  page27_i148
#ISCELL
  standard tap *
  page27_i149
#ISCELL
  standard tap *
  page27_i15
#ISCELL
  standard tap *
  page27_i150
#ISCELL
  standard tap *
  page27_i151
#ISCELL
  standard tap *
  page27_i152
#ISCELL
  standard tap *
  page27_i153
#ISCELL
  standard tap *
  page27_i154
#ISCELL
  standard tap *
  page27_i155
#ISCELL
  standard tap *
  page27_i156
#ISCELL
  standard tap *
  page27_i157
#ISCELL
  standard tap *
  page27_i158
#ISCELL
  standard offpage *
  page27_i159
#ISCELL
  standard tap *
  page27_i16
#ISCELL
  standard offpage *
  page27_i160
#ISCELL
  standard offpage *
  page27_i161
#ISCELL
  standard offpage *
  page27_i162
#ISCELL
  standard offpage *
  page27_i163
#ISCELL
  standard offpage *
  page27_i164
#ISCELL
  standard offpage *
  page27_i165
#ISCELL
  standard offpage *
  page27_i166
#ISCELL
  standard offpage *
  page27_i167
#ISCELL
  standard offpage *
  page27_i168
#CELL
  pure_quanta socket4677_azif0045p001c01cs *
  page27_i169
#ISCELL
  standard tap *
  page27_i17
#ISCELL
  standard tap *
  page27_i18
#ISCELL
  standard tap *
  page27_i19
#ISCELL
  standard offpage *
  page27_i2
#ISCELL
  standard tap *
  page27_i20
#ISCELL
  standard tap *
  page27_i21
#ISCELL
  standard tap *
  page27_i22
#ISCELL
  standard tap *
  page27_i23
#ISCELL
  standard tap *
  page27_i24
#ISCELL
  standard tap *
  page27_i25
#ISCELL
  standard tap *
  page27_i26
#ISCELL
  standard tap *
  page27_i27
#ISCELL
  standard tap *
  page27_i28
#ISCELL
  standard tap *
  page27_i29
#ISCELL
  standard tap *
  page27_i3
#ISCELL
  standard tap *
  page27_i30
#ISCELL
  standard tap *
  page27_i31
#ISCELL
  standard tap *
  page27_i32
#ISCELL
  standard tap *
  page27_i33
#ISCELL
  standard tap *
  page27_i34
#ISCELL
  standard tap *
  page27_i35
#ISCELL
  standard tap *
  page27_i36
#ISCELL
  standard tap *
  page27_i37
#ISCELL
  standard tap *
  page27_i38
#ISCELL
  standard tap *
  page27_i39
#ISCELL
  standard tap *
  page27_i4
#ISCELL
  standard tap *
  page27_i40
#ISCELL
  standard tap *
  page27_i41
#ISCELL
  standard tap *
  page27_i42
#ISCELL
  standard tap *
  page27_i43
#ISCELL
  standard tap *
  page27_i44
#ISCELL
  standard tap *
  page27_i45
#ISCELL
  standard tap *
  page27_i46
#ISCELL
  standard tap *
  page27_i47
#ISCELL
  standard tap *
  page27_i48
#ISCELL
  standard tap *
  page27_i49
#ISCELL
  standard tap *
  page27_i5
#ISCELL
  standard tap *
  page27_i50
#ISCELL
  standard tap *
  page27_i51
#ISCELL
  standard offpage *
  page27_i52
#ISCELL
  standard offpage *
  page27_i53
#ISCELL
  standard tap *
  page27_i54
#ISCELL
  standard tap *
  page27_i55
#ISCELL
  standard tap *
  page27_i56
#ISCELL
  standard tap *
  page27_i57
#ISCELL
  standard tap *
  page27_i58
#ISCELL
  standard tap *
  page27_i59
#ISCELL
  standard tap *
  page27_i6
#ISCELL
  standard tap *
  page27_i60
#ISCELL
  standard tap *
  page27_i61
#ISCELL
  standard tap *
  page27_i62
#ISCELL
  standard tap *
  page27_i63
#ISCELL
  standard tap *
  page27_i64
#ISCELL
  standard tap *
  page27_i65
#ISCELL
  standard tap *
  page27_i66
#ISCELL
  standard tap *
  page27_i67
#ISCELL
  standard tap *
  page27_i68
#ISCELL
  standard tap *
  page27_i69
#ISCELL
  standard tap *
  page27_i7
#ISCELL
  standard tap *
  page27_i70
#ISCELL
  standard tap *
  page27_i71
#ISCELL
  standard tap *
  page27_i72
#ISCELL
  standard tap *
  page27_i73
#ISCELL
  standard tap *
  page27_i74
#ISCELL
  standard tap *
  page27_i75
#ISCELL
  standard tap *
  page27_i76
#ISCELL
  standard tap *
  page27_i77
#ISCELL
  standard tap *
  page27_i78
#ISCELL
  standard tap *
  page27_i79
#ISCELL
  standard tap *
  page27_i8
#ISCELL
  standard tap *
  page27_i80
#ISCELL
  standard tap *
  page27_i81
#ISCELL
  standard tap *
  page27_i82
#ISCELL
  standard tap *
  page27_i83
#ISCELL
  standard tap *
  page27_i84
#ISCELL
  standard tap *
  page27_i85
#ISCELL
  standard tap *
  page27_i86
#ISCELL
  standard tap *
  page27_i87
#ISCELL
  standard tap *
  page27_i88
#ISCELL
  standard tap *
  page27_i89
#ISCELL
  standard tap *
  page27_i9
#ISCELL
  standard tap *
  page27_i90
#ISCELL
  standard offpage *
  page27_i92
#ISCELL
  standard offpage *
  page27_i93
#ISCELL
  standard offpage *
  page27_i94
#ISCELL
  standard offpage *
  page27_i95
#ISCELL
  standard offpage *
  page27_i96
#ISCELL
  standard tap *
  page27_i97
#ISCELL
  standard tap *
  page27_i98
#ISCELL
  standard tap *
  page27_i99
#ISCELL
  pure_quanta quanta_title_block_c *
  *
#ISCELL
  standard tap *
  page28_i151
#ISCELL
  standard tap *
  page28_i152
#ISCELL
  standard tap *
  page28_i161
#ISCELL
  standard tap *
  page28_i165
#CELL
  pure_quanta socket4677_azif0045p001c01cs *
  page28_i169
#ISCELL
  standard tap *
  page28_i171
#ISCELL
  standard tap *
  page28_i173
#ISCELL
  standard tap *
  page28_i179
#ISCELL
  standard tap *
  page28_i184
#ISCELL
  standard tap *
  page28_i186
#ISCELL
  standard tap *
  page28_i188
#ISCELL
  standard offpage *
  page28_i281
#ISCELL
  standard offpage *
  page28_i282
#ISCELL
  standard offpage *
  page28_i286
#ISCELL
  standard offpage *
  page28_i287
#ISCELL
  standard tap *
  page28_i288
#ISCELL
  standard tap *
  page28_i289
#ISCELL
  standard tap *
  page28_i290
#ISCELL
  standard tap *
  page28_i292
#ISCELL
  standard tap *
  page28_i293
#ISCELL
  standard tap *
  page28_i294
#ISCELL
  standard tap *
  page28_i296
#ISCELL
  standard tap *
  page28_i297
#ISCELL
  standard tap *
  page28_i298
#ISCELL
  standard tap *
  page28_i299
#ISCELL
  standard tap *
  page28_i300
#ISCELL
  standard tap *
  page28_i301
#ISCELL
  standard tap *
  page28_i302
#ISCELL
  standard tap *
  page28_i303
#ISCELL
  standard tap *
  page28_i304
#ISCELL
  standard tap *
  page28_i305
#ISCELL
  standard tap *
  page28_i306
#ISCELL
  standard tap *
  page28_i307
#ISCELL
  standard tap *
  page28_i308
#ISCELL
  standard tap *
  page28_i309
#ISCELL
  standard tap *
  page28_i310
#ISCELL
  standard tap *
  page28_i311
#ISCELL
  pure_quanta quanta_title_block_c *
  *
#CELL
  pure_quanta socket4677_azif0045p001c01cs *
  page29_i176
#CELL
  pure_quanta socket4677_azif0045p001c01cs *
  page29_i37
#ISCELL
  standard offpage *
  page29_i402
#ISCELL
  standard offpage *
  page29_i403
#ISCELL
  standard tap *
  page29_i404
#ISCELL
  standard tap *
  page29_i405
#ISCELL
  standard tap *
  page29_i406
#ISCELL
  standard tap *
  page29_i407
#ISCELL
  standard tap *
  page29_i408
#ISCELL
  standard tap *
  page29_i409
#ISCELL
  standard tap *
  page29_i410
#ISCELL
  standard tap *
  page29_i411
#ISCELL
  standard tap *
  page29_i412
#ISCELL
  standard tap *
  page29_i413
#ISCELL
  standard tap *
  page29_i414
#ISCELL
  standard tap *
  page29_i415
#ISCELL
  standard tap *
  page29_i416
#ISCELL
  standard tap *
  page29_i417
#ISCELL
  standard tap *
  page29_i418
#ISCELL
  standard tap *
  page29_i419
#ISCELL
  standard tap *
  page29_i420
#ISCELL
  standard tap *
  page29_i421
#ISCELL
  standard tap *
  page29_i422
#ISCELL
  standard tap *
  page29_i423
#ISCELL
  standard tap *
  page29_i424
#ISCELL
  standard tap *
  page29_i425
#ISCELL
  standard tap *
  page29_i426
#ISCELL
  standard tap *
  page29_i427
#ISCELL
  standard tap *
  page29_i428
#ISCELL
  standard tap *
  page29_i429
#ISCELL
  standard tap *
  page29_i430
#ISCELL
  standard tap *
  page29_i431
#ISCELL
  standard tap *
  page29_i432
#ISCELL
  standard tap *
  page29_i433
#ISCELL
  standard tap *
  page29_i434
#ISCELL
  standard tap *
  page29_i435
#ISCELL
  standard tap *
  page29_i436
#ISCELL
  standard tap *
  page29_i437
#ISCELL
  standard tap *
  page29_i438
#ISCELL
  standard tap *
  page29_i439
#ISCELL
  standard tap *
  page29_i440
#ISCELL
  standard tap *
  page29_i441
#ISCELL
  standard tap *
  page29_i442
#ISCELL
  standard tap *
  page29_i443
#ISCELL
  standard tap *
  page29_i444
#ISCELL
  standard tap *
  page29_i445
#ISCELL
  standard tap *
  page29_i446
#ISCELL
  standard tap *
  page29_i447
#ISCELL
  standard tap *
  page29_i448
#ISCELL
  standard tap *
  page29_i449
#ISCELL
  standard tap *
  page29_i450
#ISCELL
  standard tap *
  page29_i451
#ISCELL
  standard tap *
  page29_i452
#ISCELL
  standard tap *
  page29_i453
#ISCELL
  standard tap *
  page29_i454
#ISCELL
  standard tap *
  page29_i455
#ISCELL
  standard tap *
  page29_i456
#ISCELL
  standard tap *
  page29_i457
#ISCELL
  standard tap *
  page29_i458
#ISCELL
  standard tap *
  page29_i459
#ISCELL
  standard tap *
  page29_i460
#ISCELL
  standard tap *
  page29_i461
#ISCELL
  standard tap *
  page29_i462
#ISCELL
  standard tap *
  page29_i463
#ISCELL
  standard tap *
  page29_i464
#ISCELL
  standard tap *
  page29_i465
#ISCELL
  standard tap *
  page29_i466
#ISCELL
  standard tap *
  page29_i467
#ISCELL
  standard offpage *
  page29_i468
#ISCELL
  standard offpage *
  page29_i469
#ISCELL
  standard tap *
  page29_i470
#ISCELL
  standard tap *
  page29_i471
#ISCELL
  standard tap *
  page29_i472
#ISCELL
  standard tap *
  page29_i473
#ISCELL
  standard tap *
  page29_i474
#ISCELL
  standard tap *
  page29_i475
#ISCELL
  standard tap *
  page29_i476
#ISCELL
  standard tap *
  page29_i477
#ISCELL
  standard tap *
  page29_i478
#ISCELL
  standard tap *
  page29_i479
#ISCELL
  standard tap *
  page29_i480
#ISCELL
  standard tap *
  page29_i481
#ISCELL
  standard tap *
  page29_i482
#ISCELL
  standard tap *
  page29_i483
#ISCELL
  standard tap *
  page29_i484
#ISCELL
  standard tap *
  page29_i485
#ISCELL
  standard tap *
  page29_i486
#ISCELL
  standard tap *
  page29_i487
#ISCELL
  standard tap *
  page29_i488
#ISCELL
  standard tap *
  page29_i489
#ISCELL
  standard tap *
  page29_i490
#ISCELL
  standard tap *
  page29_i491
#ISCELL
  standard tap *
  page29_i492
#ISCELL
  standard tap *
  page29_i493
#ISCELL
  standard tap *
  page29_i494
#ISCELL
  standard tap *
  page29_i495
#ISCELL
  standard tap *
  page29_i496
#ISCELL
  standard tap *
  page29_i497
#ISCELL
  standard tap *
  page29_i498
#ISCELL
  standard tap *
  page29_i499
#ISCELL
  standard tap *
  page29_i500
#ISCELL
  standard tap *
  page29_i501
#ISCELL
  standard offpage *
  page29_i502
#ISCELL
  standard offpage *
  page29_i503
#ISCELL
  standard tap *
  page29_i504
#ISCELL
  standard tap *
  page29_i505
#ISCELL
  standard tap *
  page29_i506
#ISCELL
  standard tap *
  page29_i507
#ISCELL
  standard tap *
  page29_i508
#ISCELL
  standard tap *
  page29_i509
#ISCELL
  standard tap *
  page29_i510
#ISCELL
  standard tap *
  page29_i511
#ISCELL
  standard tap *
  page29_i512
#ISCELL
  standard tap *
  page29_i513
#ISCELL
  standard tap *
  page29_i514
#ISCELL
  standard tap *
  page29_i515
#ISCELL
  standard tap *
  page29_i516
#ISCELL
  standard tap *
  page29_i517
#ISCELL
  standard tap *
  page29_i518
#ISCELL
  standard tap *
  page29_i519
#ISCELL
  standard tap *
  page29_i520
#ISCELL
  standard tap *
  page29_i521
#ISCELL
  standard tap *
  page29_i522
#ISCELL
  standard tap *
  page29_i523
#ISCELL
  standard tap *
  page29_i524
#ISCELL
  standard tap *
  page29_i525
#ISCELL
  standard tap *
  page29_i526
#ISCELL
  standard tap *
  page29_i527
#ISCELL
  standard tap *
  page29_i528
#ISCELL
  standard tap *
  page29_i529
#ISCELL
  standard tap *
  page29_i530
#ISCELL
  standard tap *
  page29_i531
#ISCELL
  standard tap *
  page29_i532
#ISCELL
  standard tap *
  page29_i533
#ISCELL
  standard tap *
  page29_i534
#ISCELL
  standard tap *
  page29_i535
#ISCELL
  standard offpage *
  page29_i536
#ISCELL
  standard offpage *
  page29_i537
#ISCELL
  pure_quanta quanta_title_block_c *
  *
#CELL
  pure_quanta socket4677_azif0045p001c01cs *
  page30_i139
#CELL
  pure_quanta socket4677_azif0045p001c01cs *
  page30_i140
#ISCELL
  standard offpage *
  page30_i181
#ISCELL
  standard offpage *
  page30_i182
#ISCELL
  standard offpage *
  page30_i251
#ISCELL
  standard offpage *
  page30_i252
#ISCELL
  standard tap *
  page30_i253
#ISCELL
  standard tap *
  page30_i254
#ISCELL
  standard tap *
  page30_i255
#ISCELL
  standard tap *
  page30_i256
#ISCELL
  standard tap *
  page30_i257
#ISCELL
  standard tap *
  page30_i258
#ISCELL
  standard tap *
  page30_i259
#ISCELL
  standard tap *
  page30_i260
#ISCELL
  standard tap *
  page30_i261
#ISCELL
  standard tap *
  page30_i262
#ISCELL
  standard tap *
  page30_i263
#ISCELL
  standard tap *
  page30_i264
#ISCELL
  standard tap *
  page30_i265
#ISCELL
  standard tap *
  page30_i266
#ISCELL
  standard tap *
  page30_i267
#ISCELL
  standard tap *
  page30_i268
#ISCELL
  standard tap *
  page30_i269
#ISCELL
  standard tap *
  page30_i270
#ISCELL
  standard tap *
  page30_i271
#ISCELL
  standard tap *
  page30_i272
#ISCELL
  standard tap *
  page30_i273
#ISCELL
  standard tap *
  page30_i274
#ISCELL
  standard tap *
  page30_i275
#ISCELL
  standard tap *
  page30_i276
#ISCELL
  standard tap *
  page30_i277
#ISCELL
  standard tap *
  page30_i278
#ISCELL
  standard tap *
  page30_i279
#ISCELL
  standard tap *
  page30_i280
#ISCELL
  standard tap *
  page30_i281
#ISCELL
  standard tap *
  page30_i282
#ISCELL
  standard tap *
  page30_i283
#ISCELL
  standard tap *
  page30_i284
#ISCELL
  standard tap *
  page30_i285
#ISCELL
  standard tap *
  page30_i286
#ISCELL
  standard tap *
  page30_i287
#ISCELL
  standard tap *
  page30_i288
#ISCELL
  standard tap *
  page30_i289
#ISCELL
  standard tap *
  page30_i290
#ISCELL
  standard tap *
  page30_i291
#ISCELL
  standard tap *
  page30_i292
#ISCELL
  standard tap *
  page30_i293
#ISCELL
  standard tap *
  page30_i294
#ISCELL
  standard tap *
  page30_i295
#ISCELL
  standard tap *
  page30_i296
#ISCELL
  standard tap *
  page30_i297
#ISCELL
  standard tap *
  page30_i298
#ISCELL
  standard tap *
  page30_i299
#ISCELL
  standard tap *
  page30_i300
#ISCELL
  standard tap *
  page30_i301
#ISCELL
  standard tap *
  page30_i302
#ISCELL
  standard tap *
  page30_i303
#ISCELL
  standard tap *
  page30_i304
#ISCELL
  standard tap *
  page30_i305
#ISCELL
  standard tap *
  page30_i306
#ISCELL
  standard tap *
  page30_i307
#ISCELL
  standard tap *
  page30_i308
#ISCELL
  standard tap *
  page30_i309
#ISCELL
  standard tap *
  page30_i310
#ISCELL
  standard tap *
  page30_i311
#ISCELL
  standard tap *
  page30_i312
#ISCELL
  standard tap *
  page30_i313
#ISCELL
  standard tap *
  page30_i314
#ISCELL
  standard tap *
  page30_i315
#ISCELL
  standard tap *
  page30_i316
#ISCELL
  standard offpage *
  page30_i317
#ISCELL
  standard offpage *
  page30_i318
#ISCELL
  standard tap *
  page30_i319
#ISCELL
  standard tap *
  page30_i320
#ISCELL
  standard tap *
  page30_i321
#ISCELL
  standard tap *
  page30_i322
#ISCELL
  standard tap *
  page30_i323
#ISCELL
  standard tap *
  page30_i324
#ISCELL
  standard tap *
  page30_i325
#ISCELL
  standard tap *
  page30_i326
#ISCELL
  standard tap *
  page30_i327
#ISCELL
  standard tap *
  page30_i328
#ISCELL
  standard tap *
  page30_i329
#ISCELL
  standard tap *
  page30_i330
#ISCELL
  standard tap *
  page30_i331
#ISCELL
  standard tap *
  page30_i332
#ISCELL
  standard tap *
  page30_i333
#ISCELL
  standard tap *
  page30_i334
#ISCELL
  standard tap *
  page30_i335
#ISCELL
  standard tap *
  page30_i336
#ISCELL
  standard tap *
  page30_i337
#ISCELL
  standard tap *
  page30_i338
#ISCELL
  standard tap *
  page30_i339
#ISCELL
  standard tap *
  page30_i340
#ISCELL
  standard tap *
  page30_i341
#ISCELL
  standard tap *
  page30_i342
#ISCELL
  standard tap *
  page30_i343
#ISCELL
  standard tap *
  page30_i344
#ISCELL
  standard tap *
  page30_i345
#ISCELL
  standard tap *
  page30_i346
#ISCELL
  standard tap *
  page30_i347
#ISCELL
  standard tap *
  page30_i348
#ISCELL
  standard tap *
  page30_i349
#ISCELL
  standard tap *
  page30_i350
#ISCELL
  standard offpage *
  page30_i351
#ISCELL
  standard offpage *
  page30_i352
#ISCELL
  standard tap *
  page30_i37
#ISCELL
  standard tap *
  page30_i38
#ISCELL
  standard tap *
  page30_i39
#ISCELL
  standard tap *
  page30_i40
#ISCELL
  standard tap *
  page30_i41
#ISCELL
  standard tap *
  page30_i42
#ISCELL
  standard tap *
  page30_i43
#ISCELL
  standard tap *
  page30_i44
#ISCELL
  standard tap *
  page30_i45
#ISCELL
  standard tap *
  page30_i46
#ISCELL
  standard tap *
  page30_i47
#ISCELL
  standard tap *
  page30_i48
#ISCELL
  standard tap *
  page30_i49
#ISCELL
  standard tap *
  page30_i50
#ISCELL
  standard tap *
  page30_i51
#ISCELL
  standard tap *
  page30_i52
#ISCELL
  standard tap *
  page30_i53
#ISCELL
  standard tap *
  page30_i54
#ISCELL
  standard tap *
  page30_i55
#ISCELL
  standard tap *
  page30_i56
#ISCELL
  standard tap *
  page30_i57
#ISCELL
  standard tap *
  page30_i58
#ISCELL
  standard tap *
  page30_i59
#ISCELL
  standard tap *
  page30_i60
#ISCELL
  standard tap *
  page30_i61
#ISCELL
  standard tap *
  page30_i62
#ISCELL
  standard tap *
  page30_i63
#ISCELL
  standard tap *
  page30_i64
#ISCELL
  standard tap *
  page30_i65
#ISCELL
  standard tap *
  page30_i66
#ISCELL
  standard tap *
  page30_i67
#ISCELL
  standard tap *
  page30_i68
#ISCELL
  pure_quanta quanta_title_block_c *
  *
#CELL
  pure_quanta socket4677_azif0045p001c01cs *
  page31_i139
#ISCELL
  standard tap *
  page31_i207
#ISCELL
  standard tap *
  page31_i208
#ISCELL
  standard tap *
  page31_i209
#ISCELL
  standard tap *
  page31_i210
#ISCELL
  standard tap *
  page31_i211
#ISCELL
  standard tap *
  page31_i212
#ISCELL
  standard tap *
  page31_i213
#ISCELL
  standard tap *
  page31_i214
#ISCELL
  standard tap *
  page31_i215
#ISCELL
  standard tap *
  page31_i216
#ISCELL
  standard tap *
  page31_i217
#ISCELL
  standard tap *
  page31_i218
#ISCELL
  standard tap *
  page31_i219
#ISCELL
  standard tap *
  page31_i220
#ISCELL
  standard tap *
  page31_i221
#ISCELL
  standard tap *
  page31_i222
#ISCELL
  standard tap *
  page31_i223
#ISCELL
  standard tap *
  page31_i224
#ISCELL
  standard tap *
  page31_i225
#ISCELL
  standard tap *
  page31_i226
#ISCELL
  standard tap *
  page31_i227
#ISCELL
  standard tap *
  page31_i228
#ISCELL
  standard tap *
  page31_i229
#ISCELL
  standard tap *
  page31_i230
#ISCELL
  standard tap *
  page31_i231
#ISCELL
  standard tap *
  page31_i232
#ISCELL
  standard tap *
  page31_i233
#ISCELL
  standard tap *
  page31_i234
#ISCELL
  standard tap *
  page31_i235
#ISCELL
  standard tap *
  page31_i236
#ISCELL
  standard tap *
  page31_i237
#ISCELL
  standard tap *
  page31_i238
#ISCELL
  standard offpage *
  page31_i239
#ISCELL
  standard offpage *
  page31_i240
#ISCELL
  standard offpage *
  page31_i241
#ISCELL
  standard offpage *
  page31_i242
#ISCELL
  standard tap *
  page31_i243
#ISCELL
  standard tap *
  page31_i244
#ISCELL
  standard tap *
  page31_i245
#ISCELL
  standard tap *
  page31_i246
#ISCELL
  standard tap *
  page31_i247
#ISCELL
  standard tap *
  page31_i248
#ISCELL
  standard tap *
  page31_i249
#ISCELL
  standard tap *
  page31_i250
#ISCELL
  standard tap *
  page31_i251
#ISCELL
  standard tap *
  page31_i252
#ISCELL
  standard tap *
  page31_i253
#ISCELL
  standard tap *
  page31_i254
#ISCELL
  standard tap *
  page31_i255
#ISCELL
  standard tap *
  page31_i256
#ISCELL
  standard tap *
  page31_i257
#ISCELL
  standard tap *
  page31_i258
#ISCELL
  standard tap *
  page31_i259
#ISCELL
  standard tap *
  page31_i260
#ISCELL
  standard tap *
  page31_i261
#ISCELL
  standard tap *
  page31_i262
#ISCELL
  standard tap *
  page31_i263
#ISCELL
  standard tap *
  page31_i264
#ISCELL
  standard tap *
  page31_i265
#ISCELL
  standard tap *
  page31_i266
#ISCELL
  standard tap *
  page31_i267
#ISCELL
  standard tap *
  page31_i268
#ISCELL
  standard tap *
  page31_i269
#ISCELL
  standard tap *
  page31_i270
#ISCELL
  standard tap *
  page31_i271
#ISCELL
  standard tap *
  page31_i272
#ISCELL
  standard tap *
  page31_i273
#ISCELL
  standard tap *
  page31_i274
#ISCELL
  logical_power design_note *
  *
#ISCELL
  pure_quanta quanta_title_block_c *
  *
#ISCELL
  standard tap *
  page32_i101
#ISCELL
  standard tap *
  page32_i102
#ISCELL
  standard tap *
  page32_i103
#ISCELL
  standard tap *
  page32_i104
#ISCELL
  standard tap *
  page32_i106
#ISCELL
  standard tap *
  page32_i107
#ISCELL
  standard tap *
  page32_i108
#ISCELL
  standard tap *
  page32_i109
#ISCELL
  standard tap *
  page32_i110
#ISCELL
  standard tap *
  page32_i111
#ISCELL
  standard tap *
  page32_i112
#ISCELL
  standard tap *
  page32_i113
#ISCELL
  standard tap *
  page32_i114
#ISCELL
  standard tap *
  page32_i115
#ISCELL
  standard tap *
  page32_i116
#ISCELL
  standard tap *
  page32_i117
#ISCELL
  standard tap *
  page32_i118
#ISCELL
  standard tap *
  page32_i119
#ISCELL
  standard tap *
  page32_i120
#ISCELL
  standard tap *
  page32_i121
#ISCELL
  standard tap *
  page32_i122
#ISCELL
  standard tap *
  page32_i123
#ISCELL
  standard tap *
  page32_i124
#ISCELL
  standard tap *
  page32_i125
#ISCELL
  standard tap *
  page32_i126
#ISCELL
  standard tap *
  page32_i127
#ISCELL
  standard tap *
  page32_i128
#ISCELL
  standard tap *
  page32_i129
#ISCELL
  standard tap *
  page32_i130
#ISCELL
  standard tap *
  page32_i131
#ISCELL
  standard tap *
  page32_i132
#ISCELL
  standard tap *
  page32_i133
#ISCELL
  standard tap *
  page32_i134
#ISCELL
  standard tap *
  page32_i135
#ISCELL
  standard tap *
  page32_i136
#ISCELL
  standard tap *
  page32_i137
#ISCELL
  standard tap *
  page32_i139
#ISCELL
  standard tap *
  page32_i140
#ISCELL
  standard tap *
  page32_i141
#ISCELL
  standard tap *
  page32_i142
#ISCELL
  standard tap *
  page32_i143
#ISCELL
  standard tap *
  page32_i144
#ISCELL
  standard offpage *
  page32_i145
#ISCELL
  standard tap *
  page32_i146
#ISCELL
  standard tap *
  page32_i147
#ISCELL
  standard tap *
  page32_i148
#ISCELL
  standard tap *
  page32_i149
#ISCELL
  standard tap *
  page32_i150
#ISCELL
  standard tap *
  page32_i151
#ISCELL
  standard tap *
  page32_i152
#ISCELL
  standard tap *
  page32_i153
#ISCELL
  standard tap *
  page32_i154
#ISCELL
  standard tap *
  page32_i155
#ISCELL
  standard tap *
  page32_i156
#ISCELL
  standard tap *
  page32_i157
#ISCELL
  standard tap *
  page32_i158
#ISCELL
  standard tap *
  page32_i159
#ISCELL
  standard tap *
  page32_i160
#ISCELL
  standard tap *
  page32_i161
#ISCELL
  standard tap *
  page32_i162
#ISCELL
  standard tap *
  page32_i163
#ISCELL
  standard offpage *
  page32_i164
#ISCELL
  standard tap *
  page32_i165
#ISCELL
  standard tap *
  page32_i166
#ISCELL
  standard tap *
  page32_i167
#ISCELL
  standard tap *
  page32_i168
#ISCELL
  standard tap *
  page32_i169
#ISCELL
  standard tap *
  page32_i170
#ISCELL
  standard tap *
  page32_i171
#ISCELL
  standard tap *
  page32_i172
#ISCELL
  standard tap *
  page32_i173
#ISCELL
  standard tap *
  page32_i174
#ISCELL
  standard tap *
  page32_i175
#ISCELL
  standard tap *
  page32_i176
#ISCELL
  standard tap *
  page32_i19
#ISCELL
  standard offpage *
  page32_i2
#ISCELL
  standard tap *
  page32_i21
#ISCELL
  standard tap *
  page32_i34
#ISCELL
  standard tap *
  page32_i52
#ISCELL
  standard tap *
  page32_i53
#ISCELL
  standard tap *
  page32_i54
#ISCELL
  standard tap *
  page32_i55
#ISCELL
  standard tap *
  page32_i58
#ISCELL
  standard tap *
  page32_i59
#ISCELL
  standard tap *
  page32_i61
#ISCELL
  standard tap *
  page32_i62
#ISCELL
  standard tap *
  page32_i64
#ISCELL
  standard tap *
  page32_i66
#ISCELL
  standard offpage *
  page32_i69
#CELL
  pure_quanta socket4677_azif0045p001c01cs *
  page32_i70
#ISCELL
  standard tap *
  page32_i77
#ISCELL
  standard tap *
  page32_i78
#ISCELL
  standard tap *
  page32_i79
#ISCELL
  standard tap *
  page32_i80
#ISCELL
  standard tap *
  page32_i82
#ISCELL
  standard tap *
  page32_i84
#ISCELL
  standard tap *
  page32_i85
#ISCELL
  standard tap *
  page32_i86
#ISCELL
  standard tap *
  page32_i95
#ISCELL
  standard tap *
  page32_i97
#ISCELL
  standard tap *
  page32_i98
#ISCELL
  logical_power design_note *
  *
#ISCELL
  pure_quanta quanta_title_block_c *
  *
#ISCELL
  standard tap *
  page33_i1
#ISCELL
  standard tap *
  page33_i10
#ISCELL
  standard offpage *
  page33_i101
#CELL
  pure_quanta socket4677_azif0045p001c01cs *
  page33_i102
#ISCELL
  standard tap *
  page33_i103
#ISCELL
  standard tap *
  page33_i104
#ISCELL
  standard tap *
  page33_i105
#ISCELL
  standard tap *
  page33_i106
#ISCELL
  standard tap *
  page33_i107
#ISCELL
  standard tap *
  page33_i108
#ISCELL
  standard tap *
  page33_i109
#ISCELL
  standard tap *
  page33_i11
#ISCELL
  standard tap *
  page33_i111
#ISCELL
  standard tap *
  page33_i112
#ISCELL
  standard tap *
  page33_i113
#ISCELL
  standard tap *
  page33_i114
#ISCELL
  standard tap *
  page33_i115
#ISCELL
  standard tap *
  page33_i116
#ISCELL
  standard tap *
  page33_i117
#ISCELL
  standard tap *
  page33_i118
#ISCELL
  standard tap *
  page33_i119
#ISCELL
  standard tap *
  page33_i12
#ISCELL
  standard tap *
  page33_i120
#ISCELL
  standard tap *
  page33_i121
#ISCELL
  standard tap *
  page33_i122
#ISCELL
  standard tap *
  page33_i123
#ISCELL
  standard tap *
  page33_i124
#ISCELL
  standard tap *
  page33_i125
#ISCELL
  standard tap *
  page33_i126
#ISCELL
  standard tap *
  page33_i127
#ISCELL
  standard tap *
  page33_i128
#ISCELL
  standard tap *
  page33_i129
#ISCELL
  standard tap *
  page33_i13
#ISCELL
  standard tap *
  page33_i130
#ISCELL
  standard tap *
  page33_i131
#ISCELL
  standard tap *
  page33_i132
#ISCELL
  standard tap *
  page33_i133
#ISCELL
  standard tap *
  page33_i134
#ISCELL
  standard tap *
  page33_i135
#ISCELL
  standard offpage *
  page33_i136
#ISCELL
  standard tap *
  page33_i137
#ISCELL
  standard tap *
  page33_i138
#ISCELL
  standard tap *
  page33_i139
#ISCELL
  standard tap *
  page33_i14
#ISCELL
  standard tap *
  page33_i140
#ISCELL
  standard tap *
  page33_i141
#ISCELL
  standard tap *
  page33_i142
#ISCELL
  standard tap *
  page33_i143
#ISCELL
  standard tap *
  page33_i144
#ISCELL
  standard tap *
  page33_i145
#ISCELL
  standard tap *
  page33_i15
#ISCELL
  standard tap *
  page33_i16
#ISCELL
  standard offpage *
  page33_i17
#ISCELL
  standard offpage *
  page33_i18
#ISCELL
  standard tap *
  page33_i19
#ISCELL
  standard tap *
  page33_i2
#ISCELL
  standard tap *
  page33_i20
#ISCELL
  standard tap *
  page33_i22
#ISCELL
  standard tap *
  page33_i24
#ISCELL
  standard tap *
  page33_i25
#ISCELL
  standard tap *
  page33_i27
#ISCELL
  standard tap *
  page33_i29
#ISCELL
  standard tap *
  page33_i30
#ISCELL
  standard tap *
  page33_i31
#ISCELL
  standard tap *
  page33_i32
#ISCELL
  standard tap *
  page33_i33
#ISCELL
  standard tap *
  page33_i34
#ISCELL
  standard tap *
  page33_i35
#ISCELL
  standard tap *
  page33_i36
#ISCELL
  standard tap *
  page33_i37
#ISCELL
  standard tap *
  page33_i38
#ISCELL
  standard tap *
  page33_i4
#ISCELL
  standard tap *
  page33_i40
#ISCELL
  standard tap *
  page33_i41
#ISCELL
  standard tap *
  page33_i42
#ISCELL
  standard tap *
  page33_i43
#ISCELL
  standard tap *
  page33_i44
#ISCELL
  standard tap *
  page33_i48
#ISCELL
  standard tap *
  page33_i5
#ISCELL
  standard tap *
  page33_i52
#ISCELL
  standard tap *
  page33_i53
#ISCELL
  standard tap *
  page33_i54
#ISCELL
  standard tap *
  page33_i56
#ISCELL
  standard tap *
  page33_i58
#ISCELL
  standard tap *
  page33_i59
#ISCELL
  standard tap *
  page33_i6
#ISCELL
  standard tap *
  page33_i61
#ISCELL
  standard tap *
  page33_i62
#ISCELL
  standard tap *
  page33_i7
#ISCELL
  standard tap *
  page33_i75
#ISCELL
  standard tap *
  page33_i76
#ISCELL
  standard tap *
  page33_i77
#ISCELL
  standard tap *
  page33_i78
#ISCELL
  standard tap *
  page33_i8
#ISCELL
  standard tap *
  page33_i81
#ISCELL
  standard tap *
  page33_i82
#ISCELL
  standard tap *
  page33_i84
#ISCELL
  standard tap *
  page33_i85
#ISCELL
  standard tap *
  page33_i86
#ISCELL
  standard tap *
  page33_i9
#ISCELL
  standard tap *
  page33_i99
#ISCELL
  logical_power design_note *
  *
#ISCELL
  pure_quanta quanta_title_block_c *
  *
#ISCELL
  standard offpage *
  page34_i100
#ISCELL
  standard offpage *
  page34_i101
#CELL
  pure_quanta socket4677_azif0045p001c01cs *
  page34_i102
#ISCELL
  standard tap *
  page34_i103
#ISCELL
  standard tap *
  page34_i105
#ISCELL
  standard tap *
  page34_i106
#ISCELL
  standard tap *
  page34_i107
#ISCELL
  standard tap *
  page34_i108
#ISCELL
  standard tap *
  page34_i109
#ISCELL
  standard tap *
  page34_i110
#ISCELL
  standard tap *
  page34_i111
#ISCELL
  standard tap *
  page34_i112
#ISCELL
  standard tap *
  page34_i113
#ISCELL
  standard tap *
  page34_i114
#ISCELL
  standard tap *
  page34_i115
#ISCELL
  standard tap *
  page34_i116
#ISCELL
  standard tap *
  page34_i118
#ISCELL
  standard tap *
  page34_i119
#ISCELL
  standard tap *
  page34_i120
#ISCELL
  standard tap *
  page34_i121
#ISCELL
  standard tap *
  page34_i122
#ISCELL
  standard tap *
  page34_i123
#ISCELL
  standard tap *
  page34_i124
#ISCELL
  standard tap *
  page34_i125
#ISCELL
  standard tap *
  page34_i126
#ISCELL
  standard tap *
  page34_i127
#ISCELL
  standard tap *
  page34_i128
#ISCELL
  standard offpage *
  page34_i129
#ISCELL
  standard tap *
  page34_i130
#ISCELL
  standard tap *
  page34_i131
#ISCELL
  standard tap *
  page34_i14
#ISCELL
  standard tap *
  page34_i16
#ISCELL
  standard tap *
  page34_i17
#ISCELL
  standard offpage *
  page34_i2
#ISCELL
  standard tap *
  page34_i20
#ISCELL
  standard tap *
  page34_i22
#ISCELL
  standard tap *
  page34_i26
#ISCELL
  standard tap *
  page34_i28
#ISCELL
  standard tap *
  page34_i31
#ISCELL
  standard tap *
  page34_i32
#ISCELL
  standard tap *
  page34_i33
#ISCELL
  standard tap *
  page34_i34
#ISCELL
  standard tap *
  page34_i38
#ISCELL
  standard tap *
  page34_i41
#ISCELL
  standard tap *
  page34_i42
#ISCELL
  standard tap *
  page34_i45
#ISCELL
  standard tap *
  page34_i46
#ISCELL
  standard tap *
  page34_i5
#ISCELL
  standard tap *
  page34_i50
#ISCELL
  standard tap *
  page34_i52
#ISCELL
  standard tap *
  page34_i53
#ISCELL
  standard tap *
  page34_i54
#ISCELL
  standard tap *
  page34_i55
#ISCELL
  standard tap *
  page34_i56
#ISCELL
  standard tap *
  page34_i57
#ISCELL
  standard tap *
  page34_i58
#ISCELL
  standard tap *
  page34_i59
#ISCELL
  standard tap *
  page34_i6
#ISCELL
  standard tap *
  page34_i60
#ISCELL
  standard tap *
  page34_i61
#ISCELL
  standard tap *
  page34_i62
#ISCELL
  standard tap *
  page34_i63
#ISCELL
  standard tap *
  page34_i64
#ISCELL
  standard tap *
  page34_i65
#ISCELL
  standard tap *
  page34_i66
#ISCELL
  standard tap *
  page34_i67
#ISCELL
  standard tap *
  page34_i68
#ISCELL
  standard tap *
  page34_i69
#ISCELL
  standard tap *
  page34_i7
#ISCELL
  standard tap *
  page34_i70
#ISCELL
  standard tap *
  page34_i71
#ISCELL
  standard tap *
  page34_i72
#ISCELL
  standard tap *
  page34_i73
#ISCELL
  standard tap *
  page34_i74
#ISCELL
  standard tap *
  page34_i75
#ISCELL
  standard tap *
  page34_i76
#ISCELL
  standard tap *
  page34_i77
#ISCELL
  standard tap *
  page34_i78
#ISCELL
  standard tap *
  page34_i79
#ISCELL
  standard tap *
  page34_i8
#ISCELL
  standard tap *
  page34_i80
#ISCELL
  standard tap *
  page34_i81
#ISCELL
  standard tap *
  page34_i82
#ISCELL
  standard tap *
  page34_i83
#ISCELL
  standard tap *
  page34_i84
#ISCELL
  standard tap *
  page34_i85
#ISCELL
  standard tap *
  page34_i86
#ISCELL
  standard tap *
  page34_i87
#ISCELL
  standard tap *
  page34_i88
#ISCELL
  standard tap *
  page34_i89
#ISCELL
  standard tap *
  page34_i9
#ISCELL
  standard tap *
  page34_i90
#ISCELL
  standard tap *
  page34_i91
#ISCELL
  standard tap *
  page34_i92
#ISCELL
  standard tap *
  page34_i93
#ISCELL
  standard tap *
  page34_i94
#ISCELL
  standard tap *
  page34_i95
#ISCELL
  standard tap *
  page34_i96
#ISCELL
  standard tap *
  page34_i97
#ISCELL
  standard tap *
  page34_i98
#ISCELL
  standard tap *
  page34_i99
#ISCELL
  pure_quanta quanta_title_block_c *
  *
#CELL
  pure_quanta socket4677_azif0045p001c01cs *
  page35_i102
#ISCELL
  logical_power universal_gnd *
  page35_i104
#ISCELL
  pure_quanta quanta_title_block_c *
  *
#CELL
  pure_quanta socket4677_azif0045p001c01cs *
  page36_i1
#ISCELL
  logical_power vcc_core *
  page36_i2
#ISCELL
  logical_power vcc_core *
  page36_i3
#ISCELL
  logical_power vcc_core *
  page36_i5
#ISCELL
  logical_power vcc_core *
  page36_i6
#CELL
  pure_quanta socket4677_azif0045p001c01cs *
  page36_i7
#ISCELL
  pure_quanta quanta_title_block_c *
  *
#ISCELL
  logical_power vcc_core *
  page37_i10
#ISCELL
  logical_power vcc_core *
  page37_i11
#ISCELL
  logical_power vcc_core *
  page37_i12
#ISCELL
  logical_power vcc_core *
  page37_i13
#ISCELL
  logical_power universal_gnd *
  page37_i14
#CELL
  pure_quanta q_cap *
  page37_i15
#ISCELL
  logical_power vcc_core *
  page37_i2
#ISCELL
  logical_power vcc_core *
  page37_i4
#ISCELL
  logical_power vcc_core *
  page37_i5
#ISCELL
  logical_power vcc_core *
  page37_i6
#CELL
  pure_quanta socket4677_azif0045p001c01cs *
  page37_i7
#CELL
  pure_quanta socket4677_azif0045p001c01cs *
  page37_i8
#ISCELL
  logical_power vcc_core *
  page37_i9
#ISCELL
  pure_quanta quanta_title_block_c *
  *
#ISCELL
  logical_power vcc_core *
  page38_i2
#CELL
  pure_quanta socket4677_azif0045p001c01cs *
  page38_i4
#ISCELL
  logical_power vcc_core *
  page38_i5
#ISCELL
  pure_quanta quanta_title_block_c *
  *
#CELL
  pure_quanta socket4677_azif0045p001c01cs *
  page39_i1
#CELL
  pure_quanta socket4677_azif0045p001c01cs *
  page39_i10
#ISCELL
  logical_power universal_gnd *
  page39_i2
#ISCELL
  logical_power universal_gnd *
  page39_i3
#ISCELL
  logical_power universal_gnd *
  page39_i5
#ISCELL
  logical_power universal_gnd *
  page39_i6
#ISCELL
  logical_power universal_gnd *
  page39_i7
#ISCELL
  logical_power universal_gnd *
  page39_i8
#CELL
  pure_quanta socket4677_azif0045p001c01cs *
  page39_i9
#ISCELL
  pure_quanta quanta_title_block_c *
  *
#ISCELL
  logical_power universal_gnd *
  page40_i1
#CELL
  pure_quanta socket4677_azif0045p001c01cs *
  page40_i10
#CELL
  pure_quanta socket4677_azif0045p001c01cs *
  page40_i11
#CELL
  pure_quanta socket4677_azif0045p001c01cs *
  page40_i12
#ISCELL
  logical_power universal_gnd *
  page40_i3
#ISCELL
  logical_power universal_gnd *
  page40_i4
#ISCELL
  logical_power universal_gnd *
  page40_i6
#ISCELL
  logical_power universal_gnd *
  page40_i7
#ISCELL
  logical_power universal_gnd *
  page40_i9
#ISCELL
  pure_quanta quanta_title_block_c *
  *
#ISCELL
  logical_power universal_gnd *
  page41_i1
#CELL
  pure_quanta socket4677_azif0045p001c01cs *
  page41_i10
#CELL
  pure_quanta socket4677_azif0045p001c01cs *
  page41_i11
#ISCELL
  logical_power universal_gnd *
  page41_i3
#ISCELL
  logical_power universal_gnd *
  page41_i4
#ISCELL
  logical_power universal_gnd *
  page41_i5
#ISCELL
  logical_power universal_gnd *
  page41_i6
#ISCELL
  logical_power universal_gnd *
  page41_i8
#CELL
  pure_quanta socket4677_azif0045p001c01cs *
  page41_i9
#ISCELL
  pure_quanta quanta_title_block_c *
  *
#ISCELL
  logical_power universal_gnd *
  page42_i1
#CELL
  pure_quanta socket4677_azif0045p001c01cs *
  page42_i10
#CELL
  pure_quanta socket4677_azif0045p001c01cs *
  page42_i11
#CELL
  pure_quanta socket4677_azif0045p001c01cs *
  page42_i12
#ISCELL
  logical_power universal_gnd *
  page42_i3
#ISCELL
  logical_power universal_gnd *
  page42_i4
#ISCELL
  logical_power universal_gnd *
  page42_i6
#ISCELL
  logical_power universal_gnd *
  page42_i7
#ISCELL
  pure_quanta quanta_title_block_c *
  *
#ISCELL
  standard offpage *
  page43_i1
#ISCELL
  standard offpage *
  page43_i10
#ISCELL
  standard offpage *
  page43_i11
#CELL
  pure_quanta q_res *
  page43_i12
#CELL
  pure_quanta q_res *
  page43_i13
#ISCELL
  standard offpage *
  page43_i14
#ISCELL
  standard offpage *
  page43_i15
#CELL
  pure_quanta q_res *
  page43_i16
#CELL
  pure_quanta q_res *
  page43_i17
#ISCELL
  standard offpage *
  page43_i2
#ISCELL
  logical_power universal_gnd *
  page43_i20
#ISCELL
  standard offpage *
  page43_i47
#CELL
  pure_quanta q_res *
  page43_i52
#ISCELL
  logical_power universal_gnd *
  page43_i54
#ISCELL
  standard offpage *
  page43_i55
#CELL
  pure_quanta q_res *
  page43_i56
#ISCELL
  mstr_misc dns *
  *
#ISCELL
  pure_quanta quanta_title_block_c *
  *
#ISCELL
  standard offpage *
  page44_i1
#CELL
  pure_quanta q_res *
  page44_i10
#CELL
  pure_quanta q_res *
  page44_i11
#ISCELL
  standard offpage *
  page44_i12
#ISCELL
  standard offpage *
  page44_i13
#ISCELL
  standard offpage *
  page44_i14
#ISCELL
  standard offpage *
  page44_i15
#CELL
  pure_quanta q_res *
  page44_i16
#ISCELL
  standard offpage *
  page44_i17
#ISCELL
  standard offpage *
  page44_i18
#ISCELL
  standard offpage *
  page44_i19
#ISCELL
  standard offpage *
  page44_i2
#ISCELL
  standard offpage *
  page44_i20
#ISCELL
  standard offpage *
  page44_i21
#ISCELL
  standard offpage *
  page44_i22
#ISCELL
  standard offpage *
  page44_i23
#ISCELL
  standard offpage *
  page44_i24
#ISCELL
  standard offpage *
  page44_i25
#ISCELL
  standard offpage *
  page44_i26
#ISCELL
  standard offpage *
  page44_i28
#ISCELL
  standard offpage *
  page44_i3
#ISCELL
  standard offpage *
  page44_i30
#ISCELL
  standard offpage *
  page44_i31
#ISCELL
  standard offpage *
  page44_i32
#ISCELL
  standard offpage *
  page44_i33
#ISCELL
  standard offpage *
  page44_i34
#ISCELL
  standard offpage *
  page44_i35
#ISCELL
  standard offpage *
  page44_i36
#ISCELL
  standard offpage *
  page44_i38
#ISCELL
  standard offpage *
  page44_i39
#ISCELL
  standard offpage *
  page44_i4
#ISCELL
  standard offpage *
  page44_i40
#ISCELL
  standard offpage *
  page44_i41
#ISCELL
  standard offpage *
  page44_i42
#ISCELL
  standard offpage *
  page44_i43
#ISCELL
  standard offpage *
  page44_i44
#ISCELL
  standard offpage *
  page44_i45
#ISCELL
  standard offpage *
  page44_i46
#ISCELL
  standard offpage *
  page44_i47
#ISCELL
  standard offpage *
  page44_i48
#ISCELL
  standard offpage *
  page44_i49
#ISCELL
  standard offpage *
  page44_i5
#ISCELL
  standard offpage *
  page44_i50
#CELL
  pure_quanta socket4677_azif0045p001c01cs *
  page44_i51
#ISCELL
  standard offpage *
  page44_i52
#ISCELL
  standard offpage *
  page44_i53
#ISCELL
  standard offpage *
  page44_i54
#CELL
  pure_quanta q_res *
  page44_i55
#ISCELL
  logical_power universal_gnd *
  page44_i56
#ISCELL
  standard offpage *
  page44_i57
#ISCELL
  standard offpage *
  page44_i58
#ISCELL
  standard offpage *
  page44_i6
#CELL
  pure_quanta q_res *
  page44_i7
#CELL
  pure_quanta q_res *
  page44_i8
#CELL
  pure_quanta q_res *
  page44_i9
#ISCELL
  pure_quanta quanta_title_block_c *
  *
#ISCELL
  standard offpage *
  page45_i1
#ISCELL
  standard offpage *
  page45_i10
#ISCELL
  standard offpage *
  page45_i11
#ISCELL
  standard offpage *
  page45_i13
#ISCELL
  standard offpage *
  page45_i14
#ISCELL
  standard offpage *
  page45_i16
#ISCELL
  standard offpage *
  page45_i17
#ISCELL
  standard offpage *
  page45_i18
#ISCELL
  standard offpage *
  page45_i19
#ISCELL
  standard offpage *
  page45_i20
#ISCELL
  standard offpage *
  page45_i21
#ISCELL
  standard offpage *
  page45_i22
#ISCELL
  standard offpage *
  page45_i23
#CELL
  pure_quanta socket4677_azif0045p001c01cs *
  page45_i29
#ISCELL
  standard offpage *
  page45_i32
#ISCELL
  standard offpage *
  page45_i33
#ISCELL
  standard offpage *
  page45_i38
#ISCELL
  standard offpage *
  page45_i39
#ISCELL
  standard offpage *
  page45_i41
#ISCELL
  standard offpage *
  page45_i42
#ISCELL
  standard offpage *
  page45_i43
#ISCELL
  standard offpage *
  page45_i44
#ISCELL
  standard offpage *
  page45_i45
#ISCELL
  standard offpage *
  page45_i46
#ISCELL
  standard offpage *
  page45_i47
#ISCELL
  standard offpage *
  page45_i48
#ISCELL
  standard offpage *
  page45_i49
#ISCELL
  standard offpage *
  page45_i50
#CELL
  pure_quanta q_res *
  page45_i51
#CELL
  pure_quanta q_res *
  page45_i52
#CELL
  pure_quanta q_res *
  page45_i53
#CELL
  pure_quanta q_res *
  page45_i54
#CELL
  pure_quanta q_res *
  page45_i55
#CELL
  pure_quanta q_res *
  page45_i56
#ISCELL
  standard offpage *
  page45_i57
#ISCELL
  standard offpage *
  page45_i58
#ISCELL
  standard offpage *
  page45_i59
#ISCELL
  standard offpage *
  page45_i60
#ISCELL
  standard offpage *
  page45_i61
#ISCELL
  standard offpage *
  page45_i62
#ISCELL
  standard offpage *
  page45_i67
#CELL
  pure_quanta q_res *
  page45_i69
#ISCELL
  standard offpage *
  page45_i7
#CELL
  pure_quanta q_res *
  page45_i70
#ISCELL
  standard offpage *
  page45_i71
#ISCELL
  standard offpage *
  page45_i72
#CELL
  pure_quanta q_res *
  page45_i73
#CELL
  pure_quanta q_res *
  page45_i74
#ISCELL
  logical_power universal_power *
  page45_i75
#ISCELL
  standard offpage *
  page45_i78
#ISCELL
  standard offpage *
  page45_i79
#ISCELL
  standard offpage *
  page45_i8
#CELL
  pure_quanta q_res *
  page45_i81
#CELL
  pure_quanta q_res *
  page45_i82
#ISCELL
  standard offpage *
  page45_i83
#ISCELL
  standard offpage *
  page45_i9
#ISCELL
  pure_quanta quanta_title_block_c *
  *
#ISCELL
  standard offpage *
  page46_i1
#ISCELL
  standard offpage *
  page46_i10
#ISCELL
  standard offpage *
  page46_i11
#ISCELL
  standard offpage *
  page46_i12
#ISCELL
  standard offpage *
  page46_i13
#ISCELL
  standard offpage *
  page46_i14
#ISCELL
  standard offpage *
  page46_i15
#ISCELL
  standard offpage *
  page46_i16
#ISCELL
  standard offpage *
  page46_i17
#ISCELL
  standard offpage *
  page46_i18
#ISCELL
  standard offpage *
  page46_i2
#ISCELL
  standard offpage *
  page46_i26
#ISCELL
  standard offpage *
  page46_i37
#ISCELL
  standard offpage *
  page46_i4
#CELL
  pure_quanta socket4677_azif0045p001c01cs *
  page46_i5
#ISCELL
  pure_quanta quanta_title_block_c *
  *
#ISCELL
  standard offpage *
  page47_i1
#ISCELL
  standard offpage *
  page47_i10
#ISCELL
  standard offpage *
  page47_i11
#CELL
  pure_quanta socket4677_azif0045p001c01cs *
  page47_i16
#ISCELL
  standard offpage *
  page47_i2
#CELL
  pure_quanta q_res *
  page47_i22
#CELL
  pure_quanta q_res *
  page47_i23
#CELL
  pure_quanta q_res *
  page47_i24
#CELL
  pure_quanta q_res *
  page47_i25
#ISCELL
  standard offpage *
  page47_i26
#ISCELL
  standard offpage *
  page47_i3
#ISCELL
  standard offpage *
  page47_i30
#ISCELL
  standard offpage *
  page47_i31
#ISCELL
  standard offpage *
  page47_i32
#ISCELL
  standard offpage *
  page47_i33
#CELL
  pure_quanta q_res *
  page47_i34
#CELL
  pure_quanta q_res *
  page47_i35
#ISCELL
  logical_power universal_power *
  page47_i36
#ISCELL
  standard offpage *
  page47_i4
#ISCELL
  standard offpage *
  page47_i5
#ISCELL
  standard offpage *
  page47_i6
#ISCELL
  standard offpage *
  page47_i7
#ISCELL
  standard offpage *
  page47_i8
#ISCELL
  standard offpage *
  page47_i9
#ISCELL
  pure_quanta quanta_title_block_c *
  *
#CELL
  pure_quanta socket4677_azif0045p001c01cs *
  page48_i1
#ISCELL
  pure_quanta quanta_title_block_c *
  *
#CELL
  pure_quanta socket4677_azif0045p001c01cs *
  page49_i2
#ISCELL
  pure_quanta quanta_title_block_c *
  *
#ISCELL
  standard offpage *
  page50_i19
#ISCELL
  standard offpage *
  page50_i20
#ISCELL
  standard offpage *
  page50_i21
#ISCELL
  standard offpage *
  page50_i22
#CELL
  pure_quanta socket4677_azif0045p001c01cs *
  page50_i23
#ISCELL
  pure_quanta quanta_title_block_c *
  *
#ISCELL
  standard tap *
  page51_i1
#ISCELL
  standard tap *
  page51_i10
#ISCELL
  standard tap *
  page51_i100
#ISCELL
  standard tap *
  page51_i101
#ISCELL
  standard tap *
  page51_i102
#ISCELL
  standard tap *
  page51_i103
#ISCELL
  standard tap *
  page51_i104
#ISCELL
  standard tap *
  page51_i105
#ISCELL
  standard tap *
  page51_i106
#ISCELL
  standard tap *
  page51_i107
#ISCELL
  standard tap *
  page51_i108
#ISCELL
  standard tap *
  page51_i109
#ISCELL
  standard tap *
  page51_i11
#ISCELL
  standard tap *
  page51_i110
#ISCELL
  standard tap *
  page51_i111
#ISCELL
  standard tap *
  page51_i112
#ISCELL
  standard tap *
  page51_i113
#ISCELL
  standard tap *
  page51_i114
#ISCELL
  standard offpage *
  page51_i115
#ISCELL
  standard offpage *
  page51_i116
#ISCELL
  standard offpage *
  page51_i117
#ISCELL
  standard offpage *
  page51_i118
#ISCELL
  standard offpage *
  page51_i119
#ISCELL
  standard tap *
  page51_i12
#ISCELL
  standard offpage *
  page51_i120
#ISCELL
  standard offpage *
  page51_i121
#ISCELL
  standard offpage *
  page51_i122
#ISCELL
  standard offpage *
  page51_i123
#ISCELL
  standard offpage *
  page51_i124
#ISCELL
  standard tap *
  page51_i125
#ISCELL
  standard tap *
  page51_i126
#ISCELL
  standard tap *
  page51_i127
#ISCELL
  standard tap *
  page51_i128
#ISCELL
  standard tap *
  page51_i129
#ISCELL
  standard tap *
  page51_i13
#ISCELL
  standard tap *
  page51_i130
#ISCELL
  standard tap *
  page51_i131
#ISCELL
  standard tap *
  page51_i132
#ISCELL
  standard tap *
  page51_i133
#ISCELL
  standard tap *
  page51_i134
#ISCELL
  standard tap *
  page51_i135
#ISCELL
  standard tap *
  page51_i136
#ISCELL
  standard tap *
  page51_i137
#ISCELL
  standard tap *
  page51_i138
#ISCELL
  standard tap *
  page51_i139
#ISCELL
  standard tap *
  page51_i14
#ISCELL
  standard tap *
  page51_i140
#ISCELL
  standard tap *
  page51_i141
#ISCELL
  standard tap *
  page51_i142
#ISCELL
  standard tap *
  page51_i143
#ISCELL
  standard tap *
  page51_i144
#ISCELL
  standard tap *
  page51_i145
#ISCELL
  standard tap *
  page51_i146
#ISCELL
  standard tap *
  page51_i147
#ISCELL
  standard tap *
  page51_i148
#ISCELL
  standard tap *
  page51_i149
#ISCELL
  standard tap *
  page51_i15
#ISCELL
  standard tap *
  page51_i150
#ISCELL
  standard tap *
  page51_i151
#ISCELL
  standard tap *
  page51_i152
#ISCELL
  standard tap *
  page51_i153
#ISCELL
  standard tap *
  page51_i154
#ISCELL
  standard tap *
  page51_i155
#ISCELL
  standard tap *
  page51_i156
#ISCELL
  standard tap *
  page51_i157
#ISCELL
  standard tap *
  page51_i158
#ISCELL
  standard tap *
  page51_i159
#ISCELL
  standard tap *
  page51_i16
#ISCELL
  standard tap *
  page51_i160
#ISCELL
  standard tap *
  page51_i161
#ISCELL
  standard offpage *
  page51_i162
#ISCELL
  standard offpage *
  page51_i163
#ISCELL
  standard offpage *
  page51_i164
#ISCELL
  standard tap *
  page51_i165
#ISCELL
  standard tap *
  page51_i166
#ISCELL
  standard tap *
  page51_i167
#ISCELL
  standard offpage *
  page51_i168
#ISCELL
  standard tap *
  page51_i17
#ISCELL
  standard tap *
  page51_i18
#ISCELL
  standard tap *
  page51_i19
#CELL
  pure_quanta socket4677_azif0045p001c01cs *
  page51_i2
#ISCELL
  standard tap *
  page51_i20
#ISCELL
  standard tap *
  page51_i21
#ISCELL
  standard tap *
  page51_i22
#ISCELL
  standard tap *
  page51_i23
#ISCELL
  standard tap *
  page51_i24
#ISCELL
  standard tap *
  page51_i25
#ISCELL
  standard tap *
  page51_i26
#ISCELL
  standard tap *
  page51_i27
#ISCELL
  standard tap *
  page51_i28
#ISCELL
  standard tap *
  page51_i29
#ISCELL
  standard offpage *
  page51_i3
#ISCELL
  standard tap *
  page51_i30
#ISCELL
  standard tap *
  page51_i31
#ISCELL
  standard tap *
  page51_i32
#ISCELL
  standard tap *
  page51_i33
#ISCELL
  standard tap *
  page51_i34
#ISCELL
  standard tap *
  page51_i35
#ISCELL
  standard tap *
  page51_i36
#ISCELL
  standard tap *
  page51_i37
#ISCELL
  standard tap *
  page51_i38
#ISCELL
  standard tap *
  page51_i39
#ISCELL
  standard offpage *
  page51_i4
#ISCELL
  standard tap *
  page51_i40
#ISCELL
  standard tap *
  page51_i41
#ISCELL
  standard tap *
  page51_i42
#ISCELL
  standard tap *
  page51_i43
#ISCELL
  standard tap *
  page51_i44
#ISCELL
  standard offpage *
  page51_i45
#ISCELL
  standard offpage *
  page51_i46
#ISCELL
  standard tap *
  page51_i47
#ISCELL
  standard tap *
  page51_i48
#ISCELL
  standard tap *
  page51_i49
#ISCELL
  standard offpage *
  page51_i5
#ISCELL
  standard tap *
  page51_i50
#ISCELL
  standard tap *
  page51_i51
#ISCELL
  standard tap *
  page51_i52
#ISCELL
  standard tap *
  page51_i53
#ISCELL
  standard tap *
  page51_i54
#ISCELL
  standard tap *
  page51_i55
#ISCELL
  standard tap *
  page51_i56
#ISCELL
  standard tap *
  page51_i57
#ISCELL
  standard tap *
  page51_i58
#ISCELL
  standard tap *
  page51_i59
#ISCELL
  standard tap *
  page51_i6
#ISCELL
  standard tap *
  page51_i60
#ISCELL
  standard tap *
  page51_i61
#ISCELL
  standard tap *
  page51_i62
#ISCELL
  standard tap *
  page51_i63
#ISCELL
  standard tap *
  page51_i64
#ISCELL
  standard tap *
  page51_i65
#ISCELL
  standard tap *
  page51_i66
#ISCELL
  standard tap *
  page51_i67
#ISCELL
  standard tap *
  page51_i68
#ISCELL
  standard tap *
  page51_i69
#ISCELL
  standard tap *
  page51_i7
#ISCELL
  standard tap *
  page51_i70
#ISCELL
  standard tap *
  page51_i71
#ISCELL
  standard tap *
  page51_i72
#ISCELL
  standard tap *
  page51_i73
#ISCELL
  standard tap *
  page51_i74
#ISCELL
  standard tap *
  page51_i75
#ISCELL
  standard tap *
  page51_i76
#ISCELL
  standard tap *
  page51_i77
#ISCELL
  standard tap *
  page51_i78
#ISCELL
  standard tap *
  page51_i79
#ISCELL
  standard tap *
  page51_i8
#ISCELL
  standard tap *
  page51_i80
#ISCELL
  standard tap *
  page51_i81
#ISCELL
  standard tap *
  page51_i82
#ISCELL
  standard tap *
  page51_i83
#ISCELL
  standard tap *
  page51_i84
#ISCELL
  standard tap *
  page51_i85
#ISCELL
  standard tap *
  page51_i86
#ISCELL
  standard tap *
  page51_i87
#ISCELL
  standard offpage *
  page51_i88
#ISCELL
  standard tap *
  page51_i89
#ISCELL
  standard tap *
  page51_i9
#ISCELL
  standard tap *
  page51_i90
#ISCELL
  standard tap *
  page51_i91
#ISCELL
  standard offpage *
  page51_i92
#ISCELL
  standard tap *
  page51_i93
#ISCELL
  standard tap *
  page51_i94
#ISCELL
  standard tap *
  page51_i95
#ISCELL
  standard tap *
  page51_i96
#ISCELL
  standard tap *
  page51_i97
#ISCELL
  standard tap *
  page51_i98
#ISCELL
  standard tap *
  page51_i99
#ISCELL
  pure_quanta quanta_title_block_c *
  *
#ISCELL
  standard offpage *
  page52_i1
#ISCELL
  standard tap *
  page52_i10
#ISCELL
  standard tap *
  page52_i100
#ISCELL
  standard tap *
  page52_i101
#ISCELL
  standard tap *
  page52_i102
#ISCELL
  standard tap *
  page52_i103
#ISCELL
  standard tap *
  page52_i104
#ISCELL
  standard tap *
  page52_i105
#ISCELL
  standard tap *
  page52_i106
#ISCELL
  standard tap *
  page52_i107
#ISCELL
  standard tap *
  page52_i108
#ISCELL
  standard tap *
  page52_i109
#ISCELL
  standard tap *
  page52_i11
#ISCELL
  standard tap *
  page52_i110
#ISCELL
  standard tap *
  page52_i111
#ISCELL
  standard tap *
  page52_i112
#ISCELL
  standard tap *
  page52_i113
#ISCELL
  standard tap *
  page52_i114
#ISCELL
  standard tap *
  page52_i115
#ISCELL
  standard tap *
  page52_i116
#ISCELL
  standard tap *
  page52_i117
#ISCELL
  standard tap *
  page52_i118
#ISCELL
  standard tap *
  page52_i119
#ISCELL
  standard tap *
  page52_i12
#ISCELL
  standard tap *
  page52_i120
#ISCELL
  standard tap *
  page52_i121
#ISCELL
  standard tap *
  page52_i122
#ISCELL
  standard tap *
  page52_i123
#ISCELL
  standard tap *
  page52_i124
#ISCELL
  standard tap *
  page52_i125
#ISCELL
  standard tap *
  page52_i126
#ISCELL
  standard tap *
  page52_i127
#ISCELL
  standard tap *
  page52_i128
#ISCELL
  standard tap *
  page52_i129
#ISCELL
  standard tap *
  page52_i13
#ISCELL
  standard tap *
  page52_i130
#ISCELL
  standard tap *
  page52_i131
#ISCELL
  standard tap *
  page52_i132
#ISCELL
  standard tap *
  page52_i133
#ISCELL
  standard tap *
  page52_i134
#ISCELL
  standard tap *
  page52_i135
#ISCELL
  standard tap *
  page52_i136
#ISCELL
  standard tap *
  page52_i137
#ISCELL
  standard tap *
  page52_i138
#ISCELL
  standard tap *
  page52_i139
#ISCELL
  standard tap *
  page52_i14
#ISCELL
  standard tap *
  page52_i140
#ISCELL
  standard tap *
  page52_i141
#ISCELL
  standard tap *
  page52_i142
#ISCELL
  standard tap *
  page52_i143
#ISCELL
  standard tap *
  page52_i144
#ISCELL
  standard tap *
  page52_i145
#ISCELL
  standard tap *
  page52_i146
#ISCELL
  standard tap *
  page52_i147
#ISCELL
  standard tap *
  page52_i148
#ISCELL
  standard tap *
  page52_i149
#ISCELL
  standard tap *
  page52_i15
#ISCELL
  standard tap *
  page52_i150
#ISCELL
  standard tap *
  page52_i151
#ISCELL
  standard tap *
  page52_i152
#ISCELL
  standard tap *
  page52_i153
#ISCELL
  standard tap *
  page52_i154
#ISCELL
  standard tap *
  page52_i155
#ISCELL
  standard tap *
  page52_i156
#ISCELL
  standard tap *
  page52_i157
#ISCELL
  standard offpage *
  page52_i158
#ISCELL
  standard offpage *
  page52_i159
#ISCELL
  standard tap *
  page52_i16
#ISCELL
  standard offpage *
  page52_i160
#ISCELL
  standard offpage *
  page52_i161
#ISCELL
  standard offpage *
  page52_i162
#ISCELL
  standard offpage *
  page52_i163
#ISCELL
  standard offpage *
  page52_i164
#ISCELL
  standard offpage *
  page52_i165
#ISCELL
  standard offpage *
  page52_i166
#ISCELL
  standard offpage *
  page52_i167
#ISCELL
  standard offpage *
  page52_i168
#ISCELL
  standard tap *
  page52_i17
#ISCELL
  standard tap *
  page52_i18
#ISCELL
  standard tap *
  page52_i19
#ISCELL
  standard offpage *
  page52_i2
#ISCELL
  standard tap *
  page52_i20
#ISCELL
  standard tap *
  page52_i21
#ISCELL
  standard tap *
  page52_i22
#ISCELL
  standard tap *
  page52_i23
#ISCELL
  standard tap *
  page52_i24
#ISCELL
  standard tap *
  page52_i25
#ISCELL
  standard tap *
  page52_i26
#ISCELL
  standard tap *
  page52_i27
#ISCELL
  standard tap *
  page52_i28
#ISCELL
  standard tap *
  page52_i29
#ISCELL
  standard tap *
  page52_i3
#ISCELL
  standard tap *
  page52_i30
#ISCELL
  standard tap *
  page52_i31
#ISCELL
  standard tap *
  page52_i32
#ISCELL
  standard tap *
  page52_i33
#ISCELL
  standard tap *
  page52_i34
#ISCELL
  standard tap *
  page52_i35
#ISCELL
  standard tap *
  page52_i36
#ISCELL
  standard tap *
  page52_i37
#ISCELL
  standard tap *
  page52_i38
#ISCELL
  standard tap *
  page52_i39
#ISCELL
  standard tap *
  page52_i4
#ISCELL
  standard tap *
  page52_i40
#ISCELL
  standard tap *
  page52_i41
#ISCELL
  standard tap *
  page52_i42
#ISCELL
  standard tap *
  page52_i43
#ISCELL
  standard tap *
  page52_i44
#ISCELL
  standard tap *
  page52_i45
#ISCELL
  standard tap *
  page52_i46
#ISCELL
  standard tap *
  page52_i47
#ISCELL
  standard tap *
  page52_i48
#ISCELL
  standard tap *
  page52_i49
#ISCELL
  standard tap *
  page52_i5
#ISCELL
  standard offpage *
  page52_i50
#ISCELL
  standard offpage *
  page52_i51
#ISCELL
  standard tap *
  page52_i52
#ISCELL
  standard tap *
  page52_i53
#ISCELL
  standard tap *
  page52_i54
#ISCELL
  standard tap *
  page52_i55
#ISCELL
  standard tap *
  page52_i56
#ISCELL
  standard tap *
  page52_i57
#ISCELL
  standard tap *
  page52_i58
#ISCELL
  standard tap *
  page52_i59
#ISCELL
  standard tap *
  page52_i6
#ISCELL
  standard tap *
  page52_i60
#ISCELL
  standard tap *
  page52_i61
#ISCELL
  standard tap *
  page52_i62
#ISCELL
  standard tap *
  page52_i63
#ISCELL
  standard tap *
  page52_i64
#ISCELL
  standard tap *
  page52_i65
#ISCELL
  standard tap *
  page52_i66
#ISCELL
  standard tap *
  page52_i67
#ISCELL
  standard tap *
  page52_i68
#ISCELL
  standard tap *
  page52_i69
#ISCELL
  standard offpage *
  page52_i7
#ISCELL
  standard tap *
  page52_i70
#ISCELL
  standard tap *
  page52_i71
#ISCELL
  standard tap *
  page52_i72
#ISCELL
  standard tap *
  page52_i73
#ISCELL
  standard tap *
  page52_i74
#ISCELL
  standard tap *
  page52_i75
#ISCELL
  standard tap *
  page52_i76
#ISCELL
  standard tap *
  page52_i77
#ISCELL
  standard tap *
  page52_i78
#ISCELL
  standard tap *
  page52_i79
#ISCELL
  standard offpage *
  page52_i8
#ISCELL
  standard tap *
  page52_i80
#ISCELL
  standard tap *
  page52_i81
#ISCELL
  standard tap *
  page52_i82
#ISCELL
  standard tap *
  page52_i83
#ISCELL
  standard tap *
  page52_i84
#ISCELL
  standard tap *
  page52_i85
#ISCELL
  standard tap *
  page52_i86
#ISCELL
  standard tap *
  page52_i87
#ISCELL
  standard tap *
  page52_i88
#ISCELL
  standard tap *
  page52_i89
#ISCELL
  standard tap *
  page52_i9
#ISCELL
  standard tap *
  page52_i90
#CELL
  pure_quanta socket4677_azif0045p001c01cs *
  page52_i91
#ISCELL
  standard offpage *
  page52_i92
#ISCELL
  standard offpage *
  page52_i93
#ISCELL
  standard offpage *
  page52_i94
#ISCELL
  standard offpage *
  page52_i95
#ISCELL
  standard tap *
  page52_i96
#ISCELL
  standard tap *
  page52_i97
#ISCELL
  standard tap *
  page52_i98
#ISCELL
  standard tap *
  page52_i99
#ISCELL
  pure_quanta quanta_title_block_c *
  *
#ISCELL
  standard offpage *
  page53_i1
#ISCELL
  standard tap *
  page53_i10
#ISCELL
  standard tap *
  page53_i100
#ISCELL
  standard tap *
  page53_i101
#ISCELL
  standard tap *
  page53_i102
#ISCELL
  standard tap *
  page53_i103
#ISCELL
  standard tap *
  page53_i104
#ISCELL
  standard tap *
  page53_i105
#ISCELL
  standard tap *
  page53_i106
#ISCELL
  standard tap *
  page53_i107
#ISCELL
  standard tap *
  page53_i108
#ISCELL
  standard tap *
  page53_i109
#ISCELL
  standard tap *
  page53_i11
#ISCELL
  standard tap *
  page53_i110
#ISCELL
  standard tap *
  page53_i111
#ISCELL
  standard tap *
  page53_i112
#ISCELL
  standard tap *
  page53_i113
#ISCELL
  standard tap *
  page53_i114
#ISCELL
  standard tap *
  page53_i115
#ISCELL
  standard tap *
  page53_i116
#ISCELL
  standard tap *
  page53_i117
#ISCELL
  standard tap *
  page53_i118
#ISCELL
  standard tap *
  page53_i119
#ISCELL
  standard tap *
  page53_i12
#ISCELL
  standard tap *
  page53_i120
#ISCELL
  standard tap *
  page53_i121
#ISCELL
  standard tap *
  page53_i122
#ISCELL
  standard tap *
  page53_i123
#ISCELL
  standard tap *
  page53_i124
#ISCELL
  standard tap *
  page53_i125
#ISCELL
  standard tap *
  page53_i126
#ISCELL
  standard tap *
  page53_i127
#ISCELL
  standard tap *
  page53_i128
#ISCELL
  standard tap *
  page53_i129
#ISCELL
  standard tap *
  page53_i13
#ISCELL
  standard tap *
  page53_i130
#ISCELL
  standard tap *
  page53_i131
#ISCELL
  standard tap *
  page53_i132
#ISCELL
  standard tap *
  page53_i133
#ISCELL
  standard tap *
  page53_i134
#ISCELL
  standard tap *
  page53_i135
#ISCELL
  standard tap *
  page53_i136
#ISCELL
  standard tap *
  page53_i137
#ISCELL
  standard tap *
  page53_i138
#ISCELL
  standard tap *
  page53_i139
#ISCELL
  standard offpage *
  page53_i14
#ISCELL
  standard tap *
  page53_i140
#ISCELL
  standard tap *
  page53_i141
#ISCELL
  standard tap *
  page53_i142
#ISCELL
  standard tap *
  page53_i143
#ISCELL
  standard tap *
  page53_i144
#ISCELL
  standard tap *
  page53_i145
#ISCELL
  standard tap *
  page53_i146
#ISCELL
  standard tap *
  page53_i147
#ISCELL
  standard tap *
  page53_i148
#ISCELL
  standard tap *
  page53_i149
#ISCELL
  standard offpage *
  page53_i15
#ISCELL
  standard tap *
  page53_i150
#ISCELL
  standard tap *
  page53_i151
#ISCELL
  standard tap *
  page53_i152
#ISCELL
  standard tap *
  page53_i153
#ISCELL
  standard tap *
  page53_i154
#ISCELL
  standard tap *
  page53_i155
#ISCELL
  standard tap *
  page53_i156
#ISCELL
  standard tap *
  page53_i157
#ISCELL
  standard tap *
  page53_i158
#ISCELL
  standard offpage *
  page53_i159
#ISCELL
  standard offpage *
  page53_i16
#ISCELL
  standard offpage *
  page53_i160
#ISCELL
  standard offpage *
  page53_i161
#ISCELL
  standard offpage *
  page53_i162
#ISCELL
  standard offpage *
  page53_i163
#ISCELL
  standard offpage *
  page53_i164
#ISCELL
  standard offpage *
  page53_i165
#ISCELL
  standard offpage *
  page53_i166
#ISCELL
  standard offpage *
  page53_i167
#ISCELL
  standard offpage *
  page53_i168
#ISCELL
  standard tap *
  page53_i17
#ISCELL
  standard tap *
  page53_i18
#ISCELL
  standard tap *
  page53_i19
#ISCELL
  standard offpage *
  page53_i2
#ISCELL
  standard tap *
  page53_i20
#ISCELL
  standard tap *
  page53_i21
#ISCELL
  standard tap *
  page53_i22
#ISCELL
  standard tap *
  page53_i23
#ISCELL
  standard tap *
  page53_i24
#ISCELL
  standard tap *
  page53_i25
#ISCELL
  standard tap *
  page53_i26
#ISCELL
  standard tap *
  page53_i27
#ISCELL
  standard tap *
  page53_i28
#ISCELL
  standard tap *
  page53_i29
#ISCELL
  standard tap *
  page53_i3
#ISCELL
  standard tap *
  page53_i30
#ISCELL
  standard tap *
  page53_i31
#ISCELL
  standard tap *
  page53_i32
#ISCELL
  standard tap *
  page53_i33
#ISCELL
  standard tap *
  page53_i34
#ISCELL
  standard tap *
  page53_i35
#ISCELL
  standard tap *
  page53_i36
#ISCELL
  standard tap *
  page53_i37
#ISCELL
  standard tap *
  page53_i38
#ISCELL
  standard tap *
  page53_i39
#ISCELL
  standard tap *
  page53_i4
#ISCELL
  standard tap *
  page53_i40
#ISCELL
  standard tap *
  page53_i41
#ISCELL
  standard tap *
  page53_i42
#ISCELL
  standard tap *
  page53_i43
#ISCELL
  standard tap *
  page53_i44
#ISCELL
  standard tap *
  page53_i45
#ISCELL
  standard tap *
  page53_i46
#ISCELL
  standard tap *
  page53_i47
#ISCELL
  standard tap *
  page53_i48
#ISCELL
  standard tap *
  page53_i49
#ISCELL
  standard tap *
  page53_i5
#ISCELL
  standard tap *
  page53_i50
#ISCELL
  standard tap *
  page53_i51
#ISCELL
  standard tap *
  page53_i52
#ISCELL
  standard tap *
  page53_i53
#ISCELL
  standard tap *
  page53_i54
#ISCELL
  standard tap *
  page53_i55
#ISCELL
  standard tap *
  page53_i56
#ISCELL
  standard offpage *
  page53_i57
#ISCELL
  standard tap *
  page53_i58
#ISCELL
  standard tap *
  page53_i59
#ISCELL
  standard tap *
  page53_i6
#ISCELL
  standard tap *
  page53_i60
#ISCELL
  standard tap *
  page53_i61
#ISCELL
  standard tap *
  page53_i62
#ISCELL
  standard tap *
  page53_i63
#ISCELL
  standard tap *
  page53_i64
#ISCELL
  standard tap *
  page53_i65
#ISCELL
  standard tap *
  page53_i66
#ISCELL
  standard tap *
  page53_i67
#ISCELL
  standard tap *
  page53_i68
#ISCELL
  standard tap *
  page53_i69
#ISCELL
  standard tap *
  page53_i7
#ISCELL
  standard tap *
  page53_i70
#ISCELL
  standard tap *
  page53_i71
#ISCELL
  standard tap *
  page53_i72
#ISCELL
  standard tap *
  page53_i73
#ISCELL
  standard tap *
  page53_i74
#ISCELL
  standard tap *
  page53_i75
#ISCELL
  standard tap *
  page53_i76
#ISCELL
  standard tap *
  page53_i77
#ISCELL
  standard tap *
  page53_i78
#ISCELL
  standard tap *
  page53_i79
#ISCELL
  standard tap *
  page53_i8
#ISCELL
  standard tap *
  page53_i80
#ISCELL
  standard tap *
  page53_i81
#ISCELL
  standard tap *
  page53_i82
#ISCELL
  standard tap *
  page53_i83
#ISCELL
  standard tap *
  page53_i84
#ISCELL
  standard tap *
  page53_i85
#ISCELL
  standard tap *
  page53_i86
#ISCELL
  standard tap *
  page53_i87
#ISCELL
  standard tap *
  page53_i88
#ISCELL
  standard tap *
  page53_i89
#ISCELL
  standard tap *
  page53_i9
#ISCELL
  standard tap *
  page53_i90
#CELL
  pure_quanta socket4677_azif0045p001c01cs *
  page53_i91
#ISCELL
  standard tap *
  page53_i92
#ISCELL
  standard tap *
  page53_i93
#ISCELL
  standard tap *
  page53_i94
#ISCELL
  standard offpage *
  page53_i95
#ISCELL
  standard offpage *
  page53_i96
#ISCELL
  standard offpage *
  page53_i97
#ISCELL
  standard offpage *
  page53_i98
#ISCELL
  standard offpage *
  page53_i99
#ISCELL
  pure_quanta quanta_title_block_c *
  *
#ISCELL
  standard offpage *
  page54_i1
#ISCELL
  standard offpage *
  page54_i10
#ISCELL
  standard tap *
  page54_i100
#ISCELL
  standard tap *
  page54_i101
#ISCELL
  standard tap *
  page54_i102
#ISCELL
  standard tap *
  page54_i103
#ISCELL
  standard tap *
  page54_i104
#ISCELL
  standard tap *
  page54_i105
#ISCELL
  standard tap *
  page54_i106
#ISCELL
  standard tap *
  page54_i107
#ISCELL
  standard tap *
  page54_i108
#ISCELL
  standard tap *
  page54_i109
#ISCELL
  standard tap *
  page54_i11
#ISCELL
  standard tap *
  page54_i110
#ISCELL
  standard tap *
  page54_i111
#ISCELL
  standard tap *
  page54_i112
#ISCELL
  standard tap *
  page54_i113
#ISCELL
  standard tap *
  page54_i114
#ISCELL
  standard tap *
  page54_i115
#ISCELL
  standard tap *
  page54_i116
#ISCELL
  standard tap *
  page54_i117
#ISCELL
  standard tap *
  page54_i118
#ISCELL
  standard tap *
  page54_i119
#ISCELL
  standard tap *
  page54_i12
#ISCELL
  standard tap *
  page54_i120
#ISCELL
  standard tap *
  page54_i121
#ISCELL
  standard tap *
  page54_i122
#ISCELL
  standard tap *
  page54_i123
#ISCELL
  standard tap *
  page54_i124
#ISCELL
  standard tap *
  page54_i125
#ISCELL
  standard tap *
  page54_i126
#ISCELL
  standard tap *
  page54_i127
#ISCELL
  standard tap *
  page54_i128
#ISCELL
  standard tap *
  page54_i129
#ISCELL
  standard tap *
  page54_i13
#ISCELL
  standard tap *
  page54_i130
#ISCELL
  standard tap *
  page54_i131
#ISCELL
  standard tap *
  page54_i132
#ISCELL
  standard tap *
  page54_i133
#ISCELL
  standard tap *
  page54_i134
#ISCELL
  standard tap *
  page54_i135
#ISCELL
  standard tap *
  page54_i136
#ISCELL
  standard tap *
  page54_i137
#ISCELL
  standard tap *
  page54_i138
#ISCELL
  standard tap *
  page54_i139
#ISCELL
  standard tap *
  page54_i14
#ISCELL
  standard tap *
  page54_i140
#ISCELL
  standard tap *
  page54_i141
#ISCELL
  standard tap *
  page54_i142
#ISCELL
  standard tap *
  page54_i143
#ISCELL
  standard tap *
  page54_i144
#ISCELL
  standard tap *
  page54_i145
#ISCELL
  standard tap *
  page54_i146
#ISCELL
  standard tap *
  page54_i147
#ISCELL
  standard tap *
  page54_i148
#ISCELL
  standard tap *
  page54_i149
#ISCELL
  standard tap *
  page54_i15
#ISCELL
  standard tap *
  page54_i150
#ISCELL
  standard tap *
  page54_i151
#ISCELL
  standard tap *
  page54_i152
#ISCELL
  standard tap *
  page54_i153
#ISCELL
  standard tap *
  page54_i154
#ISCELL
  standard tap *
  page54_i155
#ISCELL
  standard tap *
  page54_i156
#ISCELL
  standard tap *
  page54_i157
#ISCELL
  standard tap *
  page54_i158
#ISCELL
  standard offpage *
  page54_i159
#ISCELL
  standard tap *
  page54_i16
#ISCELL
  standard offpage *
  page54_i160
#ISCELL
  standard offpage *
  page54_i161
#ISCELL
  standard offpage *
  page54_i162
#ISCELL
  standard offpage *
  page54_i163
#ISCELL
  standard offpage *
  page54_i164
#ISCELL
  standard offpage *
  page54_i165
#ISCELL
  standard offpage *
  page54_i166
#ISCELL
  standard offpage *
  page54_i167
#ISCELL
  standard offpage *
  page54_i168
#ISCELL
  standard tap *
  page54_i17
#ISCELL
  standard tap *
  page54_i18
#ISCELL
  standard tap *
  page54_i19
#ISCELL
  standard offpage *
  page54_i2
#ISCELL
  standard tap *
  page54_i20
#ISCELL
  standard tap *
  page54_i21
#ISCELL
  standard tap *
  page54_i22
#ISCELL
  standard tap *
  page54_i23
#ISCELL
  standard tap *
  page54_i24
#ISCELL
  standard tap *
  page54_i25
#ISCELL
  standard tap *
  page54_i26
#ISCELL
  standard tap *
  page54_i27
#ISCELL
  standard tap *
  page54_i28
#ISCELL
  standard tap *
  page54_i29
#ISCELL
  standard tap *
  page54_i3
#ISCELL
  standard tap *
  page54_i30
#ISCELL
  standard tap *
  page54_i31
#ISCELL
  standard tap *
  page54_i32
#ISCELL
  standard tap *
  page54_i33
#ISCELL
  standard tap *
  page54_i34
#ISCELL
  standard tap *
  page54_i35
#ISCELL
  standard tap *
  page54_i36
#ISCELL
  standard tap *
  page54_i37
#ISCELL
  standard tap *
  page54_i38
#ISCELL
  standard tap *
  page54_i39
#ISCELL
  standard tap *
  page54_i4
#ISCELL
  standard tap *
  page54_i40
#ISCELL
  standard tap *
  page54_i41
#ISCELL
  standard tap *
  page54_i42
#ISCELL
  standard tap *
  page54_i43
#ISCELL
  standard tap *
  page54_i44
#ISCELL
  standard tap *
  page54_i45
#ISCELL
  standard tap *
  page54_i46
#ISCELL
  standard tap *
  page54_i47
#ISCELL
  standard tap *
  page54_i48
#ISCELL
  standard tap *
  page54_i49
#ISCELL
  standard tap *
  page54_i5
#ISCELL
  standard tap *
  page54_i50
#ISCELL
  standard offpage *
  page54_i51
#ISCELL
  standard offpage *
  page54_i52
#ISCELL
  standard tap *
  page54_i53
#ISCELL
  standard tap *
  page54_i54
#ISCELL
  standard tap *
  page54_i55
#ISCELL
  standard tap *
  page54_i56
#ISCELL
  standard tap *
  page54_i57
#ISCELL
  standard tap *
  page54_i58
#ISCELL
  standard tap *
  page54_i59
#ISCELL
  standard tap *
  page54_i6
#ISCELL
  standard tap *
  page54_i60
#ISCELL
  standard tap *
  page54_i61
#ISCELL
  standard tap *
  page54_i62
#ISCELL
  standard tap *
  page54_i63
#ISCELL
  standard tap *
  page54_i64
#ISCELL
  standard tap *
  page54_i65
#ISCELL
  standard tap *
  page54_i66
#ISCELL
  standard tap *
  page54_i67
#ISCELL
  standard tap *
  page54_i68
#ISCELL
  standard tap *
  page54_i69
#ISCELL
  standard tap *
  page54_i7
#ISCELL
  standard tap *
  page54_i70
#ISCELL
  standard tap *
  page54_i71
#ISCELL
  standard tap *
  page54_i72
#ISCELL
  standard tap *
  page54_i73
#ISCELL
  standard tap *
  page54_i74
#ISCELL
  standard tap *
  page54_i75
#ISCELL
  standard tap *
  page54_i76
#ISCELL
  standard tap *
  page54_i77
#ISCELL
  standard tap *
  page54_i78
#ISCELL
  standard tap *
  page54_i79
#ISCELL
  standard tap *
  page54_i8
#ISCELL
  standard tap *
  page54_i80
#ISCELL
  standard tap *
  page54_i81
#ISCELL
  standard tap *
  page54_i82
#ISCELL
  standard tap *
  page54_i83
#ISCELL
  standard tap *
  page54_i84
#ISCELL
  standard tap *
  page54_i85
#ISCELL
  standard tap *
  page54_i86
#ISCELL
  standard tap *
  page54_i87
#ISCELL
  standard tap *
  page54_i88
#ISCELL
  standard tap *
  page54_i89
#ISCELL
  standard offpage *
  page54_i9
#ISCELL
  standard tap *
  page54_i90
#CELL
  pure_quanta socket4677_azif0045p001c01cs *
  page54_i91
#ISCELL
  standard offpage *
  page54_i92
#ISCELL
  standard offpage *
  page54_i93
#ISCELL
  standard offpage *
  page54_i94
#ISCELL
  standard offpage *
  page54_i95
#ISCELL
  standard offpage *
  page54_i96
#ISCELL
  standard tap *
  page54_i97
#ISCELL
  standard tap *
  page54_i98
#ISCELL
  standard tap *
  page54_i99
#ISCELL
  pure_quanta quanta_title_block_c *
  *
#ISCELL
  standard offpage *
  page55_i1
#ISCELL
  standard tap *
  page55_i10
#ISCELL
  standard tap *
  page55_i100
#ISCELL
  standard tap *
  page55_i101
#ISCELL
  standard tap *
  page55_i102
#ISCELL
  standard tap *
  page55_i103
#ISCELL
  standard tap *
  page55_i104
#ISCELL
  standard tap *
  page55_i105
#ISCELL
  standard tap *
  page55_i106
#ISCELL
  standard tap *
  page55_i107
#ISCELL
  standard tap *
  page55_i108
#ISCELL
  standard tap *
  page55_i109
#ISCELL
  standard tap *
  page55_i11
#ISCELL
  standard tap *
  page55_i110
#ISCELL
  standard tap *
  page55_i111
#ISCELL
  standard tap *
  page55_i112
#ISCELL
  standard tap *
  page55_i113
#ISCELL
  standard tap *
  page55_i114
#ISCELL
  standard tap *
  page55_i115
#ISCELL
  standard tap *
  page55_i116
#ISCELL
  standard tap *
  page55_i117
#ISCELL
  standard tap *
  page55_i118
#ISCELL
  standard tap *
  page55_i119
#ISCELL
  standard tap *
  page55_i12
#ISCELL
  standard tap *
  page55_i120
#ISCELL
  standard offpage *
  page55_i121
#ISCELL
  standard offpage *
  page55_i122
#ISCELL
  standard offpage *
  page55_i123
#ISCELL
  standard offpage *
  page55_i124
#ISCELL
  standard offpage *
  page55_i125
#ISCELL
  standard offpage *
  page55_i126
#ISCELL
  standard offpage *
  page55_i127
#ISCELL
  standard offpage *
  page55_i128
#ISCELL
  standard tap *
  page55_i129
#ISCELL
  standard tap *
  page55_i13
#ISCELL
  standard tap *
  page55_i130
#ISCELL
  standard tap *
  page55_i131
#ISCELL
  standard tap *
  page55_i132
#ISCELL
  standard tap *
  page55_i133
#ISCELL
  standard tap *
  page55_i134
#ISCELL
  standard tap *
  page55_i135
#ISCELL
  standard tap *
  page55_i136
#ISCELL
  standard tap *
  page55_i137
#ISCELL
  standard tap *
  page55_i138
#ISCELL
  standard tap *
  page55_i139
#ISCELL
  standard tap *
  page55_i14
#ISCELL
  standard tap *
  page55_i140
#ISCELL
  standard tap *
  page55_i141
#ISCELL
  standard tap *
  page55_i142
#ISCELL
  standard tap *
  page55_i143
#ISCELL
  standard tap *
  page55_i144
#ISCELL
  standard tap *
  page55_i145
#ISCELL
  standard tap *
  page55_i146
#ISCELL
  standard tap *
  page55_i147
#ISCELL
  standard tap *
  page55_i148
#ISCELL
  standard tap *
  page55_i149
#ISCELL
  standard tap *
  page55_i15
#ISCELL
  standard tap *
  page55_i150
#ISCELL
  standard tap *
  page55_i151
#ISCELL
  standard tap *
  page55_i152
#ISCELL
  standard tap *
  page55_i153
#ISCELL
  standard tap *
  page55_i154
#ISCELL
  standard tap *
  page55_i155
#ISCELL
  standard tap *
  page55_i156
#ISCELL
  standard tap *
  page55_i157
#ISCELL
  standard tap *
  page55_i158
#ISCELL
  standard tap *
  page55_i159
#ISCELL
  standard tap *
  page55_i16
#ISCELL
  standard tap *
  page55_i160
#ISCELL
  standard tap *
  page55_i161
#ISCELL
  standard tap *
  page55_i162
#ISCELL
  standard tap *
  page55_i163
#ISCELL
  standard tap *
  page55_i164
#ISCELL
  standard offpage *
  page55_i165
#ISCELL
  standard offpage *
  page55_i166
#ISCELL
  standard offpage *
  page55_i167
#ISCELL
  standard offpage *
  page55_i168
#ISCELL
  standard tap *
  page55_i17
#ISCELL
  standard tap *
  page55_i18
#ISCELL
  standard tap *
  page55_i19
#ISCELL
  standard offpage *
  page55_i2
#ISCELL
  standard tap *
  page55_i20
#ISCELL
  standard tap *
  page55_i21
#ISCELL
  standard tap *
  page55_i22
#ISCELL
  standard tap *
  page55_i23
#ISCELL
  standard tap *
  page55_i24
#ISCELL
  standard tap *
  page55_i25
#ISCELL
  standard tap *
  page55_i26
#ISCELL
  standard tap *
  page55_i27
#ISCELL
  standard tap *
  page55_i28
#ISCELL
  standard tap *
  page55_i29
#ISCELL
  standard tap *
  page55_i3
#ISCELL
  standard tap *
  page55_i30
#ISCELL
  standard tap *
  page55_i31
#ISCELL
  standard tap *
  page55_i32
#ISCELL
  standard tap *
  page55_i33
#ISCELL
  standard tap *
  page55_i34
#ISCELL
  standard tap *
  page55_i35
#ISCELL
  standard tap *
  page55_i36
#ISCELL
  standard tap *
  page55_i37
#ISCELL
  standard tap *
  page55_i38
#ISCELL
  standard tap *
  page55_i39
#ISCELL
  standard tap *
  page55_i4
#ISCELL
  standard tap *
  page55_i40
#ISCELL
  standard tap *
  page55_i41
#ISCELL
  standard tap *
  page55_i42
#ISCELL
  standard tap *
  page55_i43
#ISCELL
  standard tap *
  page55_i44
#ISCELL
  standard tap *
  page55_i45
#ISCELL
  standard tap *
  page55_i46
#ISCELL
  standard tap *
  page55_i47
#ISCELL
  standard tap *
  page55_i48
#ISCELL
  standard tap *
  page55_i49
#ISCELL
  standard tap *
  page55_i5
#ISCELL
  standard offpage *
  page55_i50
#ISCELL
  standard offpage *
  page55_i51
#ISCELL
  standard tap *
  page55_i52
#ISCELL
  standard tap *
  page55_i53
#ISCELL
  standard tap *
  page55_i54
#ISCELL
  standard tap *
  page55_i55
#ISCELL
  standard tap *
  page55_i56
#ISCELL
  standard tap *
  page55_i57
#ISCELL
  standard tap *
  page55_i58
#ISCELL
  standard tap *
  page55_i59
#ISCELL
  standard tap *
  page55_i6
#ISCELL
  standard tap *
  page55_i60
#ISCELL
  standard tap *
  page55_i61
#ISCELL
  standard tap *
  page55_i62
#ISCELL
  standard tap *
  page55_i63
#ISCELL
  standard tap *
  page55_i64
#ISCELL
  standard tap *
  page55_i65
#ISCELL
  standard tap *
  page55_i66
#ISCELL
  standard tap *
  page55_i67
#ISCELL
  standard tap *
  page55_i68
#ISCELL
  standard tap *
  page55_i69
#CELL
  pure_quanta socket4677_azif0045p001c01cs *
  page55_i7
#ISCELL
  standard tap *
  page55_i70
#ISCELL
  standard tap *
  page55_i71
#ISCELL
  standard tap *
  page55_i72
#ISCELL
  standard tap *
  page55_i73
#ISCELL
  standard tap *
  page55_i74
#ISCELL
  standard tap *
  page55_i75
#ISCELL
  standard tap *
  page55_i76
#ISCELL
  standard tap *
  page55_i77
#ISCELL
  standard tap *
  page55_i78
#ISCELL
  standard tap *
  page55_i79
#ISCELL
  standard offpage *
  page55_i8
#ISCELL
  standard tap *
  page55_i80
#ISCELL
  standard tap *
  page55_i81
#ISCELL
  standard tap *
  page55_i82
#ISCELL
  standard tap *
  page55_i83
#ISCELL
  standard tap *
  page55_i84
#ISCELL
  standard tap *
  page55_i85
#ISCELL
  standard tap *
  page55_i86
#ISCELL
  standard tap *
  page55_i87
#ISCELL
  standard tap *
  page55_i88
#ISCELL
  standard tap *
  page55_i89
#ISCELL
  standard offpage *
  page55_i9
#ISCELL
  standard tap *
  page55_i90
#ISCELL
  standard tap *
  page55_i91
#ISCELL
  standard offpage *
  page55_i92
#ISCELL
  standard offpage *
  page55_i93
#ISCELL
  standard offpage *
  page55_i94
#ISCELL
  standard tap *
  page55_i95
#ISCELL
  standard tap *
  page55_i96
#ISCELL
  standard tap *
  page55_i97
#ISCELL
  standard tap *
  page55_i98
#ISCELL
  standard tap *
  page55_i99
#ISCELL
  pure_quanta quanta_title_block_c *
  *
#ISCELL
  standard offpage *
  page56_i1
#ISCELL
  standard offpage *
  page56_i10
#ISCELL
  standard tap *
  page56_i100
#ISCELL
  standard tap *
  page56_i101
#ISCELL
  standard tap *
  page56_i102
#ISCELL
  standard tap *
  page56_i103
#ISCELL
  standard tap *
  page56_i104
#ISCELL
  standard tap *
  page56_i105
#ISCELL
  standard tap *
  page56_i106
#ISCELL
  standard tap *
  page56_i107
#ISCELL
  standard tap *
  page56_i108
#ISCELL
  standard tap *
  page56_i109
#ISCELL
  standard offpage *
  page56_i11
#ISCELL
  standard tap *
  page56_i110
#ISCELL
  standard tap *
  page56_i111
#ISCELL
  standard tap *
  page56_i112
#ISCELL
  standard tap *
  page56_i113
#ISCELL
  standard tap *
  page56_i114
#ISCELL
  standard tap *
  page56_i115
#ISCELL
  standard tap *
  page56_i116
#ISCELL
  standard tap *
  page56_i117
#ISCELL
  standard tap *
  page56_i118
#ISCELL
  standard tap *
  page56_i119
#ISCELL
  standard tap *
  page56_i12
#ISCELL
  standard tap *
  page56_i120
#ISCELL
  standard tap *
  page56_i121
#ISCELL
  standard tap *
  page56_i122
#ISCELL
  standard tap *
  page56_i123
#ISCELL
  standard tap *
  page56_i124
#ISCELL
  standard tap *
  page56_i125
#ISCELL
  standard tap *
  page56_i126
#ISCELL
  standard tap *
  page56_i127
#ISCELL
  standard tap *
  page56_i128
#ISCELL
  standard tap *
  page56_i129
#ISCELL
  standard tap *
  page56_i13
#ISCELL
  standard tap *
  page56_i130
#ISCELL
  standard tap *
  page56_i131
#ISCELL
  standard tap *
  page56_i132
#ISCELL
  standard tap *
  page56_i133
#ISCELL
  standard tap *
  page56_i134
#ISCELL
  standard tap *
  page56_i135
#ISCELL
  standard tap *
  page56_i136
#ISCELL
  standard tap *
  page56_i137
#ISCELL
  standard tap *
  page56_i138
#ISCELL
  standard tap *
  page56_i139
#ISCELL
  standard tap *
  page56_i14
#ISCELL
  standard tap *
  page56_i140
#ISCELL
  standard tap *
  page56_i141
#ISCELL
  standard tap *
  page56_i142
#ISCELL
  standard tap *
  page56_i143
#ISCELL
  standard tap *
  page56_i144
#ISCELL
  standard tap *
  page56_i145
#ISCELL
  standard tap *
  page56_i146
#ISCELL
  standard tap *
  page56_i147
#ISCELL
  standard tap *
  page56_i148
#ISCELL
  standard tap *
  page56_i149
#ISCELL
  standard tap *
  page56_i15
#ISCELL
  standard tap *
  page56_i150
#ISCELL
  standard tap *
  page56_i151
#ISCELL
  standard tap *
  page56_i152
#ISCELL
  standard tap *
  page56_i153
#ISCELL
  standard tap *
  page56_i154
#ISCELL
  standard tap *
  page56_i155
#ISCELL
  standard tap *
  page56_i156
#ISCELL
  standard tap *
  page56_i157
#ISCELL
  standard offpage *
  page56_i158
#ISCELL
  standard offpage *
  page56_i159
#ISCELL
  standard tap *
  page56_i16
#ISCELL
  standard offpage *
  page56_i160
#ISCELL
  standard offpage *
  page56_i161
#ISCELL
  standard offpage *
  page56_i162
#ISCELL
  standard offpage *
  page56_i163
#ISCELL
  standard offpage *
  page56_i164
#ISCELL
  standard offpage *
  page56_i165
#ISCELL
  standard offpage *
  page56_i166
#ISCELL
  standard offpage *
  page56_i167
#CELL
  pure_quanta socket4677_azif0045p001c01cs *
  page56_i168
#ISCELL
  standard tap *
  page56_i17
#ISCELL
  standard tap *
  page56_i18
#ISCELL
  standard tap *
  page56_i19
#ISCELL
  standard offpage *
  page56_i2
#ISCELL
  standard tap *
  page56_i20
#ISCELL
  standard tap *
  page56_i21
#ISCELL
  standard tap *
  page56_i22
#ISCELL
  standard tap *
  page56_i23
#ISCELL
  standard tap *
  page56_i24
#ISCELL
  standard tap *
  page56_i25
#ISCELL
  standard tap *
  page56_i26
#ISCELL
  standard tap *
  page56_i27
#ISCELL
  standard tap *
  page56_i28
#ISCELL
  standard tap *
  page56_i29
#ISCELL
  standard tap *
  page56_i3
#ISCELL
  standard tap *
  page56_i30
#ISCELL
  standard tap *
  page56_i31
#ISCELL
  standard tap *
  page56_i32
#ISCELL
  standard tap *
  page56_i33
#ISCELL
  standard tap *
  page56_i34
#ISCELL
  standard tap *
  page56_i35
#ISCELL
  standard tap *
  page56_i36
#ISCELL
  standard tap *
  page56_i37
#ISCELL
  standard tap *
  page56_i38
#ISCELL
  standard tap *
  page56_i39
#ISCELL
  standard tap *
  page56_i4
#ISCELL
  standard tap *
  page56_i40
#ISCELL
  standard tap *
  page56_i41
#ISCELL
  standard tap *
  page56_i42
#ISCELL
  standard tap *
  page56_i43
#ISCELL
  standard tap *
  page56_i44
#ISCELL
  standard tap *
  page56_i45
#ISCELL
  standard tap *
  page56_i46
#ISCELL
  standard tap *
  page56_i47
#ISCELL
  standard tap *
  page56_i48
#ISCELL
  standard tap *
  page56_i49
#ISCELL
  standard tap *
  page56_i5
#ISCELL
  standard tap *
  page56_i50
#ISCELL
  standard tap *
  page56_i51
#ISCELL
  standard offpage *
  page56_i52
#ISCELL
  standard offpage *
  page56_i53
#ISCELL
  standard tap *
  page56_i54
#ISCELL
  standard tap *
  page56_i55
#ISCELL
  standard tap *
  page56_i56
#ISCELL
  standard tap *
  page56_i57
#ISCELL
  standard tap *
  page56_i58
#ISCELL
  standard tap *
  page56_i59
#ISCELL
  standard tap *
  page56_i6
#ISCELL
  standard tap *
  page56_i60
#ISCELL
  standard tap *
  page56_i61
#ISCELL
  standard tap *
  page56_i62
#ISCELL
  standard tap *
  page56_i63
#ISCELL
  standard tap *
  page56_i64
#ISCELL
  standard tap *
  page56_i65
#ISCELL
  standard tap *
  page56_i66
#ISCELL
  standard tap *
  page56_i67
#ISCELL
  standard tap *
  page56_i68
#ISCELL
  standard tap *
  page56_i69
#ISCELL
  standard tap *
  page56_i7
#ISCELL
  standard tap *
  page56_i70
#ISCELL
  standard tap *
  page56_i71
#ISCELL
  standard tap *
  page56_i72
#ISCELL
  standard tap *
  page56_i73
#ISCELL
  standard tap *
  page56_i74
#ISCELL
  standard tap *
  page56_i75
#ISCELL
  standard tap *
  page56_i76
#ISCELL
  standard tap *
  page56_i77
#ISCELL
  standard tap *
  page56_i78
#ISCELL
  standard tap *
  page56_i79
#ISCELL
  standard tap *
  page56_i8
#ISCELL
  standard tap *
  page56_i80
#ISCELL
  standard tap *
  page56_i81
#ISCELL
  standard tap *
  page56_i82
#ISCELL
  standard tap *
  page56_i83
#ISCELL
  standard tap *
  page56_i84
#ISCELL
  standard tap *
  page56_i85
#ISCELL
  standard tap *
  page56_i86
#ISCELL
  standard tap *
  page56_i87
#ISCELL
  standard tap *
  page56_i88
#ISCELL
  standard tap *
  page56_i89
#ISCELL
  standard tap *
  page56_i9
#ISCELL
  standard tap *
  page56_i90
#ISCELL
  standard offpage *
  page56_i91
#ISCELL
  standard offpage *
  page56_i92
#ISCELL
  standard offpage *
  page56_i93
#ISCELL
  standard offpage *
  page56_i94
#ISCELL
  standard offpage *
  page56_i95
#ISCELL
  standard tap *
  page56_i96
#ISCELL
  standard tap *
  page56_i97
#ISCELL
  standard tap *
  page56_i98
#ISCELL
  standard tap *
  page56_i99
#ISCELL
  pure_quanta quanta_title_block_c *
  *
#ISCELL
  standard offpage *
  page57_i1
#ISCELL
  standard tap *
  page57_i10
#ISCELL
  standard tap *
  page57_i100
#ISCELL
  standard tap *
  page57_i101
#ISCELL
  standard tap *
  page57_i102
#ISCELL
  standard tap *
  page57_i103
#ISCELL
  standard tap *
  page57_i104
#ISCELL
  standard tap *
  page57_i105
#ISCELL
  standard tap *
  page57_i106
#ISCELL
  standard tap *
  page57_i107
#ISCELL
  standard tap *
  page57_i108
#ISCELL
  standard tap *
  page57_i109
#ISCELL
  standard tap *
  page57_i11
#ISCELL
  standard tap *
  page57_i110
#ISCELL
  standard tap *
  page57_i111
#ISCELL
  standard tap *
  page57_i112
#ISCELL
  standard tap *
  page57_i113
#ISCELL
  standard tap *
  page57_i114
#ISCELL
  standard tap *
  page57_i115
#ISCELL
  standard tap *
  page57_i116
#ISCELL
  standard tap *
  page57_i117
#ISCELL
  standard tap *
  page57_i118
#ISCELL
  standard tap *
  page57_i119
#ISCELL
  standard tap *
  page57_i12
#ISCELL
  standard tap *
  page57_i120
#ISCELL
  standard tap *
  page57_i121
#ISCELL
  standard tap *
  page57_i122
#ISCELL
  standard tap *
  page57_i123
#ISCELL
  standard tap *
  page57_i124
#ISCELL
  standard tap *
  page57_i125
#ISCELL
  standard tap *
  page57_i126
#ISCELL
  standard tap *
  page57_i127
#ISCELL
  standard tap *
  page57_i128
#ISCELL
  standard tap *
  page57_i129
#ISCELL
  standard tap *
  page57_i13
#ISCELL
  standard tap *
  page57_i130
#ISCELL
  standard tap *
  page57_i131
#ISCELL
  standard tap *
  page57_i132
#ISCELL
  standard tap *
  page57_i133
#ISCELL
  standard tap *
  page57_i134
#ISCELL
  standard tap *
  page57_i135
#ISCELL
  standard tap *
  page57_i136
#ISCELL
  standard tap *
  page57_i137
#ISCELL
  standard tap *
  page57_i138
#ISCELL
  standard tap *
  page57_i139
#ISCELL
  standard tap *
  page57_i14
#ISCELL
  standard tap *
  page57_i140
#ISCELL
  standard tap *
  page57_i141
#ISCELL
  standard tap *
  page57_i142
#ISCELL
  standard tap *
  page57_i143
#ISCELL
  standard tap *
  page57_i144
#ISCELL
  standard tap *
  page57_i145
#ISCELL
  standard tap *
  page57_i146
#ISCELL
  standard tap *
  page57_i147
#ISCELL
  standard tap *
  page57_i148
#ISCELL
  standard tap *
  page57_i149
#ISCELL
  standard tap *
  page57_i15
#ISCELL
  standard tap *
  page57_i150
#ISCELL
  standard tap *
  page57_i151
#ISCELL
  standard tap *
  page57_i152
#ISCELL
  standard tap *
  page57_i153
#ISCELL
  standard tap *
  page57_i154
#ISCELL
  standard tap *
  page57_i155
#ISCELL
  standard offpage *
  page57_i156
#ISCELL
  standard offpage *
  page57_i157
#ISCELL
  standard offpage *
  page57_i158
#ISCELL
  standard offpage *
  page57_i159
#ISCELL
  standard tap *
  page57_i16
#ISCELL
  standard offpage *
  page57_i160
#ISCELL
  standard offpage *
  page57_i161
#ISCELL
  standard offpage *
  page57_i162
#ISCELL
  standard offpage *
  page57_i163
#ISCELL
  standard offpage *
  page57_i164
#ISCELL
  standard offpage *
  page57_i165
#ISCELL
  standard offpage *
  page57_i166
#ISCELL
  standard offpage *
  page57_i167
#CELL
  pure_quanta socket4677_azif0045p001c01cs *
  page57_i168
#ISCELL
  standard tap *
  page57_i17
#ISCELL
  standard tap *
  page57_i18
#ISCELL
  standard tap *
  page57_i19
#ISCELL
  standard offpage *
  page57_i2
#ISCELL
  standard tap *
  page57_i20
#ISCELL
  standard tap *
  page57_i21
#ISCELL
  standard tap *
  page57_i22
#ISCELL
  standard tap *
  page57_i23
#ISCELL
  standard tap *
  page57_i24
#ISCELL
  standard tap *
  page57_i25
#ISCELL
  standard tap *
  page57_i26
#ISCELL
  standard tap *
  page57_i27
#ISCELL
  standard tap *
  page57_i28
#ISCELL
  standard tap *
  page57_i29
#ISCELL
  standard tap *
  page57_i3
#ISCELL
  standard tap *
  page57_i30
#ISCELL
  standard tap *
  page57_i31
#ISCELL
  standard tap *
  page57_i32
#ISCELL
  standard tap *
  page57_i33
#ISCELL
  standard tap *
  page57_i34
#ISCELL
  standard tap *
  page57_i35
#ISCELL
  standard tap *
  page57_i36
#ISCELL
  standard tap *
  page57_i37
#ISCELL
  standard tap *
  page57_i38
#ISCELL
  standard tap *
  page57_i39
#ISCELL
  standard tap *
  page57_i4
#ISCELL
  standard tap *
  page57_i40
#ISCELL
  standard tap *
  page57_i41
#ISCELL
  standard tap *
  page57_i42
#ISCELL
  standard tap *
  page57_i43
#ISCELL
  standard tap *
  page57_i44
#ISCELL
  standard tap *
  page57_i45
#ISCELL
  standard tap *
  page57_i46
#ISCELL
  standard tap *
  page57_i47
#ISCELL
  standard offpage *
  page57_i48
#ISCELL
  standard offpage *
  page57_i49
#ISCELL
  standard tap *
  page57_i5
#ISCELL
  standard tap *
  page57_i50
#ISCELL
  standard tap *
  page57_i51
#ISCELL
  standard tap *
  page57_i52
#ISCELL
  standard tap *
  page57_i53
#ISCELL
  standard tap *
  page57_i54
#ISCELL
  standard tap *
  page57_i55
#ISCELL
  standard tap *
  page57_i56
#ISCELL
  standard tap *
  page57_i57
#ISCELL
  standard tap *
  page57_i58
#ISCELL
  standard tap *
  page57_i59
#ISCELL
  standard tap *
  page57_i6
#ISCELL
  standard tap *
  page57_i60
#ISCELL
  standard tap *
  page57_i61
#ISCELL
  standard tap *
  page57_i62
#ISCELL
  standard tap *
  page57_i63
#ISCELL
  standard tap *
  page57_i64
#ISCELL
  standard tap *
  page57_i65
#ISCELL
  standard tap *
  page57_i66
#ISCELL
  standard tap *
  page57_i67
#ISCELL
  standard tap *
  page57_i68
#ISCELL
  standard tap *
  page57_i69
#ISCELL
  standard offpage *
  page57_i7
#ISCELL
  standard tap *
  page57_i70
#ISCELL
  standard tap *
  page57_i71
#ISCELL
  standard tap *
  page57_i72
#ISCELL
  standard tap *
  page57_i73
#ISCELL
  standard tap *
  page57_i74
#ISCELL
  standard tap *
  page57_i75
#ISCELL
  standard tap *
  page57_i76
#ISCELL
  standard tap *
  page57_i77
#ISCELL
  standard tap *
  page57_i78
#ISCELL
  standard tap *
  page57_i79
#ISCELL
  standard offpage *
  page57_i8
#ISCELL
  standard tap *
  page57_i80
#ISCELL
  standard tap *
  page57_i81
#ISCELL
  standard tap *
  page57_i82
#ISCELL
  standard tap *
  page57_i83
#ISCELL
  standard tap *
  page57_i84
#ISCELL
  standard tap *
  page57_i85
#ISCELL
  standard tap *
  page57_i86
#ISCELL
  standard tap *
  page57_i87
#ISCELL
  standard tap *
  page57_i88
#ISCELL
  standard tap *
  page57_i89
#ISCELL
  standard tap *
  page57_i9
#ISCELL
  standard tap *
  page57_i90
#ISCELL
  standard offpage *
  page57_i91
#ISCELL
  standard offpage *
  page57_i92
#ISCELL
  standard offpage *
  page57_i93
#ISCELL
  standard tap *
  page57_i94
#ISCELL
  standard tap *
  page57_i95
#ISCELL
  standard tap *
  page57_i96
#ISCELL
  standard tap *
  page57_i97
#ISCELL
  standard tap *
  page57_i98
#ISCELL
  standard tap *
  page57_i99
#ISCELL
  pure_quanta quanta_title_block_c *
  *
#ISCELL
  standard offpage *
  page58_i1
#ISCELL
  standard tap *
  page58_i10
#ISCELL
  standard tap *
  page58_i100
#ISCELL
  standard tap *
  page58_i101
#ISCELL
  standard tap *
  page58_i102
#ISCELL
  standard tap *
  page58_i103
#ISCELL
  standard tap *
  page58_i104
#ISCELL
  standard tap *
  page58_i105
#ISCELL
  standard tap *
  page58_i106
#ISCELL
  standard tap *
  page58_i107
#ISCELL
  standard tap *
  page58_i108
#ISCELL
  standard tap *
  page58_i109
#ISCELL
  standard tap *
  page58_i11
#ISCELL
  standard offpage *
  page58_i110
#ISCELL
  standard offpage *
  page58_i111
#ISCELL
  standard offpage *
  page58_i112
#ISCELL
  standard offpage *
  page58_i113
#ISCELL
  standard offpage *
  page58_i114
#ISCELL
  standard offpage *
  page58_i115
#ISCELL
  standard offpage *
  page58_i116
#ISCELL
  standard offpage *
  page58_i117
#ISCELL
  standard offpage *
  page58_i118
#ISCELL
  standard offpage *
  page58_i119
#ISCELL
  standard tap *
  page58_i12
#ISCELL
  standard tap *
  page58_i120
#ISCELL
  standard tap *
  page58_i121
#ISCELL
  standard tap *
  page58_i122
#ISCELL
  standard tap *
  page58_i123
#ISCELL
  standard tap *
  page58_i124
#ISCELL
  standard tap *
  page58_i125
#ISCELL
  standard tap *
  page58_i126
#ISCELL
  standard tap *
  page58_i127
#ISCELL
  standard tap *
  page58_i128
#ISCELL
  standard tap *
  page58_i129
#ISCELL
  standard tap *
  page58_i13
#ISCELL
  standard tap *
  page58_i130
#ISCELL
  standard tap *
  page58_i131
#ISCELL
  standard tap *
  page58_i132
#ISCELL
  standard tap *
  page58_i133
#ISCELL
  standard tap *
  page58_i134
#ISCELL
  standard tap *
  page58_i135
#ISCELL
  standard tap *
  page58_i136
#ISCELL
  standard tap *
  page58_i137
#ISCELL
  standard tap *
  page58_i138
#ISCELL
  standard tap *
  page58_i139
#ISCELL
  standard tap *
  page58_i14
#ISCELL
  standard tap *
  page58_i140
#ISCELL
  standard tap *
  page58_i141
#ISCELL
  standard tap *
  page58_i142
#ISCELL
  standard tap *
  page58_i143
#ISCELL
  standard tap *
  page58_i144
#ISCELL
  standard tap *
  page58_i145
#ISCELL
  standard tap *
  page58_i146
#ISCELL
  standard tap *
  page58_i147
#ISCELL
  standard tap *
  page58_i148
#ISCELL
  standard tap *
  page58_i149
#ISCELL
  standard tap *
  page58_i15
#ISCELL
  standard tap *
  page58_i150
#ISCELL
  standard tap *
  page58_i151
#ISCELL
  standard tap *
  page58_i152
#ISCELL
  standard tap *
  page58_i153
#ISCELL
  standard tap *
  page58_i154
#ISCELL
  standard offpage *
  page58_i155
#ISCELL
  standard offpage *
  page58_i156
#ISCELL
  standard offpage *
  page58_i157
#ISCELL
  standard offpage *
  page58_i158
#ISCELL
  standard tap *
  page58_i159
#ISCELL
  standard tap *
  page58_i16
#ISCELL
  standard tap *
  page58_i160
#ISCELL
  standard tap *
  page58_i161
#ISCELL
  standard tap *
  page58_i162
#ISCELL
  standard tap *
  page58_i163
#ISCELL
  standard tap *
  page58_i164
#ISCELL
  standard tap *
  page58_i165
#ISCELL
  standard tap *
  page58_i166
#ISCELL
  standard tap *
  page58_i167
#ISCELL
  standard offpage *
  page58_i168
#ISCELL
  standard tap *
  page58_i17
#ISCELL
  standard tap *
  page58_i18
#ISCELL
  standard tap *
  page58_i19
#ISCELL
  standard offpage *
  page58_i2
#CELL
  pure_quanta socket4677_azif0045p001c01cs *
  page58_i20
#ISCELL
  standard tap *
  page58_i21
#ISCELL
  standard tap *
  page58_i22
#ISCELL
  standard tap *
  page58_i23
#ISCELL
  standard tap *
  page58_i24
#ISCELL
  standard tap *
  page58_i25
#ISCELL
  standard tap *
  page58_i26
#ISCELL
  standard tap *
  page58_i27
#ISCELL
  standard tap *
  page58_i28
#ISCELL
  standard tap *
  page58_i29
#ISCELL
  standard offpage *
  page58_i3
#ISCELL
  standard tap *
  page58_i30
#ISCELL
  standard tap *
  page58_i31
#ISCELL
  standard tap *
  page58_i32
#ISCELL
  standard tap *
  page58_i33
#ISCELL
  standard tap *
  page58_i34
#ISCELL
  standard tap *
  page58_i35
#ISCELL
  standard tap *
  page58_i36
#ISCELL
  standard tap *
  page58_i37
#ISCELL
  standard tap *
  page58_i38
#ISCELL
  standard tap *
  page58_i39
#ISCELL
  standard offpage *
  page58_i4
#ISCELL
  standard tap *
  page58_i40
#ISCELL
  standard tap *
  page58_i41
#ISCELL
  standard tap *
  page58_i42
#ISCELL
  standard tap *
  page58_i43
#ISCELL
  standard tap *
  page58_i44
#ISCELL
  standard tap *
  page58_i45
#ISCELL
  standard tap *
  page58_i46
#ISCELL
  standard tap *
  page58_i47
#ISCELL
  standard tap *
  page58_i48
#ISCELL
  standard tap *
  page58_i49
#ISCELL
  standard offpage *
  page58_i5
#ISCELL
  standard tap *
  page58_i50
#ISCELL
  standard tap *
  page58_i51
#ISCELL
  standard tap *
  page58_i52
#ISCELL
  standard tap *
  page58_i53
#ISCELL
  standard tap *
  page58_i54
#ISCELL
  standard tap *
  page58_i55
#ISCELL
  standard tap *
  page58_i56
#ISCELL
  standard tap *
  page58_i57
#ISCELL
  standard tap *
  page58_i58
#ISCELL
  standard tap *
  page58_i59
#ISCELL
  standard tap *
  page58_i6
#ISCELL
  standard tap *
  page58_i60
#ISCELL
  standard tap *
  page58_i61
#ISCELL
  standard tap *
  page58_i62
#ISCELL
  standard tap *
  page58_i63
#ISCELL
  standard tap *
  page58_i64
#ISCELL
  standard tap *
  page58_i65
#ISCELL
  standard tap *
  page58_i66
#ISCELL
  standard tap *
  page58_i67
#ISCELL
  standard tap *
  page58_i68
#ISCELL
  standard tap *
  page58_i69
#ISCELL
  standard tap *
  page58_i7
#ISCELL
  standard tap *
  page58_i70
#ISCELL
  standard tap *
  page58_i71
#ISCELL
  standard tap *
  page58_i72
#ISCELL
  standard tap *
  page58_i73
#ISCELL
  standard tap *
  page58_i74
#ISCELL
  standard tap *
  page58_i75
#ISCELL
  standard tap *
  page58_i76
#ISCELL
  standard tap *
  page58_i77
#ISCELL
  standard tap *
  page58_i78
#ISCELL
  standard tap *
  page58_i79
#ISCELL
  standard tap *
  page58_i8
#ISCELL
  standard tap *
  page58_i80
#ISCELL
  standard tap *
  page58_i81
#ISCELL
  standard offpage *
  page58_i82
#ISCELL
  standard tap *
  page58_i83
#ISCELL
  standard tap *
  page58_i84
#ISCELL
  standard tap *
  page58_i85
#ISCELL
  standard tap *
  page58_i86
#ISCELL
  standard tap *
  page58_i87
#ISCELL
  standard tap *
  page58_i88
#ISCELL
  standard tap *
  page58_i89
#ISCELL
  standard tap *
  page58_i9
#ISCELL
  standard tap *
  page58_i90
#ISCELL
  standard tap *
  page58_i91
#ISCELL
  standard tap *
  page58_i92
#ISCELL
  standard tap *
  page58_i93
#ISCELL
  standard tap *
  page58_i94
#ISCELL
  standard tap *
  page58_i95
#ISCELL
  standard tap *
  page58_i96
#ISCELL
  standard tap *
  page58_i97
#ISCELL
  standard tap *
  page58_i98
#ISCELL
  standard tap *
  page58_i99
#ISCELL
  pure_quanta quanta_title_block_c *
  *
#ISCELL
  standard tap *
  page59_i10
#ISCELL
  standard tap *
  page59_i11
#ISCELL
  standard tap *
  page59_i12
#ISCELL
  standard tap *
  page59_i13
#ISCELL
  standard tap *
  page59_i14
#ISCELL
  standard tap *
  page59_i15
#ISCELL
  standard tap *
  page59_i16
#ISCELL
  standard tap *
  page59_i17
#ISCELL
  standard tap *
  page59_i18
#ISCELL
  standard tap *
  page59_i19
#CELL
  pure_quanta socket4677_azif0045p001c01cs *
  page59_i20
#ISCELL
  standard tap *
  page59_i21
#ISCELL
  standard tap *
  page59_i22
#ISCELL
  standard tap *
  page59_i23
#ISCELL
  standard tap *
  page59_i24
#ISCELL
  standard tap *
  page59_i25
#ISCELL
  standard tap *
  page59_i26
#ISCELL
  standard tap *
  page59_i27
#ISCELL
  standard tap *
  page59_i28
#ISCELL
  standard tap *
  page59_i29
#ISCELL
  standard tap *
  page59_i30
#ISCELL
  standard tap *
  page59_i31
#ISCELL
  standard tap *
  page59_i32
#ISCELL
  standard tap *
  page59_i33
#ISCELL
  standard tap *
  page59_i34
#ISCELL
  standard tap *
  page59_i35
#ISCELL
  standard tap *
  page59_i36
#ISCELL
  standard tap *
  page59_i4
#ISCELL
  standard tap *
  page59_i5
#ISCELL
  standard tap *
  page59_i6
#ISCELL
  standard tap *
  page59_i7
#ISCELL
  standard tap *
  page59_i8
#ISCELL
  standard tap *
  page59_i9
#ISCELL
  pure_quanta quanta_title_block_c *
  *
#ISCELL
  standard tap *
  page60_i304
#ISCELL
  standard tap *
  page60_i305
#ISCELL
  standard tap *
  page60_i306
#ISCELL
  standard tap *
  page60_i307
#ISCELL
  standard tap *
  page60_i308
#ISCELL
  standard tap *
  page60_i309
#ISCELL
  standard tap *
  page60_i310
#ISCELL
  standard tap *
  page60_i311
#ISCELL
  standard tap *
  page60_i312
#ISCELL
  standard tap *
  page60_i313
#ISCELL
  standard tap *
  page60_i314
#ISCELL
  standard tap *
  page60_i315
#ISCELL
  standard tap *
  page60_i316
#ISCELL
  standard tap *
  page60_i317
#ISCELL
  standard tap *
  page60_i318
#ISCELL
  standard tap *
  page60_i319
#ISCELL
  standard offpage *
  page60_i320
#ISCELL
  standard tap *
  page60_i321
#ISCELL
  standard tap *
  page60_i322
#ISCELL
  standard tap *
  page60_i323
#ISCELL
  standard tap *
  page60_i324
#ISCELL
  standard tap *
  page60_i325
#ISCELL
  standard tap *
  page60_i326
#ISCELL
  standard tap *
  page60_i327
#ISCELL
  standard tap *
  page60_i328
#ISCELL
  standard tap *
  page60_i329
#ISCELL
  standard tap *
  page60_i330
#ISCELL
  standard tap *
  page60_i331
#ISCELL
  standard tap *
  page60_i332
#ISCELL
  standard tap *
  page60_i333
#ISCELL
  standard tap *
  page60_i334
#ISCELL
  standard tap *
  page60_i335
#ISCELL
  standard tap *
  page60_i336
#ISCELL
  standard offpage *
  page60_i337
#ISCELL
  standard tap *
  page60_i338
#ISCELL
  standard tap *
  page60_i339
#ISCELL
  standard tap *
  page60_i340
#ISCELL
  standard tap *
  page60_i341
#ISCELL
  standard tap *
  page60_i342
#ISCELL
  standard tap *
  page60_i343
#ISCELL
  standard tap *
  page60_i344
#ISCELL
  standard tap *
  page60_i345
#ISCELL
  standard tap *
  page60_i346
#ISCELL
  standard tap *
  page60_i347
#ISCELL
  standard tap *
  page60_i348
#ISCELL
  standard tap *
  page60_i349
#ISCELL
  standard tap *
  page60_i350
#ISCELL
  standard tap *
  page60_i351
#ISCELL
  standard tap *
  page60_i352
#ISCELL
  standard tap *
  page60_i353
#ISCELL
  standard tap *
  page60_i354
#ISCELL
  standard tap *
  page60_i355
#ISCELL
  standard tap *
  page60_i356
#ISCELL
  standard tap *
  page60_i357
#ISCELL
  standard tap *
  page60_i358
#ISCELL
  standard tap *
  page60_i359
#ISCELL
  standard tap *
  page60_i360
#ISCELL
  standard tap *
  page60_i361
#ISCELL
  standard tap *
  page60_i362
#ISCELL
  standard tap *
  page60_i363
#ISCELL
  standard tap *
  page60_i364
#ISCELL
  standard tap *
  page60_i365
#ISCELL
  standard tap *
  page60_i366
#ISCELL
  standard tap *
  page60_i367
#ISCELL
  standard tap *
  page60_i368
#ISCELL
  standard tap *
  page60_i369
#ISCELL
  standard offpage *
  page60_i370
#ISCELL
  standard offpage *
  page60_i371
#ISCELL
  standard tap *
  page60_i440
#ISCELL
  standard tap *
  page60_i441
#ISCELL
  standard tap *
  page60_i442
#ISCELL
  standard tap *
  page60_i443
#ISCELL
  standard tap *
  page60_i444
#ISCELL
  standard tap *
  page60_i445
#ISCELL
  standard tap *
  page60_i446
#ISCELL
  standard tap *
  page60_i447
#ISCELL
  standard tap *
  page60_i448
#ISCELL
  standard tap *
  page60_i449
#ISCELL
  standard tap *
  page60_i450
#ISCELL
  standard tap *
  page60_i451
#ISCELL
  standard tap *
  page60_i452
#ISCELL
  standard tap *
  page60_i453
#ISCELL
  standard tap *
  page60_i454
#ISCELL
  standard tap *
  page60_i455
#ISCELL
  standard tap *
  page60_i456
#ISCELL
  standard tap *
  page60_i457
#ISCELL
  standard tap *
  page60_i458
#ISCELL
  standard tap *
  page60_i459
#ISCELL
  standard tap *
  page60_i460
#ISCELL
  standard tap *
  page60_i461
#ISCELL
  standard tap *
  page60_i462
#ISCELL
  standard tap *
  page60_i463
#ISCELL
  standard tap *
  page60_i464
#ISCELL
  standard tap *
  page60_i465
#ISCELL
  standard tap *
  page60_i466
#ISCELL
  standard tap *
  page60_i467
#ISCELL
  standard tap *
  page60_i468
#ISCELL
  standard tap *
  page60_i469
#ISCELL
  standard offpage *
  page60_i470
#ISCELL
  standard offpage *
  page60_i471
#ISCELL
  standard tap *
  page60_i472
#ISCELL
  standard tap *
  page60_i473
#ISCELL
  standard offpage *
  page60_i474
#ISCELL
  standard offpage *
  page60_i475
#ISCELL
  standard tap *
  page60_i476
#ISCELL
  standard tap *
  page60_i477
#ISCELL
  standard tap *
  page60_i478
#ISCELL
  standard tap *
  page60_i479
#ISCELL
  standard tap *
  page60_i480
#ISCELL
  standard tap *
  page60_i481
#ISCELL
  standard tap *
  page60_i482
#ISCELL
  standard tap *
  page60_i483
#ISCELL
  standard tap *
  page60_i484
#ISCELL
  standard tap *
  page60_i485
#ISCELL
  standard tap *
  page60_i486
#ISCELL
  standard tap *
  page60_i487
#ISCELL
  standard tap *
  page60_i488
#ISCELL
  standard tap *
  page60_i489
#ISCELL
  standard tap *
  page60_i490
#ISCELL
  standard tap *
  page60_i491
#ISCELL
  standard tap *
  page60_i492
#ISCELL
  standard tap *
  page60_i493
#ISCELL
  standard tap *
  page60_i494
#ISCELL
  standard tap *
  page60_i495
#ISCELL
  standard tap *
  page60_i496
#ISCELL
  standard tap *
  page60_i497
#ISCELL
  standard tap *
  page60_i498
#ISCELL
  standard tap *
  page60_i499
#ISCELL
  standard tap *
  page60_i500
#ISCELL
  standard tap *
  page60_i501
#ISCELL
  standard tap *
  page60_i502
#ISCELL
  standard tap *
  page60_i503
#ISCELL
  standard tap *
  page60_i504
#ISCELL
  standard tap *
  page60_i505
#ISCELL
  standard tap *
  page60_i506
#ISCELL
  standard tap *
  page60_i507
#CELL
  pure_quanta socket4677_azif0045p001c01cs *
  page60_i69
#CELL
  pure_quanta socket4677_azif0045p001c01cs *
  page60_i80
#ISCELL
  pure_quanta quanta_title_block_c *
  *
#ISCELL
  standard tap *
  page61_i1
#ISCELL
  standard tap *
  page61_i10
#ISCELL
  standard tap *
  page61_i100
#ISCELL
  standard tap *
  page61_i101
#ISCELL
  standard tap *
  page61_i102
#ISCELL
  standard offpage *
  page61_i103
#ISCELL
  standard offpage *
  page61_i104
#ISCELL
  standard tap *
  page61_i11
#CELL
  pure_quanta socket4677_azif0045p001c01cs *
  page61_i12
#ISCELL
  standard tap *
  page61_i13
#ISCELL
  standard offpage *
  page61_i14
#ISCELL
  standard offpage *
  page61_i15
#ISCELL
  standard tap *
  page61_i16
#ISCELL
  standard tap *
  page61_i17
#ISCELL
  standard tap *
  page61_i18
#ISCELL
  standard tap *
  page61_i19
#ISCELL
  standard tap *
  page61_i2
#ISCELL
  standard tap *
  page61_i20
#ISCELL
  standard tap *
  page61_i21
#ISCELL
  standard tap *
  page61_i22
#ISCELL
  standard offpage *
  page61_i223
#ISCELL
  standard offpage *
  page61_i224
#ISCELL
  standard tap *
  page61_i225
#ISCELL
  standard tap *
  page61_i226
#ISCELL
  standard tap *
  page61_i227
#ISCELL
  standard tap *
  page61_i228
#ISCELL
  standard tap *
  page61_i229
#ISCELL
  standard tap *
  page61_i23
#ISCELL
  standard tap *
  page61_i230
#ISCELL
  standard tap *
  page61_i231
#ISCELL
  standard tap *
  page61_i232
#ISCELL
  standard tap *
  page61_i233
#ISCELL
  standard tap *
  page61_i234
#ISCELL
  standard tap *
  page61_i235
#ISCELL
  standard tap *
  page61_i236
#ISCELL
  standard tap *
  page61_i237
#ISCELL
  standard tap *
  page61_i238
#ISCELL
  standard tap *
  page61_i239
#ISCELL
  standard tap *
  page61_i24
#ISCELL
  standard tap *
  page61_i240
#ISCELL
  standard tap *
  page61_i241
#ISCELL
  standard tap *
  page61_i242
#ISCELL
  standard tap *
  page61_i243
#ISCELL
  standard tap *
  page61_i244
#ISCELL
  standard tap *
  page61_i245
#ISCELL
  standard tap *
  page61_i246
#ISCELL
  standard tap *
  page61_i247
#ISCELL
  standard tap *
  page61_i248
#ISCELL
  standard tap *
  page61_i249
#ISCELL
  standard tap *
  page61_i25
#ISCELL
  standard tap *
  page61_i250
#ISCELL
  standard tap *
  page61_i251
#ISCELL
  standard tap *
  page61_i252
#ISCELL
  standard tap *
  page61_i253
#ISCELL
  standard tap *
  page61_i254
#ISCELL
  standard tap *
  page61_i255
#ISCELL
  standard tap *
  page61_i256
#ISCELL
  standard tap *
  page61_i257
#ISCELL
  standard tap *
  page61_i258
#ISCELL
  standard tap *
  page61_i259
#ISCELL
  standard tap *
  page61_i26
#ISCELL
  standard tap *
  page61_i260
#ISCELL
  standard tap *
  page61_i261
#ISCELL
  standard tap *
  page61_i262
#ISCELL
  standard tap *
  page61_i263
#ISCELL
  standard tap *
  page61_i264
#ISCELL
  standard tap *
  page61_i265
#ISCELL
  standard tap *
  page61_i266
#ISCELL
  standard tap *
  page61_i267
#ISCELL
  standard tap *
  page61_i268
#ISCELL
  standard tap *
  page61_i269
#ISCELL
  standard tap *
  page61_i27
#ISCELL
  standard tap *
  page61_i270
#ISCELL
  standard tap *
  page61_i271
#ISCELL
  standard tap *
  page61_i272
#ISCELL
  standard tap *
  page61_i273
#ISCELL
  standard tap *
  page61_i274
#ISCELL
  standard tap *
  page61_i275
#ISCELL
  standard tap *
  page61_i276
#ISCELL
  standard tap *
  page61_i277
#ISCELL
  standard tap *
  page61_i278
#ISCELL
  standard tap *
  page61_i279
#ISCELL
  standard tap *
  page61_i28
#ISCELL
  standard tap *
  page61_i280
#ISCELL
  standard tap *
  page61_i281
#ISCELL
  standard tap *
  page61_i282
#ISCELL
  standard tap *
  page61_i283
#ISCELL
  standard tap *
  page61_i284
#ISCELL
  standard tap *
  page61_i285
#ISCELL
  standard tap *
  page61_i286
#ISCELL
  standard tap *
  page61_i287
#ISCELL
  standard offpage *
  page61_i288
#ISCELL
  standard offpage *
  page61_i289
#ISCELL
  standard tap *
  page61_i29
#ISCELL
  standard tap *
  page61_i290
#ISCELL
  standard tap *
  page61_i3
#ISCELL
  standard tap *
  page61_i30
#ISCELL
  standard tap *
  page61_i31
#ISCELL
  standard tap *
  page61_i32
#ISCELL
  standard tap *
  page61_i33
#ISCELL
  standard tap *
  page61_i34
#ISCELL
  standard tap *
  page61_i35
#ISCELL
  standard tap *
  page61_i4
#ISCELL
  standard tap *
  page61_i5
#CELL
  pure_quanta socket4677_azif0045p001c01cs *
  page61_i54
#ISCELL
  standard tap *
  page61_i6
#ISCELL
  standard tap *
  page61_i7
#ISCELL
  standard tap *
  page61_i71
#ISCELL
  standard tap *
  page61_i72
#ISCELL
  standard tap *
  page61_i73
#ISCELL
  standard tap *
  page61_i74
#ISCELL
  standard tap *
  page61_i75
#ISCELL
  standard tap *
  page61_i76
#ISCELL
  standard tap *
  page61_i77
#ISCELL
  standard tap *
  page61_i78
#ISCELL
  standard tap *
  page61_i79
#ISCELL
  standard tap *
  page61_i8
#ISCELL
  standard tap *
  page61_i80
#ISCELL
  standard tap *
  page61_i81
#ISCELL
  standard tap *
  page61_i82
#ISCELL
  standard tap *
  page61_i83
#ISCELL
  standard tap *
  page61_i84
#ISCELL
  standard tap *
  page61_i85
#ISCELL
  standard tap *
  page61_i86
#ISCELL
  standard tap *
  page61_i87
#ISCELL
  standard tap *
  page61_i88
#ISCELL
  standard tap *
  page61_i89
#ISCELL
  standard tap *
  page61_i9
#ISCELL
  standard tap *
  page61_i90
#ISCELL
  standard tap *
  page61_i91
#ISCELL
  standard tap *
  page61_i92
#ISCELL
  standard tap *
  page61_i93
#ISCELL
  standard tap *
  page61_i94
#ISCELL
  standard tap *
  page61_i95
#ISCELL
  standard tap *
  page61_i96
#ISCELL
  standard tap *
  page61_i97
#ISCELL
  standard tap *
  page61_i98
#ISCELL
  standard tap *
  page61_i99
#ISCELL
  pure_quanta quanta_title_block_c *
  *
#ISCELL
  standard tap *
  page62_i100
#ISCELL
  standard tap *
  page62_i101
#ISCELL
  standard tap *
  page62_i102
#ISCELL
  standard tap *
  page62_i103
#ISCELL
  standard tap *
  page62_i104
#ISCELL
  standard tap *
  page62_i105
#ISCELL
  standard tap *
  page62_i106
#ISCELL
  standard tap *
  page62_i107
#ISCELL
  standard tap *
  page62_i108
#ISCELL
  standard tap *
  page62_i109
#ISCELL
  standard tap *
  page62_i110
#ISCELL
  standard tap *
  page62_i111
#ISCELL
  standard tap *
  page62_i112
#ISCELL
  standard tap *
  page62_i113
#ISCELL
  standard tap *
  page62_i114
#ISCELL
  standard tap *
  page62_i115
#ISCELL
  standard tap *
  page62_i116
#ISCELL
  standard tap *
  page62_i117
#ISCELL
  standard tap *
  page62_i118
#ISCELL
  standard tap *
  page62_i119
#ISCELL
  standard tap *
  page62_i120
#ISCELL
  standard tap *
  page62_i121
#ISCELL
  standard tap *
  page62_i122
#ISCELL
  standard tap *
  page62_i123
#ISCELL
  standard tap *
  page62_i124
#ISCELL
  standard tap *
  page62_i125
#ISCELL
  standard tap *
  page62_i126
#ISCELL
  standard tap *
  page62_i127
#ISCELL
  standard tap *
  page62_i128
#ISCELL
  standard tap *
  page62_i129
#ISCELL
  standard tap *
  page62_i130
#ISCELL
  standard tap *
  page62_i131
#ISCELL
  standard tap *
  page62_i132
#ISCELL
  standard tap *
  page62_i133
#ISCELL
  standard tap *
  page62_i134
#ISCELL
  standard tap *
  page62_i135
#ISCELL
  standard tap *
  page62_i136
#ISCELL
  standard tap *
  page62_i137
#ISCELL
  standard tap *
  page62_i138
#ISCELL
  standard tap *
  page62_i139
#ISCELL
  standard tap *
  page62_i140
#ISCELL
  standard tap *
  page62_i141
#ISCELL
  standard tap *
  page62_i142
#ISCELL
  standard tap *
  page62_i143
#ISCELL
  standard tap *
  page62_i144
#ISCELL
  standard tap *
  page62_i145
#ISCELL
  standard tap *
  page62_i146
#ISCELL
  standard tap *
  page62_i147
#ISCELL
  standard tap *
  page62_i148
#ISCELL
  standard tap *
  page62_i149
#ISCELL
  standard tap *
  page62_i150
#ISCELL
  standard tap *
  page62_i151
#ISCELL
  standard tap *
  page62_i152
#ISCELL
  standard tap *
  page62_i153
#ISCELL
  standard tap *
  page62_i154
#ISCELL
  standard tap *
  page62_i155
#ISCELL
  standard tap *
  page62_i156
#ISCELL
  standard tap *
  page62_i157
#ISCELL
  standard tap *
  page62_i158
#ISCELL
  standard tap *
  page62_i159
#ISCELL
  standard tap *
  page62_i160
#ISCELL
  standard tap *
  page62_i161
#ISCELL
  standard offpage *
  page62_i162
#ISCELL
  standard offpage *
  page62_i163
#CELL
  pure_quanta socket4677_azif0045p001c01cs *
  page62_i18
#ISCELL
  standard offpage *
  page62_i96
#ISCELL
  standard offpage *
  page62_i97
#ISCELL
  standard tap *
  page62_i98
#ISCELL
  standard tap *
  page62_i99
#ISCELL
  pure_quanta quanta_title_block_c *
  *
#ISCELL
  standard tap *
  page63_i1
#ISCELL
  standard tap *
  page63_i10
#ISCELL
  standard offpage *
  page63_i100
#ISCELL
  standard offpage *
  page63_i101
#ISCELL
  standard tap *
  page63_i11
#ISCELL
  standard tap *
  page63_i12
#ISCELL
  standard tap *
  page63_i13
#ISCELL
  standard tap *
  page63_i14
#ISCELL
  standard tap *
  page63_i15
#ISCELL
  standard tap *
  page63_i16
#ISCELL
  standard offpage *
  page63_i17
#ISCELL
  standard offpage *
  page63_i18
#ISCELL
  standard tap *
  page63_i19
#ISCELL
  standard tap *
  page63_i2
#ISCELL
  standard tap *
  page63_i20
#ISCELL
  standard tap *
  page63_i21
#ISCELL
  standard tap *
  page63_i22
#ISCELL
  standard tap *
  page63_i23
#ISCELL
  standard tap *
  page63_i24
#ISCELL
  standard tap *
  page63_i25
#ISCELL
  standard tap *
  page63_i26
#ISCELL
  standard tap *
  page63_i27
#ISCELL
  standard tap *
  page63_i28
#ISCELL
  standard tap *
  page63_i29
#ISCELL
  standard tap *
  page63_i3
#ISCELL
  standard tap *
  page63_i30
#ISCELL
  standard tap *
  page63_i31
#ISCELL
  standard tap *
  page63_i32
#ISCELL
  standard tap *
  page63_i33
#ISCELL
  standard tap *
  page63_i34
#ISCELL
  standard tap *
  page63_i35
#ISCELL
  standard tap *
  page63_i36
#ISCELL
  standard tap *
  page63_i37
#ISCELL
  standard tap *
  page63_i38
#ISCELL
  standard tap *
  page63_i39
#ISCELL
  standard tap *
  page63_i4
#ISCELL
  standard tap *
  page63_i40
#ISCELL
  standard tap *
  page63_i41
#ISCELL
  standard tap *
  page63_i42
#ISCELL
  standard tap *
  page63_i43
#ISCELL
  standard tap *
  page63_i44
#ISCELL
  standard tap *
  page63_i45
#ISCELL
  standard tap *
  page63_i46
#ISCELL
  standard tap *
  page63_i47
#ISCELL
  standard tap *
  page63_i48
#ISCELL
  standard tap *
  page63_i49
#ISCELL
  standard tap *
  page63_i5
#ISCELL
  standard tap *
  page63_i50
#CELL
  pure_quanta socket4677_azif0045p001c01cs *
  page63_i51
#ISCELL
  standard tap *
  page63_i52
#ISCELL
  standard tap *
  page63_i53
#ISCELL
  standard tap *
  page63_i54
#ISCELL
  standard tap *
  page63_i55
#ISCELL
  standard tap *
  page63_i56
#ISCELL
  standard tap *
  page63_i57
#ISCELL
  standard tap *
  page63_i58
#ISCELL
  standard tap *
  page63_i59
#ISCELL
  standard tap *
  page63_i6
#ISCELL
  standard tap *
  page63_i60
#ISCELL
  standard tap *
  page63_i61
#ISCELL
  standard tap *
  page63_i62
#ISCELL
  standard tap *
  page63_i63
#ISCELL
  standard tap *
  page63_i64
#ISCELL
  standard tap *
  page63_i65
#ISCELL
  standard tap *
  page63_i66
#ISCELL
  standard tap *
  page63_i67
#ISCELL
  standard tap *
  page63_i68
#ISCELL
  standard tap *
  page63_i69
#ISCELL
  standard tap *
  page63_i7
#ISCELL
  standard tap *
  page63_i70
#ISCELL
  standard tap *
  page63_i71
#ISCELL
  standard tap *
  page63_i72
#ISCELL
  standard tap *
  page63_i73
#ISCELL
  standard tap *
  page63_i74
#ISCELL
  standard tap *
  page63_i75
#ISCELL
  standard tap *
  page63_i76
#ISCELL
  standard tap *
  page63_i77
#ISCELL
  standard tap *
  page63_i78
#ISCELL
  standard tap *
  page63_i79
#ISCELL
  standard tap *
  page63_i8
#ISCELL
  standard tap *
  page63_i80
#ISCELL
  standard tap *
  page63_i81
#ISCELL
  standard tap *
  page63_i82
#ISCELL
  standard tap *
  page63_i83
#ISCELL
  standard tap *
  page63_i84
#ISCELL
  standard tap *
  page63_i85
#ISCELL
  standard tap *
  page63_i86
#ISCELL
  standard tap *
  page63_i87
#ISCELL
  standard tap *
  page63_i88
#ISCELL
  standard tap *
  page63_i89
#ISCELL
  standard tap *
  page63_i9
#ISCELL
  standard tap *
  page63_i90
#ISCELL
  standard tap *
  page63_i91
#ISCELL
  standard tap *
  page63_i92
#ISCELL
  standard tap *
  page63_i93
#ISCELL
  standard tap *
  page63_i94
#ISCELL
  standard tap *
  page63_i95
#ISCELL
  standard tap *
  page63_i96
#ISCELL
  standard tap *
  page63_i97
#ISCELL
  standard tap *
  page63_i98
#ISCELL
  standard tap *
  page63_i99
#ISCELL
  pure_quanta quanta_title_block_c *
  *
#ISCELL
  standard offpage *
  page64_i1
#ISCELL
  standard offpage *
  page64_i100
#ISCELL
  standard offpage *
  page64_i101
#ISCELL
  standard tap *
  page64_i102
#ISCELL
  standard tap *
  page64_i103
#ISCELL
  standard tap *
  page64_i104
#ISCELL
  standard tap *
  page64_i105
#ISCELL
  standard tap *
  page64_i106
#ISCELL
  standard tap *
  page64_i107
#ISCELL
  standard tap *
  page64_i108
#ISCELL
  standard tap *
  page64_i109
#ISCELL
  standard tap *
  page64_i110
#ISCELL
  standard tap *
  page64_i111
#ISCELL
  standard tap *
  page64_i112
#ISCELL
  standard tap *
  page64_i113
#ISCELL
  standard tap *
  page64_i114
#ISCELL
  standard tap *
  page64_i115
#ISCELL
  standard tap *
  page64_i116
#ISCELL
  standard tap *
  page64_i117
#ISCELL
  standard tap *
  page64_i118
#ISCELL
  standard tap *
  page64_i119
#ISCELL
  standard tap *
  page64_i120
#ISCELL
  standard tap *
  page64_i121
#ISCELL
  standard tap *
  page64_i122
#ISCELL
  standard tap *
  page64_i123
#ISCELL
  standard tap *
  page64_i124
#ISCELL
  standard tap *
  page64_i125
#ISCELL
  standard offpage *
  page64_i126
#ISCELL
  standard tap *
  page64_i15
#ISCELL
  standard tap *
  page64_i16
#ISCELL
  standard tap *
  page64_i19
#CELL
  pure_quanta socket4677_azif0045p001c01cs *
  page64_i21
#ISCELL
  standard tap *
  page64_i23
#ISCELL
  standard tap *
  page64_i25
#ISCELL
  standard tap *
  page64_i26
#ISCELL
  standard tap *
  page64_i28
#ISCELL
  standard tap *
  page64_i29
#ISCELL
  standard tap *
  page64_i30
#ISCELL
  standard tap *
  page64_i31
#ISCELL
  standard tap *
  page64_i32
#ISCELL
  standard tap *
  page64_i33
#ISCELL
  standard tap *
  page64_i34
#ISCELL
  standard tap *
  page64_i35
#ISCELL
  standard tap *
  page64_i36
#ISCELL
  standard tap *
  page64_i37
#ISCELL
  standard tap *
  page64_i38
#ISCELL
  standard tap *
  page64_i39
#ISCELL
  standard tap *
  page64_i41
#ISCELL
  standard tap *
  page64_i44
#ISCELL
  standard tap *
  page64_i45
#ISCELL
  standard tap *
  page64_i46
#ISCELL
  standard tap *
  page64_i47
#ISCELL
  standard tap *
  page64_i51
#ISCELL
  standard tap *
  page64_i52
#ISCELL
  standard tap *
  page64_i53
#ISCELL
  standard tap *
  page64_i54
#ISCELL
  standard tap *
  page64_i55
#ISCELL
  standard tap *
  page64_i56
#ISCELL
  standard tap *
  page64_i57
#ISCELL
  standard tap *
  page64_i58
#ISCELL
  standard tap *
  page64_i59
#ISCELL
  standard tap *
  page64_i60
#ISCELL
  standard tap *
  page64_i61
#ISCELL
  standard tap *
  page64_i62
#ISCELL
  standard tap *
  page64_i63
#ISCELL
  standard tap *
  page64_i64
#ISCELL
  standard tap *
  page64_i65
#ISCELL
  standard tap *
  page64_i66
#ISCELL
  standard tap *
  page64_i67
#ISCELL
  standard tap *
  page64_i68
#ISCELL
  standard tap *
  page64_i69
#ISCELL
  standard tap *
  page64_i70
#ISCELL
  standard tap *
  page64_i71
#ISCELL
  standard tap *
  page64_i72
#ISCELL
  standard tap *
  page64_i73
#ISCELL
  standard tap *
  page64_i74
#ISCELL
  standard tap *
  page64_i75
#ISCELL
  standard tap *
  page64_i76
#ISCELL
  standard tap *
  page64_i77
#ISCELL
  standard tap *
  page64_i78
#ISCELL
  standard tap *
  page64_i79
#ISCELL
  standard tap *
  page64_i80
#ISCELL
  standard tap *
  page64_i81
#ISCELL
  standard tap *
  page64_i82
#ISCELL
  standard tap *
  page64_i83
#ISCELL
  standard tap *
  page64_i84
#ISCELL
  standard tap *
  page64_i85
#ISCELL
  standard tap *
  page64_i86
#ISCELL
  standard tap *
  page64_i87
#ISCELL
  standard tap *
  page64_i88
#ISCELL
  standard tap *
  page64_i89
#ISCELL
  standard tap *
  page64_i90
#ISCELL
  standard tap *
  page64_i91
#ISCELL
  standard tap *
  page64_i92
#ISCELL
  standard tap *
  page64_i93
#ISCELL
  standard tap *
  page64_i94
#ISCELL
  standard tap *
  page64_i95
#ISCELL
  standard tap *
  page64_i96
#ISCELL
  standard tap *
  page64_i97
#ISCELL
  standard tap *
  page64_i98
#ISCELL
  standard tap *
  page64_i99
#ISCELL
  pure_quanta quanta_title_block_c *
  *
#ISCELL
  standard offpage *
  page65_i1
#ISCELL
  standard tap *
  page65_i10
#ISCELL
  standard offpage *
  page65_i100
#ISCELL
  standard offpage *
  page65_i101
#ISCELL
  standard tap *
  page65_i11
#ISCELL
  standard tap *
  page65_i12
#ISCELL
  standard tap *
  page65_i13
#ISCELL
  standard tap *
  page65_i14
#ISCELL
  standard tap *
  page65_i15
#CELL
  pure_quanta socket4677_azif0045p001c01cs *
  page65_i16
#ISCELL
  standard tap *
  page65_i17
#ISCELL
  standard tap *
  page65_i18
#ISCELL
  standard tap *
  page65_i19
#ISCELL
  standard offpage *
  page65_i2
#ISCELL
  standard tap *
  page65_i20
#ISCELL
  standard tap *
  page65_i21
#ISCELL
  standard tap *
  page65_i22
#ISCELL
  standard tap *
  page65_i23
#ISCELL
  standard tap *
  page65_i24
#ISCELL
  standard tap *
  page65_i25
#ISCELL
  standard tap *
  page65_i26
#ISCELL
  standard tap *
  page65_i27
#ISCELL
  standard tap *
  page65_i28
#ISCELL
  standard tap *
  page65_i29
#ISCELL
  standard tap *
  page65_i3
#ISCELL
  standard tap *
  page65_i30
#ISCELL
  standard tap *
  page65_i31
#ISCELL
  standard tap *
  page65_i32
#ISCELL
  standard tap *
  page65_i33
#ISCELL
  standard tap *
  page65_i34
#ISCELL
  standard tap *
  page65_i35
#ISCELL
  standard tap *
  page65_i36
#ISCELL
  standard tap *
  page65_i37
#ISCELL
  standard tap *
  page65_i38
#ISCELL
  standard tap *
  page65_i39
#ISCELL
  standard tap *
  page65_i4
#ISCELL
  standard tap *
  page65_i40
#ISCELL
  standard tap *
  page65_i41
#ISCELL
  standard tap *
  page65_i42
#ISCELL
  standard tap *
  page65_i43
#ISCELL
  standard tap *
  page65_i44
#ISCELL
  standard tap *
  page65_i45
#ISCELL
  standard tap *
  page65_i46
#ISCELL
  standard tap *
  page65_i47
#ISCELL
  standard tap *
  page65_i48
#ISCELL
  standard tap *
  page65_i49
#ISCELL
  standard tap *
  page65_i5
#ISCELL
  standard tap *
  page65_i50
#ISCELL
  standard tap *
  page65_i51
#ISCELL
  standard tap *
  page65_i52
#ISCELL
  standard tap *
  page65_i53
#ISCELL
  standard tap *
  page65_i54
#ISCELL
  standard tap *
  page65_i55
#ISCELL
  standard tap *
  page65_i56
#ISCELL
  standard tap *
  page65_i57
#ISCELL
  standard tap *
  page65_i58
#ISCELL
  standard tap *
  page65_i59
#ISCELL
  standard tap *
  page65_i6
#ISCELL
  standard tap *
  page65_i60
#ISCELL
  standard tap *
  page65_i61
#ISCELL
  standard tap *
  page65_i62
#ISCELL
  standard tap *
  page65_i63
#ISCELL
  standard tap *
  page65_i64
#ISCELL
  standard tap *
  page65_i65
#ISCELL
  standard tap *
  page65_i66
#ISCELL
  standard tap *
  page65_i67
#ISCELL
  standard tap *
  page65_i68
#ISCELL
  standard tap *
  page65_i69
#ISCELL
  standard tap *
  page65_i7
#ISCELL
  standard tap *
  page65_i70
#ISCELL
  standard tap *
  page65_i71
#ISCELL
  standard tap *
  page65_i72
#ISCELL
  standard tap *
  page65_i73
#ISCELL
  standard tap *
  page65_i74
#ISCELL
  standard tap *
  page65_i75
#ISCELL
  standard tap *
  page65_i76
#ISCELL
  standard tap *
  page65_i77
#ISCELL
  standard tap *
  page65_i78
#ISCELL
  standard tap *
  page65_i79
#ISCELL
  standard tap *
  page65_i8
#ISCELL
  standard tap *
  page65_i80
#ISCELL
  standard tap *
  page65_i81
#ISCELL
  standard tap *
  page65_i82
#ISCELL
  standard tap *
  page65_i83
#ISCELL
  standard tap *
  page65_i84
#ISCELL
  standard tap *
  page65_i85
#ISCELL
  standard tap *
  page65_i86
#ISCELL
  standard tap *
  page65_i87
#ISCELL
  standard tap *
  page65_i88
#ISCELL
  standard tap *
  page65_i89
#ISCELL
  standard tap *
  page65_i9
#ISCELL
  standard tap *
  page65_i90
#ISCELL
  standard tap *
  page65_i91
#ISCELL
  standard tap *
  page65_i92
#ISCELL
  standard tap *
  page65_i93
#ISCELL
  standard tap *
  page65_i94
#ISCELL
  standard tap *
  page65_i95
#ISCELL
  standard tap *
  page65_i96
#ISCELL
  standard tap *
  page65_i97
#ISCELL
  standard tap *
  page65_i98
#ISCELL
  standard tap *
  page65_i99
#ISCELL
  pure_quanta quanta_title_block_c *
  *
#CELL
  pure_quanta socket4677_azif0045p001c01cs *
  page66_i16
#ISCELL
  logical_power universal_gnd *
  page66_i17
#ISCELL
  pure_quanta quanta_title_block_c *
  *
#CELL
  pure_quanta socket4677_azif0045p001c01cs *
  page67_i1
#ISCELL
  logical_power vcc_core *
  page67_i2
#CELL
  pure_quanta socket4677_azif0045p001c01cs *
  page67_i3
#ISCELL
  logical_power vcc_core *
  page67_i4
#ISCELL
  logical_power vcc_core *
  page67_i5
#ISCELL
  logical_power vcc_core *
  page67_i6
#ISCELL
  pure_quanta quanta_title_block_c *
  *
#CELL
  pure_quanta socket4677_azif0045p001c01cs *
  page68_i1
#ISCELL
  logical_power vcc_core *
  page68_i10
#ISCELL
  logical_power vcc_core *
  page68_i11
#ISCELL
  logical_power vcc_core *
  page68_i12
#ISCELL
  logical_power vcc_core *
  page68_i13
#ISCELL
  logical_power vcc_core *
  page68_i2
#ISCELL
  logical_power vcc_core *
  page68_i3
#CELL
  pure_quanta q_cap *
  page68_i4
#ISCELL
  logical_power universal_gnd *
  page68_i5
#ISCELL
  logical_power vcc_core *
  page68_i6
#ISCELL
  logical_power vcc_core *
  page68_i7
#CELL
  pure_quanta socket4677_azif0045p001c01cs *
  page68_i8
#ISCELL
  logical_power vcc_core *
  page68_i9
#ISCELL
  pure_quanta quanta_title_block_c *
  *
#CELL
  pure_quanta socket4677_azif0045p001c01cs *
  page69_i1
#ISCELL
  logical_power vcc_core *
  page69_i2
#ISCELL
  logical_power vcc_core *
  page69_i3
#ISCELL
  pure_quanta quanta_title_block_c *
  *
#ISCELL
  logical_power universal_gnd *
  page70_i1
#CELL
  pure_quanta socket4677_azif0045p001c01cs *
  page70_i2
#ISCELL
  logical_power universal_gnd *
  page70_i3
#ISCELL
  logical_power universal_gnd *
  page70_i4
#CELL
  pure_quanta socket4677_azif0045p001c01cs *
  page70_i5
#ISCELL
  logical_power universal_gnd *
  page70_i6
#ISCELL
  logical_power universal_gnd *
  page70_i7
#CELL
  pure_quanta socket4677_azif0045p001c01cs *
  page70_i8
#ISCELL
  logical_power universal_gnd *
  page70_i9
#ISCELL
  pure_quanta quanta_title_block_c *
  *
#ISCELL
  logical_power universal_gnd *
  page71_i1
#CELL
  pure_quanta socket4677_azif0045p001c01cs *
  page71_i2
#ISCELL
  logical_power universal_gnd *
  page71_i3
#ISCELL
  logical_power universal_gnd *
  page71_i4
#CELL
  pure_quanta socket4677_azif0045p001c01cs *
  page71_i5
#ISCELL
  logical_power universal_gnd *
  page71_i6
#ISCELL
  logical_power universal_gnd *
  page71_i7
#CELL
  pure_quanta socket4677_azif0045p001c01cs *
  page71_i8
#ISCELL
  logical_power universal_gnd *
  page71_i9
#ISCELL
  pure_quanta quanta_title_block_c *
  *
#ISCELL
  logical_power universal_gnd *
  page72_i1
#CELL
  pure_quanta socket4677_azif0045p001c01cs *
  page72_i2
#ISCELL
  logical_power universal_gnd *
  page72_i3
#ISCELL
  logical_power universal_gnd *
  page72_i4
#CELL
  pure_quanta socket4677_azif0045p001c01cs *
  page72_i5
#ISCELL
  logical_power universal_gnd *
  page72_i6
#ISCELL
  logical_power universal_gnd *
  page72_i7
#CELL
  pure_quanta socket4677_azif0045p001c01cs *
  page72_i8
#ISCELL
  logical_power universal_gnd *
  page72_i9
#ISCELL
  pure_quanta quanta_title_block_c *
  *
#ISCELL
  logical_power universal_gnd *
  page73_i1
#CELL
  pure_quanta socket4677_azif0045p001c01cs *
  page73_i2
#ISCELL
  logical_power universal_gnd *
  page73_i3
#ISCELL
  logical_power universal_gnd *
  page73_i4
#CELL
  pure_quanta socket4677_azif0045p001c01cs *
  page73_i5
#ISCELL
  logical_power universal_gnd *
  page73_i6
#ISCELL
  logical_power universal_gnd *
  page73_i7
#CELL
  pure_quanta socket4677_azif0045p001c01cs *
  page73_i8
#ISCELL
  pure_quanta quanta_title_block_c *
  *
#CELL
  pure_quanta q_cap *
  page74_i1
#CELL
  pure_quanta q_cap *
  page74_i10
#CELL
  pure_quanta q_cap *
  page74_i100
#ISCELL
  logical_power universal_gnd *
  page74_i101
#CELL
  pure_quanta q_cap *
  page74_i102
#CELL
  pure_quanta q_cap *
  page74_i103
#ISCELL
  logical_power universal_power *
  page74_i104
#CELL
  pure_quanta q_cap *
  page74_i105
#CELL
  pure_quanta q_cap *
  page74_i106
#CELL
  pure_quanta q_cap *
  page74_i107
#CELL
  pure_quanta q_cap *
  page74_i108
#CELL
  pure_quanta q_cap *
  page74_i109
#CELL
  pure_quanta q_cap *
  page74_i11
#CELL
  pure_quanta q_cap *
  page74_i110
#CELL
  pure_quanta q_cap *
  page74_i111
#CELL
  pure_quanta q_cap *
  page74_i112
#CELL
  pure_quanta q_cap *
  page74_i113
#CELL
  pure_quanta q_cap *
  page74_i114
#CELL
  pure_quanta q_cap *
  page74_i115
#CELL
  pure_quanta q_cap *
  page74_i116
#CELL
  pure_quanta q_cap *
  page74_i117
#CELL
  pure_quanta q_cap *
  page74_i118
#CELL
  pure_quanta q_cap *
  page74_i119
#ISCELL
  logical_power universal_power *
  page74_i12
#CELL
  pure_quanta q_cap *
  page74_i120
#CELL
  pure_quanta q_cap *
  page74_i121
#CELL
  pure_quanta q_cap *
  page74_i122
#CELL
  pure_quanta q_cap *
  page74_i123
#CELL
  pure_quanta q_cap *
  page74_i124
#CELL
  pure_quanta q_cap *
  page74_i125
#ISCELL
  logical_power universal_power *
  page74_i126
#CELL
  pure_quanta q_cap *
  page74_i127
#CELL
  pure_quanta q_cap *
  page74_i128
#ISCELL
  logical_power universal_gnd *
  page74_i129
#CELL
  pure_quanta q_cap *
  page74_i13
#CELL
  pure_quanta q_cap *
  page74_i130
#CELL
  pure_quanta q_cap *
  page74_i131
#CELL
  pure_quanta q_cap *
  page74_i132
#CELL
  pure_quanta q_cap *
  page74_i133
#CELL
  pure_quanta q_cap *
  page74_i134
#CELL
  pure_quanta q_cap *
  page74_i135
#ISCELL
  logical_power universal_gnd *
  page74_i136
#CELL
  pure_quanta q_cap *
  page74_i137
#ISCELL
  logical_power universal_gnd *
  page74_i138
#CELL
  pure_quanta q_cap *
  page74_i139
#ISCELL
  logical_power universal_power *
  page74_i14
#ISCELL
  logical_power universal_gnd *
  page74_i140
#CELL
  pure_quanta q_cap *
  page74_i141
#CELL
  pure_quanta q_cap *
  page74_i142
#CELL
  pure_quanta q_cap *
  page74_i15
#ISCELL
  logical_power universal_power *
  page74_i16
#CELL
  pure_quanta q_cap *
  page74_i17
#CELL
  pure_quanta q_cap *
  page74_i18
#CELL
  pure_quanta q_cap *
  page74_i19
#ISCELL
  logical_power universal_power *
  page74_i2
#CELL
  pure_quanta q_cap *
  page74_i20
#CELL
  pure_quanta q_cap *
  page74_i21
#CELL
  pure_quanta q_cap *
  page74_i22
#CELL
  pure_quanta q_cap *
  page74_i23
#ISCELL
  logical_power universal_power *
  page74_i24
#CELL
  pure_quanta q_cap *
  page74_i25
#ISCELL
  logical_power universal_power *
  page74_i26
#CELL
  pure_quanta q_cap *
  page74_i27
#CELL
  pure_quanta q_cap *
  page74_i28
#CELL
  pure_quanta q_cap *
  page74_i29
#CELL
  pure_quanta q_cap *
  page74_i3
#CELL
  pure_quanta q_cap *
  page74_i30
#CELL
  pure_quanta q_cap *
  page74_i31
#CELL
  pure_quanta q_cap *
  page74_i32
#CELL
  pure_quanta q_cap *
  page74_i33
#CELL
  pure_quanta q_cap *
  page74_i34
#CELL
  pure_quanta q_cap *
  page74_i35
#CELL
  pure_quanta q_cap *
  page74_i36
#CELL
  pure_quanta q_cap *
  page74_i37
#CELL
  pure_quanta q_cap *
  page74_i38
#ISCELL
  logical_power universal_power *
  page74_i39
#CELL
  pure_quanta q_cap *
  page74_i4
#CELL
  pure_quanta q_cap *
  page74_i40
#CELL
  pure_quanta q_cap *
  page74_i41
#CELL
  pure_quanta q_cap *
  page74_i42
#CELL
  pure_quanta q_cap *
  page74_i43
#CELL
  pure_quanta q_cap *
  page74_i44
#CELL
  pure_quanta q_cap *
  page74_i45
#CELL
  pure_quanta q_cap *
  page74_i46
#CELL
  pure_quanta q_cap *
  page74_i47
#CELL
  pure_quanta q_cap *
  page74_i48
#CELL
  pure_quanta q_cap *
  page74_i49
#CELL
  pure_quanta q_cap *
  page74_i5
#CELL
  pure_quanta q_cap *
  page74_i50
#CELL
  pure_quanta q_cap *
  page74_i51
#CELL
  pure_quanta q_cap *
  page74_i52
#CELL
  pure_quanta q_cap *
  page74_i53
#CELL
  pure_quanta q_cap *
  page74_i54
#CELL
  pure_quanta q_cap *
  page74_i55
#CELL
  pure_quanta q_cap *
  page74_i56
#CELL
  pure_quanta q_cap *
  page74_i57
#CELL
  pure_quanta q_cap *
  page74_i58
#CELL
  pure_quanta q_cap *
  page74_i59
#ISCELL
  logical_power universal_gnd *
  page74_i6
#CELL
  pure_quanta q_cap *
  page74_i60
#CELL
  pure_quanta q_cap *
  page74_i61
#CELL
  pure_quanta q_cap *
  page74_i62
#ISCELL
  logical_power universal_power *
  page74_i63
#CELL
  pure_quanta q_cap *
  page74_i64
#CELL
  pure_quanta q_cap *
  page74_i65
#ISCELL
  logical_power universal_gnd *
  page74_i66
#ISCELL
  logical_power universal_gnd *
  page74_i67
#CELL
  pure_quanta q_cap *
  page74_i68
#ISCELL
  logical_power universal_gnd *
  page74_i69
#CELL
  pure_quanta q_cap *
  page74_i7
#CELL
  pure_quanta q_cap *
  page74_i70
#CELL
  pure_quanta q_cap *
  page74_i71
#CELL
  pure_quanta q_cap *
  page74_i72
#ISCELL
  logical_power universal_gnd *
  page74_i73
#CELL
  pure_quanta q_cap *
  page74_i74
#CELL
  pure_quanta q_cap *
  page74_i75
#ISCELL
  logical_power universal_gnd *
  page74_i76
#CELL
  pure_quanta q_cap *
  page74_i77
#CELL
  pure_quanta q_cap *
  page74_i78
#ISCELL
  logical_power universal_power *
  page74_i79
#CELL
  pure_quanta q_cap *
  page74_i8
#CELL
  pure_quanta q_cap *
  page74_i80
#CELL
  pure_quanta q_cap *
  page74_i81
#ISCELL
  logical_power universal_gnd *
  page74_i82
#CELL
  pure_quanta q_cap *
  page74_i83
#ISCELL
  logical_power universal_gnd *
  page74_i84
#CELL
  pure_quanta q_cap *
  page74_i85
#CELL
  pure_quanta q_cap *
  page74_i86
#CELL
  pure_quanta q_cap *
  page74_i87
#ISCELL
  logical_power universal_gnd *
  page74_i88
#CELL
  pure_quanta q_cap *
  page74_i89
#CELL
  pure_quanta q_cap *
  page74_i9
#CELL
  pure_quanta q_cap *
  page74_i90
#ISCELL
  logical_power universal_power *
  page74_i91
#CELL
  pure_quanta q_cap *
  page74_i92
#CELL
  pure_quanta q_cap *
  page74_i93
#ISCELL
  logical_power universal_power *
  page74_i94
#CELL
  pure_quanta q_cap *
  page74_i95
#CELL
  pure_quanta q_cap *
  page74_i96
#CELL
  pure_quanta q_cap *
  page74_i97
#CELL
  pure_quanta q_cap *
  page74_i98
#ISCELL
  logical_power universal_power *
  page74_i99
#ISCELL
  pure_quanta quanta_title_block_c *
  *
#CELL
  pure_quanta q_cap *
  page75_i1
#ISCELL
  logical_power universal_power *
  page75_i10
#CELL
  pure_quanta q_cap *
  page75_i11
#ISCELL
  logical_power universal_power *
  page75_i12
#CELL
  pure_quanta q_cap *
  page75_i13
#CELL
  pure_quanta q_cap *
  page75_i14
#ISCELL
  logical_power universal_gnd *
  page75_i15
#CELL
  pure_quanta q_cap *
  page75_i16
#CELL
  pure_quanta q_cap *
  page75_i17
#CELL
  pure_quanta q_cap *
  page75_i18
#CELL
  pure_quanta q_cap *
  page75_i19
#ISCELL
  logical_power universal_power *
  page75_i2
#ISCELL
  logical_power universal_power *
  page75_i20
#CELL
  pure_quanta q_cap *
  page75_i21
#ISCELL
  logical_power universal_power *
  page75_i22
#CELL
  pure_quanta q_cap *
  page75_i23
#ISCELL
  logical_power universal_power *
  page75_i24
#CELL
  pure_quanta q_cap *
  page75_i25
#CELL
  pure_quanta q_cap *
  page75_i26
#CELL
  pure_quanta q_cap *
  page75_i27
#CELL
  pure_quanta q_cap *
  page75_i28
#CELL
  pure_quanta q_cap *
  page75_i29
#CELL
  pure_quanta q_cap *
  page75_i3
#ISCELL
  logical_power universal_gnd *
  page75_i30
#CELL
  pure_quanta q_cap *
  page75_i31
#CELL
  pure_quanta q_cap *
  page75_i32
#CELL
  pure_quanta q_cap *
  page75_i33
#CELL
  pure_quanta q_cap *
  page75_i34
#CELL
  pure_quanta q_cap *
  page75_i35
#CELL
  pure_quanta q_cap *
  page75_i36
#CELL
  pure_quanta q_cap *
  page75_i37
#CELL
  pure_quanta q_cap *
  page75_i38
#CELL
  pure_quanta q_cap *
  page75_i39
#CELL
  pure_quanta q_cap *
  page75_i4
#CELL
  pure_quanta q_cap *
  page75_i40
#CELL
  pure_quanta q_cap *
  page75_i41
#ISCELL
  logical_power universal_power *
  page75_i42
#CELL
  pure_quanta q_cap *
  page75_i43
#CELL
  pure_quanta q_cap *
  page75_i44
#ISCELL
  logical_power universal_power *
  page75_i45
#CELL
  pure_quanta q_cap *
  page75_i46
#CELL
  pure_quanta q_cap *
  page75_i47
#CELL
  pure_quanta q_cap *
  page75_i48
#CELL
  pure_quanta q_cap *
  page75_i49
#ISCELL
  logical_power universal_gnd *
  page75_i5
#CELL
  pure_quanta q_cap *
  page75_i50
#CELL
  pure_quanta q_cap *
  page75_i51
#CELL
  pure_quanta q_cap *
  page75_i52
#ISCELL
  logical_power universal_gnd *
  page75_i53
#CELL
  pure_quanta q_cap *
  page75_i54
#CELL
  pure_quanta q_cap *
  page75_i55
#CELL
  pure_quanta q_cap *
  page75_i56
#ISCELL
  logical_power universal_gnd *
  page75_i57
#CELL
  pure_quanta q_cap *
  page75_i58
#CELL
  pure_quanta q_cap *
  page75_i59
#CELL
  pure_quanta q_cap *
  page75_i6
#ISCELL
  logical_power universal_gnd *
  page75_i60
#CELL
  pure_quanta q_cap *
  page75_i61
#CELL
  pure_quanta q_cap *
  page75_i62
#ISCELL
  logical_power universal_gnd *
  page75_i63
#CELL
  pure_quanta q_cap *
  page75_i64
#ISCELL
  logical_power universal_power *
  page75_i65
#ISCELL
  logical_power universal_gnd *
  page75_i66
#CELL
  pure_quanta q_cap *
  page75_i67
#CELL
  pure_quanta q_cap *
  page75_i68
#ISCELL
  logical_power universal_gnd *
  page75_i7
#CELL
  pure_quanta q_cap *
  page75_i8
#CELL
  pure_quanta q_cap *
  page75_i9
#ISCELL
  pure_quanta quanta_title_block_c *
  *
#CELL
  pure_quanta q_cap *
  page76_i1
#CELL
  pure_quanta q_cap *
  page76_i10
#CELL
  pure_quanta q_cap *
  page76_i11
#ISCELL
  logical_power universal_power *
  page76_i12
#CELL
  pure_quanta q_cap *
  page76_i13
#CELL
  pure_quanta q_cap *
  page76_i14
#ISCELL
  logical_power universal_gnd *
  page76_i15
#CELL
  pure_quanta q_cap *
  page76_i16
#ISCELL
  logical_power universal_power *
  page76_i17
#CELL
  pure_quanta q_cap *
  page76_i18
#ISCELL
  logical_power universal_power *
  page76_i19
#CELL
  pure_quanta q_cap *
  page76_i2
#CELL
  pure_quanta q_cap *
  page76_i20
#CELL
  pure_quanta q_cap *
  page76_i21
#CELL
  pure_quanta q_cap *
  page76_i22
#CELL
  pure_quanta q_cap *
  page76_i23
#ISCELL
  logical_power universal_power *
  page76_i24
#CELL
  pure_quanta q_cap *
  page76_i25
#CELL
  pure_quanta q_cap *
  page76_i26
#CELL
  pure_quanta q_cap *
  page76_i27
#CELL
  pure_quanta q_cap *
  page76_i28
#CELL
  pure_quanta q_cap *
  page76_i29
#CELL
  pure_quanta q_cap *
  page76_i3
#ISCELL
  logical_power universal_gnd *
  page76_i30
#CELL
  pure_quanta q_cap *
  page76_i31
#CELL
  pure_quanta q_cap *
  page76_i32
#CELL
  pure_quanta q_cap *
  page76_i33
#ISCELL
  logical_power universal_gnd *
  page76_i34
#CELL
  pure_quanta q_cap *
  page76_i35
#CELL
  pure_quanta q_cap *
  page76_i36
#CELL
  pure_quanta q_cap *
  page76_i37
#CELL
  pure_quanta q_cap *
  page76_i38
#CELL
  pure_quanta q_cap *
  page76_i39
#ISCELL
  logical_power universal_power *
  page76_i4
#ISCELL
  logical_power universal_gnd *
  page76_i40
#CELL
  pure_quanta q_cap *
  page76_i41
#ISCELL
  logical_power universal_gnd *
  page76_i42
#CELL
  pure_quanta q_cap *
  page76_i43
#CELL
  pure_quanta q_cap *
  page76_i44
#CELL
  pure_quanta q_cap *
  page76_i45
#CELL
  pure_quanta q_cap *
  page76_i46
#CELL
  pure_quanta q_cap *
  page76_i47
#CELL
  pure_quanta q_cap *
  page76_i48
#CELL
  pure_quanta q_cap *
  page76_i49
#CELL
  pure_quanta q_cap *
  page76_i5
#CELL
  pure_quanta q_cap *
  page76_i50
#CELL
  pure_quanta q_cap *
  page76_i51
#CELL
  pure_quanta q_cap *
  page76_i52
#CELL
  pure_quanta q_cap *
  page76_i53
#CELL
  pure_quanta q_cap *
  page76_i54
#ISCELL
  logical_power universal_gnd *
  page76_i55
#CELL
  pure_quanta q_cap *
  page76_i6
#CELL
  pure_quanta q_cap *
  page76_i7
#ISCELL
  logical_power universal_power *
  page76_i8
#CELL
  pure_quanta q_cap *
  page76_i9
#ISCELL
  pure_quanta quanta_title_block_c *
  *
#CELL
  pure_quanta q_cap *
  page77_i1
#CELL
  pure_quanta q_cap *
  page77_i10
#CELL
  pure_quanta q_cap *
  page77_i100
#CELL
  pure_quanta q_cap *
  page77_i101
#CELL
  pure_quanta q_cap *
  page77_i102
#CELL
  pure_quanta q_cap *
  page77_i103
#CELL
  pure_quanta q_cap *
  page77_i104
#CELL
  pure_quanta q_cap *
  page77_i105
#CELL
  pure_quanta q_cap *
  page77_i106
#ISCELL
  logical_power universal_power *
  page77_i107
#ISCELL
  logical_power universal_gnd *
  page77_i108
#CELL
  pure_quanta q_cap *
  page77_i109
#CELL
  pure_quanta q_cap *
  page77_i11
#CELL
  pure_quanta q_cap *
  page77_i110
#CELL
  pure_quanta q_cap *
  page77_i111
#CELL
  pure_quanta q_cap *
  page77_i112
#CELL
  pure_quanta q_cap *
  page77_i113
#CELL
  pure_quanta q_cap *
  page77_i114
#CELL
  pure_quanta q_cap *
  page77_i115
#ISCELL
  logical_power universal_gnd *
  page77_i116
#CELL
  pure_quanta q_cap *
  page77_i117
#CELL
  pure_quanta q_cap *
  page77_i118
#CELL
  pure_quanta q_cap *
  page77_i119
#ISCELL
  logical_power universal_power *
  page77_i12
#CELL
  pure_quanta q_cap *
  page77_i120
#CELL
  pure_quanta q_cap *
  page77_i121
#CELL
  pure_quanta q_cap *
  page77_i122
#CELL
  pure_quanta q_cap *
  page77_i123
#CELL
  pure_quanta q_cap *
  page77_i124
#CELL
  pure_quanta q_cap *
  page77_i125
#CELL
  pure_quanta q_cap *
  page77_i126
#CELL
  pure_quanta q_cap *
  page77_i127
#CELL
  pure_quanta q_cap *
  page77_i128
#CELL
  pure_quanta q_cap *
  page77_i129
#CELL
  pure_quanta q_cap *
  page77_i13
#CELL
  pure_quanta q_cap *
  page77_i130
#CELL
  pure_quanta q_cap *
  page77_i131
#CELL
  pure_quanta q_cap *
  page77_i132
#CELL
  pure_quanta q_cap *
  page77_i133
#CELL
  pure_quanta q_cap *
  page77_i134
#ISCELL
  logical_power universal_gnd *
  page77_i135
#CELL
  pure_quanta q_cap *
  page77_i136
#ISCELL
  logical_power universal_gnd *
  page77_i137
#CELL
  pure_quanta q_cap *
  page77_i138
#CELL
  pure_quanta q_cap *
  page77_i139
#CELL
  pure_quanta q_cap *
  page77_i14
#CELL
  pure_quanta q_cap *
  page77_i140
#ISCELL
  logical_power universal_gnd *
  page77_i141
#CELL
  pure_quanta q_cap *
  page77_i142
#CELL
  pure_quanta q_cap *
  page77_i15
#CELL
  pure_quanta q_cap *
  page77_i16
#CELL
  pure_quanta q_cap *
  page77_i17
#CELL
  pure_quanta q_cap *
  page77_i18
#CELL
  pure_quanta q_cap *
  page77_i19
#CELL
  pure_quanta q_cap *
  page77_i2
#CELL
  pure_quanta q_cap *
  page77_i20
#ISCELL
  logical_power universal_power *
  page77_i21
#CELL
  pure_quanta q_cap *
  page77_i22
#CELL
  pure_quanta q_cap *
  page77_i23
#ISCELL
  logical_power universal_power *
  page77_i24
#CELL
  pure_quanta q_cap *
  page77_i25
#CELL
  pure_quanta q_cap *
  page77_i26
#ISCELL
  logical_power universal_power *
  page77_i27
#CELL
  pure_quanta q_cap *
  page77_i28
#CELL
  pure_quanta q_cap *
  page77_i29
#ISCELL
  logical_power universal_power *
  page77_i3
#CELL
  pure_quanta q_cap *
  page77_i30
#CELL
  pure_quanta q_cap *
  page77_i31
#CELL
  pure_quanta q_cap *
  page77_i32
#CELL
  pure_quanta q_cap *
  page77_i33
#CELL
  pure_quanta q_cap *
  page77_i34
#CELL
  pure_quanta q_cap *
  page77_i35
#ISCELL
  logical_power universal_power *
  page77_i36
#CELL
  pure_quanta q_cap *
  page77_i37
#CELL
  pure_quanta q_cap *
  page77_i38
#CELL
  pure_quanta q_cap *
  page77_i39
#CELL
  pure_quanta q_cap *
  page77_i4
#CELL
  pure_quanta q_cap *
  page77_i40
#CELL
  pure_quanta q_cap *
  page77_i41
#CELL
  pure_quanta q_cap *
  page77_i42
#ISCELL
  logical_power universal_power *
  page77_i43
#CELL
  pure_quanta q_cap *
  page77_i44
#CELL
  pure_quanta q_cap *
  page77_i45
#CELL
  pure_quanta q_cap *
  page77_i46
#CELL
  pure_quanta q_cap *
  page77_i47
#CELL
  pure_quanta q_cap *
  page77_i48
#CELL
  pure_quanta q_cap *
  page77_i49
#CELL
  pure_quanta q_cap *
  page77_i5
#CELL
  pure_quanta q_cap *
  page77_i50
#CELL
  pure_quanta q_cap *
  page77_i51
#CELL
  pure_quanta q_cap *
  page77_i52
#CELL
  pure_quanta q_cap *
  page77_i53
#ISCELL
  logical_power universal_gnd *
  page77_i54
#CELL
  pure_quanta q_cap *
  page77_i55
#ISCELL
  logical_power universal_gnd *
  page77_i56
#CELL
  pure_quanta q_cap *
  page77_i57
#CELL
  pure_quanta q_cap *
  page77_i58
#CELL
  pure_quanta q_cap *
  page77_i59
#ISCELL
  logical_power universal_gnd *
  page77_i6
#ISCELL
  logical_power universal_gnd *
  page77_i60
#CELL
  pure_quanta q_cap *
  page77_i61
#CELL
  pure_quanta q_cap *
  page77_i62
#CELL
  pure_quanta q_cap *
  page77_i63
#CELL
  pure_quanta q_cap *
  page77_i64
#ISCELL
  logical_power universal_gnd *
  page77_i65
#CELL
  pure_quanta q_cap *
  page77_i66
#CELL
  pure_quanta q_cap *
  page77_i67
#ISCELL
  logical_power universal_power *
  page77_i68
#ISCELL
  logical_power universal_gnd *
  page77_i69
#CELL
  pure_quanta q_cap *
  page77_i7
#CELL
  pure_quanta q_cap *
  page77_i70
#CELL
  pure_quanta q_cap *
  page77_i71
#ISCELL
  logical_power universal_power *
  page77_i72
#CELL
  pure_quanta q_cap *
  page77_i73
#CELL
  pure_quanta q_cap *
  page77_i74
#CELL
  pure_quanta q_cap *
  page77_i75
#CELL
  pure_quanta q_cap *
  page77_i76
#CELL
  pure_quanta q_cap *
  page77_i77
#CELL
  pure_quanta q_cap *
  page77_i78
#CELL
  pure_quanta q_cap *
  page77_i79
#CELL
  pure_quanta q_cap *
  page77_i8
#CELL
  pure_quanta q_cap *
  page77_i80
#CELL
  pure_quanta q_cap *
  page77_i81
#CELL
  pure_quanta q_cap *
  page77_i82
#CELL
  pure_quanta q_cap *
  page77_i83
#CELL
  pure_quanta q_cap *
  page77_i84
#CELL
  pure_quanta q_cap *
  page77_i85
#CELL
  pure_quanta q_cap *
  page77_i86
#ISCELL
  logical_power universal_gnd *
  page77_i87
#CELL
  pure_quanta q_cap *
  page77_i88
#ISCELL
  logical_power universal_gnd *
  page77_i89
#ISCELL
  logical_power universal_power *
  page77_i9
#ISCELL
  logical_power universal_power *
  page77_i90
#CELL
  pure_quanta q_cap *
  page77_i91
#ISCELL
  logical_power universal_power *
  page77_i92
#CELL
  pure_quanta q_cap *
  page77_i93
#CELL
  pure_quanta q_cap *
  page77_i94
#CELL
  pure_quanta q_cap *
  page77_i95
#ISCELL
  logical_power universal_gnd *
  page77_i96
#CELL
  pure_quanta q_cap *
  page77_i97
#CELL
  pure_quanta q_cap *
  page77_i98
#ISCELL
  logical_power universal_power *
  page77_i99
#ISCELL
  pure_quanta quanta_title_block_c *
  *
#CELL
  pure_quanta q_cap *
  page78_i1
#CELL
  pure_quanta q_cap *
  page78_i10
#ISCELL
  logical_power universal_power *
  page78_i11
#CELL
  pure_quanta q_cap *
  page78_i12
#ISCELL
  logical_power universal_power *
  page78_i13
#CELL
  pure_quanta q_cap *
  page78_i14
#ISCELL
  logical_power universal_power *
  page78_i15
#CELL
  pure_quanta q_cap *
  page78_i16
#ISCELL
  logical_power universal_power *
  page78_i17
#CELL
  pure_quanta q_cap *
  page78_i18
#CELL
  pure_quanta q_cap *
  page78_i19
#ISCELL
  logical_power universal_power *
  page78_i2
#ISCELL
  logical_power universal_gnd *
  page78_i20
#CELL
  pure_quanta q_cap *
  page78_i21
#ISCELL
  logical_power universal_gnd *
  page78_i22
#CELL
  pure_quanta q_cap *
  page78_i23
#CELL
  pure_quanta q_cap *
  page78_i24
#CELL
  pure_quanta q_cap *
  page78_i25
#CELL
  pure_quanta q_cap *
  page78_i26
#CELL
  pure_quanta q_cap *
  page78_i27
#ISCELL
  logical_power universal_gnd *
  page78_i28
#CELL
  pure_quanta q_cap *
  page78_i29
#CELL
  pure_quanta q_cap *
  page78_i3
#CELL
  pure_quanta q_cap *
  page78_i30
#CELL
  pure_quanta q_cap *
  page78_i31
#CELL
  pure_quanta q_cap *
  page78_i32
#CELL
  pure_quanta q_cap *
  page78_i33
#CELL
  pure_quanta q_cap *
  page78_i34
#CELL
  pure_quanta q_cap *
  page78_i35
#CELL
  pure_quanta q_cap *
  page78_i36
#CELL
  pure_quanta q_cap *
  page78_i37
#CELL
  pure_quanta q_cap *
  page78_i38
#CELL
  pure_quanta q_cap *
  page78_i39
#CELL
  pure_quanta q_cap *
  page78_i4
#CELL
  pure_quanta q_cap *
  page78_i40
#CELL
  pure_quanta q_cap *
  page78_i41
#CELL
  pure_quanta q_cap *
  page78_i42
#CELL
  pure_quanta q_cap *
  page78_i43
#CELL
  pure_quanta q_cap *
  page78_i44
#CELL
  pure_quanta q_cap *
  page78_i45
#CELL
  pure_quanta q_cap *
  page78_i46
#ISCELL
  logical_power universal_power *
  page78_i47
#CELL
  pure_quanta q_cap *
  page78_i48
#CELL
  pure_quanta q_cap *
  page78_i49
#CELL
  pure_quanta q_cap *
  page78_i5
#ISCELL
  logical_power universal_power *
  page78_i50
#CELL
  pure_quanta q_cap *
  page78_i51
#CELL
  pure_quanta q_cap *
  page78_i52
#CELL
  pure_quanta q_cap *
  page78_i53
#ISCELL
  logical_power universal_gnd *
  page78_i54
#CELL
  pure_quanta q_cap *
  page78_i55
#ISCELL
  logical_power universal_gnd *
  page78_i56
#CELL
  pure_quanta q_cap *
  page78_i57
#CELL
  pure_quanta q_cap *
  page78_i58
#ISCELL
  logical_power universal_gnd *
  page78_i59
#ISCELL
  logical_power universal_gnd *
  page78_i6
#CELL
  pure_quanta q_cap *
  page78_i60
#ISCELL
  logical_power universal_gnd *
  page78_i61
#ISCELL
  logical_power universal_gnd *
  page78_i62
#CELL
  pure_quanta q_cap *
  page78_i63
#CELL
  pure_quanta q_cap *
  page78_i64
#CELL
  pure_quanta q_cap *
  page78_i65
#CELL
  pure_quanta q_cap *
  page78_i66
#ISCELL
  logical_power universal_power *
  page78_i67
#CELL
  pure_quanta q_cap *
  page78_i68
#CELL
  pure_quanta q_cap *
  page78_i7
#CELL
  pure_quanta q_cap *
  page78_i8
#ISCELL
  logical_power universal_power *
  page78_i9
#ISCELL
  pure_quanta quanta_title_block_c *
  *
#CELL
  pure_quanta q_cap *
  page79_i1
#CELL
  pure_quanta q_cap *
  page79_i10
#CELL
  pure_quanta q_cap *
  page79_i11
#CELL
  pure_quanta q_cap *
  page79_i12
#CELL
  pure_quanta q_cap *
  page79_i13
#ISCELL
  logical_power universal_power *
  page79_i14
#CELL
  pure_quanta q_cap *
  page79_i15
#CELL
  pure_quanta q_cap *
  page79_i16
#CELL
  pure_quanta q_cap *
  page79_i17
#ISCELL
  logical_power universal_power *
  page79_i18
#CELL
  pure_quanta q_cap *
  page79_i19
#ISCELL
  logical_power universal_power *
  page79_i2
#CELL
  pure_quanta q_cap *
  page79_i20
#CELL
  pure_quanta q_cap *
  page79_i21
#ISCELL
  logical_power universal_power *
  page79_i22
#CELL
  pure_quanta q_cap *
  page79_i23
#CELL
  pure_quanta q_cap *
  page79_i24
#CELL
  pure_quanta q_cap *
  page79_i25
#CELL
  pure_quanta q_cap *
  page79_i26
#CELL
  pure_quanta q_cap *
  page79_i27
#ISCELL
  logical_power universal_gnd *
  page79_i28
#CELL
  pure_quanta q_cap *
  page79_i29
#CELL
  pure_quanta q_cap *
  page79_i3
#ISCELL
  logical_power universal_gnd *
  page79_i30
#CELL
  pure_quanta q_cap *
  page79_i31
#CELL
  pure_quanta q_cap *
  page79_i32
#CELL
  pure_quanta q_cap *
  page79_i33
#CELL
  pure_quanta q_cap *
  page79_i34
#CELL
  pure_quanta q_cap *
  page79_i35
#ISCELL
  logical_power universal_power *
  page79_i36
#CELL
  pure_quanta q_cap *
  page79_i37
#CELL
  pure_quanta q_cap *
  page79_i38
#CELL
  pure_quanta q_cap *
  page79_i39
#CELL
  pure_quanta q_cap *
  page79_i4
#ISCELL
  logical_power universal_gnd *
  page79_i40
#CELL
  pure_quanta q_cap *
  page79_i41
#CELL
  pure_quanta q_cap *
  page79_i42
#CELL
  pure_quanta q_cap *
  page79_i43
#CELL
  pure_quanta q_cap *
  page79_i44
#ISCELL
  logical_power universal_power *
  page79_i45
#CELL
  pure_quanta q_cap *
  page79_i46
#CELL
  pure_quanta q_cap *
  page79_i47
#ISCELL
  logical_power universal_gnd *
  page79_i48
#CELL
  pure_quanta q_cap *
  page79_i49
#CELL
  pure_quanta q_cap *
  page79_i5
#CELL
  pure_quanta q_cap *
  page79_i50
#CELL
  pure_quanta q_cap *
  page79_i51
#CELL
  pure_quanta q_cap *
  page79_i52
#CELL
  pure_quanta q_cap *
  page79_i53
#ISCELL
  logical_power universal_gnd *
  page79_i54
#CELL
  pure_quanta q_cap *
  page79_i55
#ISCELL
  logical_power universal_gnd *
  page79_i6
#CELL
  pure_quanta q_cap *
  page79_i7
#CELL
  pure_quanta q_cap *
  page79_i8
#CELL
  pure_quanta q_cap *
  page79_i9
#ISCELL
  mstr_misc dns *
  *
#ISCELL
  pure_quanta quanta_title_block_c *
  *
#CELL
  pure_quanta q_res *
  page80_i1
#ISCELL
  logical_power universal_power *
  page80_i10
#ISCELL
  logical_power universal_power *
  page80_i11
#CELL
  pure_quanta q_res *
  page80_i12
#CELL
  pure_quanta q_res *
  page80_i13
#ISCELL
  standard offpage *
  page80_i14
#ISCELL
  standard offpage *
  page80_i15
#ISCELL
  standard offpage *
  page80_i16
#ISCELL
  standard offpage *
  page80_i17
#ISCELL
  logical_power universal_power *
  page80_i18
#ISCELL
  logical_power universal_gnd *
  page80_i19
#CELL
  pure_quanta q_res *
  page80_i2
#CELL
  pure_quanta q_cap *
  page80_i20
#ISCELL
  logical_power universal_power *
  page80_i21
#CELL
  pure_quanta q_res *
  page80_i22
#ISCELL
  standard offpage *
  page80_i23
#ISCELL
  standard offpage *
  page80_i24
#CELL
  pure_quanta q_res *
  page80_i25
#CELL
  pure_quanta q_res *
  page80_i26
#CELL
  pure_quanta q_res *
  page80_i27
#CELL
  pure_quanta q_cap *
  page80_i28
#ISCELL
  standard offpage *
  page80_i29
#ISCELL
  logical_power universal_power *
  page80_i3
#ISCELL
  standard offpage *
  page80_i30
#ISCELL
  logical_power universal_power *
  page80_i31
#ISCELL
  logical_power universal_power *
  page80_i32
#ISCELL
  logical_power universal_power *
  page80_i33
#CELL
  pure_quanta q_res *
  page80_i34
#CELL
  pure_quanta q_res *
  page80_i35
#ISCELL
  logical_power universal_power *
  page80_i36
#ISCELL
  logical_power universal_gnd *
  page80_i4
#CELL
  pure_quanta q_cap *
  page80_i5
#ISCELL
  logical_power universal_power *
  page80_i6
#CELL
  pure_quanta q_res *
  page80_i7
#CELL
  pure_quanta q_res *
  page80_i8
#CELL
  pure_quanta q_cap *
  page80_i9
#ISCELL
  pure_quanta quanta_title_block_c *
  *
#ISCELL
  logical_power bom_note *
  *
#ISCELL
  logical_power cad_note *
  *
#ISCELL
  pure_quanta quanta_title_block_c *
  *
#ISCELL
  standard tap *
  page82_i10
#ISCELL
  standard offpage *
  page82_i100
#ISCELL
  standard offpage *
  page82_i101
#ISCELL
  standard offpage *
  page82_i102
#ISCELL
  standard offpage *
  page82_i103
#ISCELL
  standard tap *
  page82_i104
#ISCELL
  standard tap *
  page82_i105
#ISCELL
  standard tap *
  page82_i106
#ISCELL
  standard tap *
  page82_i107
#ISCELL
  standard tap *
  page82_i108
#ISCELL
  standard tap *
  page82_i109
#ISCELL
  standard tap *
  page82_i11
#ISCELL
  standard tap *
  page82_i110
#ISCELL
  standard tap *
  page82_i111
#ISCELL
  standard tap *
  page82_i112
#ISCELL
  standard tap *
  page82_i113
#ISCELL
  standard tap *
  page82_i114
#ISCELL
  standard tap *
  page82_i115
#ISCELL
  standard tap *
  page82_i116
#ISCELL
  standard tap *
  page82_i117
#ISCELL
  standard tap *
  page82_i118
#ISCELL
  standard tap *
  page82_i119
#ISCELL
  standard tap *
  page82_i12
#ISCELL
  standard tap *
  page82_i120
#ISCELL
  standard tap *
  page82_i121
#ISCELL
  standard tap *
  page82_i122
#ISCELL
  standard tap *
  page82_i123
#ISCELL
  standard tap *
  page82_i124
#ISCELL
  standard tap *
  page82_i125
#ISCELL
  standard tap *
  page82_i126
#ISCELL
  standard tap *
  page82_i128
#ISCELL
  standard tap *
  page82_i129
#ISCELL
  standard tap *
  page82_i13
#ISCELL
  standard tap *
  page82_i130
#ISCELL
  standard tap *
  page82_i131
#ISCELL
  standard offpage *
  page82_i132
#ISCELL
  standard tap *
  page82_i133
#ISCELL
  standard tap *
  page82_i134
#ISCELL
  standard tap *
  page82_i135
#ISCELL
  standard tap *
  page82_i136
#ISCELL
  standard tap *
  page82_i137
#ISCELL
  standard tap *
  page82_i138
#ISCELL
  standard offpage *
  page82_i139
#ISCELL
  standard offpage *
  page82_i14
#ISCELL
  standard tap *
  page82_i140
#ISCELL
  standard offpage *
  page82_i142
#ISCELL
  standard offpage *
  page82_i143
#ISCELL
  standard offpage *
  page82_i144
#ISCELL
  standard offpage *
  page82_i145
#ISCELL
  standard offpage *
  page82_i146
#ISCELL
  standard offpage *
  page82_i147
#ISCELL
  standard offpage *
  page82_i148
#ISCELL
  standard offpage *
  page82_i149
#ISCELL
  standard tap *
  page82_i15
#ISCELL
  standard tap *
  page82_i157
#ISCELL
  standard tap *
  page82_i158
#ISCELL
  standard tap *
  page82_i16
#ISCELL
  standard tap *
  page82_i160
#ISCELL
  standard tap *
  page82_i161
#ISCELL
  standard tap *
  page82_i162
#ISCELL
  standard tap *
  page82_i163
#ISCELL
  standard tap *
  page82_i164
#ISCELL
  standard tap *
  page82_i165
#ISCELL
  standard offpage *
  page82_i166
#ISCELL
  standard tap *
  page82_i167
#ISCELL
  standard tap *
  page82_i168
#ISCELL
  standard tap *
  page82_i169
#ISCELL
  standard tap *
  page82_i17
#ISCELL
  standard tap *
  page82_i170
#ISCELL
  standard tap *
  page82_i171
#ISCELL
  standard tap *
  page82_i172
#ISCELL
  standard tap *
  page82_i173
#ISCELL
  standard tap *
  page82_i174
#ISCELL
  standard offpage *
  page82_i175
#ISCELL
  standard offpage *
  page82_i176
#ISCELL
  standard offpage *
  page82_i177
#ISCELL
  standard offpage *
  page82_i178
#ISCELL
  standard tap *
  page82_i18
#ISCELL
  standard offpage *
  page82_i180
#ISCELL
  standard offpage *
  page82_i181
#ISCELL
  standard offpage *
  page82_i182
#ISCELL
  logical_power vcc_core *
  page82_i183
#ISCELL
  logical_power universal_gnd *
  page82_i184
#ISCELL
  logical_power universal_gnd *
  page82_i185
#ISCELL
  logical_power vcc_core *
  page82_i186
#ISCELL
  logical_power vcc_core *
  page82_i187
#CELL
  pure_quanta q_cap *
  page82_i188
#ISCELL
  standard tap *
  page82_i19
#CELL
  pure_quanta q_cap *
  page82_i190
#ISCELL
  logical_power universal_gnd *
  page82_i191
#CELL
  pure_quanta q_cap *
  page82_i192
#ISCELL
  logical_power vcc_core *
  page82_i193
#ISCELL
  logical_power universal_gnd *
  page82_i194
#ISCELL
  standard offpage *
  page82_i195
#CELL
  pure_quanta q_res *
  page82_i196
#ISCELL
  logical_power universal_gnd *
  page82_i197
#CELL
  pure_quanta sconn288_adr50017p130cc *
  page82_i198
#ISCELL
  standard tap *
  page82_i20
#ISCELL
  standard offpage *
  page82_i201
#CELL
  pure_quanta sconn288_adr50017p130cc *
  page82_i202
#CELL
  pure_quanta sconn288_adr50017p130cc *
  page82_i203
#CELL
  pure_quanta q_res *
  page82_i204
#ISCELL
  standard offpage *
  page82_i205
#ISCELL
  standard tap *
  page82_i21
#ISCELL
  standard tap *
  page82_i22
#ISCELL
  standard tap *
  page82_i23
#ISCELL
  standard tap *
  page82_i24
#ISCELL
  standard tap *
  page82_i25
#ISCELL
  standard tap *
  page82_i26
#ISCELL
  standard tap *
  page82_i27
#ISCELL
  standard tap *
  page82_i28
#ISCELL
  standard tap *
  page82_i29
#ISCELL
  standard tap *
  page82_i30
#ISCELL
  standard tap *
  page82_i31
#ISCELL
  standard tap *
  page82_i32
#ISCELL
  standard tap *
  page82_i33
#ISCELL
  standard tap *
  page82_i34
#ISCELL
  standard tap *
  page82_i35
#ISCELL
  standard tap *
  page82_i36
#ISCELL
  standard tap *
  page82_i37
#ISCELL
  standard tap *
  page82_i38
#ISCELL
  standard tap *
  page82_i39
#ISCELL
  standard tap *
  page82_i4
#ISCELL
  standard tap *
  page82_i40
#ISCELL
  standard tap *
  page82_i41
#ISCELL
  standard tap *
  page82_i42
#ISCELL
  standard tap *
  page82_i43
#ISCELL
  standard tap *
  page82_i44
#ISCELL
  standard tap *
  page82_i45
#ISCELL
  standard tap *
  page82_i46
#ISCELL
  standard tap *
  page82_i47
#ISCELL
  standard tap *
  page82_i48
#ISCELL
  standard tap *
  page82_i49
#ISCELL
  standard tap *
  page82_i5
#ISCELL
  standard tap *
  page82_i50
#ISCELL
  standard tap *
  page82_i51
#ISCELL
  standard tap *
  page82_i52
#ISCELL
  standard tap *
  page82_i53
#ISCELL
  standard tap *
  page82_i54
#ISCELL
  standard tap *
  page82_i55
#ISCELL
  standard tap *
  page82_i56
#ISCELL
  standard tap *
  page82_i57
#ISCELL
  standard tap *
  page82_i58
#ISCELL
  standard tap *
  page82_i59
#ISCELL
  standard tap *
  page82_i6
#ISCELL
  standard tap *
  page82_i60
#ISCELL
  standard tap *
  page82_i61
#ISCELL
  standard tap *
  page82_i62
#ISCELL
  standard tap *
  page82_i63
#ISCELL
  standard tap *
  page82_i64
#ISCELL
  standard tap *
  page82_i65
#ISCELL
  standard tap *
  page82_i66
#ISCELL
  standard tap *
  page82_i67
#ISCELL
  standard offpage *
  page82_i68
#ISCELL
  standard tap *
  page82_i69
#ISCELL
  standard tap *
  page82_i7
#ISCELL
  standard tap *
  page82_i72
#ISCELL
  standard tap *
  page82_i74
#ISCELL
  standard tap *
  page82_i75
#ISCELL
  standard tap *
  page82_i78
#ISCELL
  standard tap *
  page82_i8
#ISCELL
  standard tap *
  page82_i80
#ISCELL
  standard tap *
  page82_i82
#ISCELL
  standard tap *
  page82_i84
#ISCELL
  standard tap *
  page82_i87
#ISCELL
  standard tap *
  page82_i88
#ISCELL
  standard tap *
  page82_i89
#ISCELL
  standard tap *
  page82_i9
#ISCELL
  standard tap *
  page82_i90
#ISCELL
  standard tap *
  page82_i91
#ISCELL
  standard tap *
  page82_i92
#ISCELL
  standard tap *
  page82_i93
#ISCELL
  standard tap *
  page82_i94
#ISCELL
  standard tap *
  page82_i95
#ISCELL
  standard tap *
  page82_i96
#ISCELL
  standard tap *
  page82_i97
#ISCELL
  standard tap *
  page82_i98
#ISCELL
  standard tap *
  page82_i99
#ISCELL
  logical_power bom_note *
  *
#ISCELL
  logical_power cad_note *
  *
#ISCELL
  pure_quanta quanta_title_block_c *
  *
#ISCELL
  logical_power universal_gnd *
  page83_i1
#CELL
  pure_quanta q_res *
  page83_i10
#ISCELL
  standard tap *
  page83_i100
#ISCELL
  standard tap *
  page83_i101
#ISCELL
  standard tap *
  page83_i102
#ISCELL
  standard tap *
  page83_i103
#ISCELL
  standard tap *
  page83_i104
#ISCELL
  standard tap *
  page83_i105
#ISCELL
  standard tap *
  page83_i106
#ISCELL
  standard tap *
  page83_i107
#ISCELL
  standard offpage *
  page83_i108
#ISCELL
  standard tap *
  page83_i109
#ISCELL
  standard tap *
  page83_i110
#ISCELL
  standard tap *
  page83_i111
#ISCELL
  standard tap *
  page83_i112
#ISCELL
  standard tap *
  page83_i113
#ISCELL
  standard tap *
  page83_i114
#ISCELL
  standard tap *
  page83_i115
#ISCELL
  standard tap *
  page83_i116
#ISCELL
  standard tap *
  page83_i117
#ISCELL
  standard tap *
  page83_i118
#ISCELL
  logical_power vcc_core *
  page83_i119
#ISCELL
  standard offpage *
  page83_i12
#CELL
  pure_quanta q_cap *
  page83_i120
#ISCELL
  logical_power universal_gnd *
  page83_i121
#CELL
  pure_quanta q_cap *
  page83_i122
#ISCELL
  logical_power vcc_core *
  page83_i123
#ISCELL
  standard offpage *
  page83_i124
#ISCELL
  standard tap *
  page83_i126
#ISCELL
  standard tap *
  page83_i127
#ISCELL
  standard tap *
  page83_i128
#ISCELL
  standard tap *
  page83_i129
#ISCELL
  logical_power vcc_core *
  page83_i13
#ISCELL
  standard tap *
  page83_i130
#ISCELL
  standard tap *
  page83_i131
#ISCELL
  standard tap *
  page83_i132
#ISCELL
  standard tap *
  page83_i133
#ISCELL
  standard tap *
  page83_i134
#ISCELL
  standard tap *
  page83_i135
#ISCELL
  standard tap *
  page83_i136
#ISCELL
  standard tap *
  page83_i137
#ISCELL
  standard tap *
  page83_i138
#ISCELL
  standard tap *
  page83_i139
#ISCELL
  standard offpage *
  page83_i14
#ISCELL
  standard tap *
  page83_i140
#ISCELL
  standard tap *
  page83_i141
#ISCELL
  standard tap *
  page83_i142
#ISCELL
  logical_power universal_gnd *
  page83_i143
#CELL
  pure_quanta q_cap *
  page83_i144
#ISCELL
  logical_power universal_gnd *
  page83_i145
#ISCELL
  standard tap *
  page83_i147
#ISCELL
  standard tap *
  page83_i148
#ISCELL
  standard tap *
  page83_i149
#ISCELL
  standard offpage *
  page83_i15
#ISCELL
  standard tap *
  page83_i150
#ISCELL
  standard tap *
  page83_i151
#ISCELL
  standard tap *
  page83_i152
#ISCELL
  standard tap *
  page83_i153
#ISCELL
  standard tap *
  page83_i154
#ISCELL
  standard tap *
  page83_i155
#ISCELL
  standard tap *
  page83_i156
#ISCELL
  standard tap *
  page83_i157
#ISCELL
  standard tap *
  page83_i158
#ISCELL
  standard tap *
  page83_i159
#ISCELL
  standard offpage *
  page83_i16
#ISCELL
  standard tap *
  page83_i160
#ISCELL
  standard tap *
  page83_i161
#ISCELL
  standard tap *
  page83_i162
#ISCELL
  standard tap *
  page83_i163
#ISCELL
  standard tap *
  page83_i164
#ISCELL
  standard offpage *
  page83_i165
#ISCELL
  standard offpage *
  page83_i166
#ISCELL
  standard offpage *
  page83_i167
#ISCELL
  standard tap *
  page83_i168
#ISCELL
  standard tap *
  page83_i169
#ISCELL
  standard offpage *
  page83_i17
#ISCELL
  standard tap *
  page83_i170
#ISCELL
  standard tap *
  page83_i171
#ISCELL
  standard tap *
  page83_i172
#ISCELL
  standard offpage *
  page83_i173
#ISCELL
  standard offpage *
  page83_i174
#ISCELL
  logical_power vcc_core *
  page83_i175
#ISCELL
  logical_power universal_gnd *
  page83_i176
#CELL
  pure_quanta sconn288_adr50017p087cc *
  page83_i177
#CELL
  pure_quanta sconn288_adr50017p087cc *
  page83_i179
#ISCELL
  standard offpage *
  page83_i18
#ISCELL
  standard offpage *
  page83_i180
#CELL
  pure_quanta sconn288_adr50017p087cc *
  page83_i181
#CELL
  pure_quanta q_res *
  page83_i182
#ISCELL
  standard offpage *
  page83_i183
#ISCELL
  standard offpage *
  page83_i19
#ISCELL
  standard offpage *
  page83_i2
#ISCELL
  standard offpage *
  page83_i20
#ISCELL
  standard offpage *
  page83_i21
#ISCELL
  standard offpage *
  page83_i22
#ISCELL
  standard offpage *
  page83_i23
#ISCELL
  standard tap *
  page83_i24
#ISCELL
  standard tap *
  page83_i25
#ISCELL
  standard tap *
  page83_i26
#ISCELL
  standard tap *
  page83_i27
#ISCELL
  standard tap *
  page83_i28
#ISCELL
  standard tap *
  page83_i29
#ISCELL
  standard offpage *
  page83_i3
#ISCELL
  standard tap *
  page83_i30
#ISCELL
  standard tap *
  page83_i31
#ISCELL
  standard tap *
  page83_i32
#ISCELL
  standard tap *
  page83_i33
#ISCELL
  standard tap *
  page83_i34
#ISCELL
  standard tap *
  page83_i35
#ISCELL
  standard tap *
  page83_i36
#ISCELL
  standard tap *
  page83_i37
#ISCELL
  standard tap *
  page83_i38
#ISCELL
  standard tap *
  page83_i39
#ISCELL
  standard offpage *
  page83_i4
#ISCELL
  standard tap *
  page83_i40
#ISCELL
  standard tap *
  page83_i41
#ISCELL
  standard tap *
  page83_i42
#ISCELL
  standard tap *
  page83_i43
#ISCELL
  standard tap *
  page83_i44
#ISCELL
  standard tap *
  page83_i45
#ISCELL
  standard tap *
  page83_i46
#ISCELL
  standard tap *
  page83_i47
#ISCELL
  standard tap *
  page83_i48
#ISCELL
  standard tap *
  page83_i49
#ISCELL
  standard tap *
  page83_i50
#ISCELL
  standard tap *
  page83_i51
#ISCELL
  standard tap *
  page83_i52
#ISCELL
  standard tap *
  page83_i53
#ISCELL
  standard tap *
  page83_i54
#ISCELL
  standard tap *
  page83_i55
#ISCELL
  standard tap *
  page83_i56
#ISCELL
  standard tap *
  page83_i57
#ISCELL
  standard tap *
  page83_i58
#ISCELL
  standard tap *
  page83_i59
#ISCELL
  standard offpage *
  page83_i6
#ISCELL
  standard tap *
  page83_i60
#ISCELL
  standard tap *
  page83_i61
#ISCELL
  standard tap *
  page83_i62
#ISCELL
  standard tap *
  page83_i63
#ISCELL
  standard tap *
  page83_i64
#ISCELL
  standard tap *
  page83_i65
#ISCELL
  standard tap *
  page83_i66
#ISCELL
  standard tap *
  page83_i67
#ISCELL
  standard tap *
  page83_i68
#ISCELL
  standard tap *
  page83_i69
#ISCELL
  standard offpage *
  page83_i7
#ISCELL
  standard tap *
  page83_i70
#ISCELL
  standard tap *
  page83_i71
#ISCELL
  standard tap *
  page83_i72
#ISCELL
  standard tap *
  page83_i73
#ISCELL
  standard tap *
  page83_i74
#ISCELL
  standard tap *
  page83_i75
#ISCELL
  standard tap *
  page83_i76
#ISCELL
  standard tap *
  page83_i77
#ISCELL
  standard tap *
  page83_i78
#ISCELL
  standard tap *
  page83_i79
#ISCELL
  standard offpage *
  page83_i8
#ISCELL
  standard tap *
  page83_i80
#ISCELL
  standard tap *
  page83_i81
#ISCELL
  standard tap *
  page83_i82
#ISCELL
  standard tap *
  page83_i83
#ISCELL
  standard tap *
  page83_i84
#ISCELL
  standard tap *
  page83_i85
#ISCELL
  standard tap *
  page83_i86
#ISCELL
  standard tap *
  page83_i87
#ISCELL
  standard tap *
  page83_i88
#ISCELL
  standard tap *
  page83_i89
#ISCELL
  standard offpage *
  page83_i9
#ISCELL
  standard tap *
  page83_i90
#ISCELL
  standard tap *
  page83_i91
#ISCELL
  standard tap *
  page83_i92
#ISCELL
  standard tap *
  page83_i93
#ISCELL
  standard tap *
  page83_i94
#ISCELL
  standard tap *
  page83_i95
#ISCELL
  standard tap *
  page83_i96
#ISCELL
  standard tap *
  page83_i97
#ISCELL
  standard tap *
  page83_i98
#ISCELL
  standard tap *
  page83_i99
#ISCELL
  logical_power cad_note *
  *
#ISCELL
  pure_quanta quanta_title_block_c *
  *
#ISCELL
  logical_power universal_gnd *
  page84_i1
#CELL
  pure_quanta q_res *
  page84_i10
#ISCELL
  standard tap *
  page84_i100
#ISCELL
  standard tap *
  page84_i101
#ISCELL
  standard tap *
  page84_i102
#ISCELL
  standard tap *
  page84_i103
#ISCELL
  standard tap *
  page84_i104
#ISCELL
  standard tap *
  page84_i105
#ISCELL
  standard tap *
  page84_i106
#ISCELL
  standard tap *
  page84_i107
#ISCELL
  standard offpage *
  page84_i108
#ISCELL
  standard tap *
  page84_i109
#ISCELL
  standard tap *
  page84_i110
#ISCELL
  standard tap *
  page84_i111
#ISCELL
  standard tap *
  page84_i112
#ISCELL
  standard tap *
  page84_i113
#ISCELL
  standard tap *
  page84_i114
#ISCELL
  standard tap *
  page84_i115
#ISCELL
  standard tap *
  page84_i116
#ISCELL
  standard tap *
  page84_i117
#ISCELL
  standard tap *
  page84_i118
#ISCELL
  logical_power vcc_core *
  page84_i119
#ISCELL
  standard offpage *
  page84_i12
#ISCELL
  logical_power universal_gnd *
  page84_i120
#CELL
  pure_quanta q_cap *
  page84_i121
#CELL
  pure_quanta q_cap *
  page84_i122
#ISCELL
  logical_power vcc_core *
  page84_i123
#ISCELL
  standard offpage *
  page84_i124
#ISCELL
  standard tap *
  page84_i126
#ISCELL
  standard tap *
  page84_i127
#ISCELL
  standard tap *
  page84_i128
#ISCELL
  standard tap *
  page84_i129
#ISCELL
  logical_power vcc_core *
  page84_i13
#ISCELL
  standard tap *
  page84_i130
#ISCELL
  standard tap *
  page84_i131
#ISCELL
  standard tap *
  page84_i132
#ISCELL
  standard tap *
  page84_i133
#ISCELL
  standard tap *
  page84_i134
#ISCELL
  standard tap *
  page84_i135
#ISCELL
  standard tap *
  page84_i136
#ISCELL
  standard tap *
  page84_i137
#ISCELL
  standard tap *
  page84_i138
#ISCELL
  standard tap *
  page84_i139
#ISCELL
  standard offpage *
  page84_i14
#ISCELL
  standard tap *
  page84_i140
#ISCELL
  standard tap *
  page84_i141
#ISCELL
  standard tap *
  page84_i142
#ISCELL
  logical_power universal_gnd *
  page84_i143
#CELL
  pure_quanta q_cap *
  page84_i144
#ISCELL
  logical_power universal_gnd *
  page84_i145
#ISCELL
  standard tap *
  page84_i147
#ISCELL
  standard tap *
  page84_i148
#ISCELL
  standard tap *
  page84_i149
#ISCELL
  standard offpage *
  page84_i15
#ISCELL
  standard tap *
  page84_i150
#ISCELL
  standard tap *
  page84_i151
#ISCELL
  standard tap *
  page84_i152
#ISCELL
  standard tap *
  page84_i153
#ISCELL
  standard tap *
  page84_i154
#ISCELL
  standard tap *
  page84_i155
#ISCELL
  standard tap *
  page84_i156
#ISCELL
  standard tap *
  page84_i157
#ISCELL
  standard tap *
  page84_i158
#ISCELL
  standard tap *
  page84_i159
#ISCELL
  standard offpage *
  page84_i16
#ISCELL
  standard tap *
  page84_i160
#ISCELL
  standard tap *
  page84_i161
#ISCELL
  standard tap *
  page84_i162
#ISCELL
  standard tap *
  page84_i163
#ISCELL
  standard tap *
  page84_i164
#ISCELL
  standard offpage *
  page84_i165
#ISCELL
  standard offpage *
  page84_i166
#ISCELL
  standard offpage *
  page84_i167
#ISCELL
  standard tap *
  page84_i168
#ISCELL
  standard tap *
  page84_i169
#ISCELL
  standard offpage *
  page84_i17
#ISCELL
  standard tap *
  page84_i170
#ISCELL
  standard tap *
  page84_i171
#ISCELL
  standard tap *
  page84_i172
#ISCELL
  standard offpage *
  page84_i173
#ISCELL
  standard offpage *
  page84_i174
#ISCELL
  logical_power vcc_core *
  page84_i175
#ISCELL
  logical_power universal_gnd *
  page84_i176
#ISCELL
  standard offpage *
  page84_i177
#CELL
  pure_quanta sconn288_adr50017p130cc *
  page84_i178
#CELL
  pure_quanta sconn288_adr50017p130cc *
  page84_i179
#ISCELL
  standard offpage *
  page84_i18
#CELL
  pure_quanta sconn288_adr50017p130cc *
  page84_i180
#CELL
  pure_quanta q_res *
  page84_i182
#ISCELL
  standard offpage *
  page84_i183
#ISCELL
  standard offpage *
  page84_i19
#ISCELL
  standard offpage *
  page84_i2
#ISCELL
  standard offpage *
  page84_i20
#ISCELL
  standard offpage *
  page84_i21
#ISCELL
  standard offpage *
  page84_i22
#ISCELL
  standard offpage *
  page84_i23
#ISCELL
  standard tap *
  page84_i24
#ISCELL
  standard tap *
  page84_i25
#ISCELL
  standard tap *
  page84_i26
#ISCELL
  standard tap *
  page84_i27
#ISCELL
  standard tap *
  page84_i28
#ISCELL
  standard tap *
  page84_i29
#ISCELL
  standard offpage *
  page84_i3
#ISCELL
  standard tap *
  page84_i30
#ISCELL
  standard tap *
  page84_i31
#ISCELL
  standard tap *
  page84_i32
#ISCELL
  standard tap *
  page84_i33
#ISCELL
  standard tap *
  page84_i34
#ISCELL
  standard tap *
  page84_i35
#ISCELL
  standard tap *
  page84_i36
#ISCELL
  standard tap *
  page84_i37
#ISCELL
  standard tap *
  page84_i38
#ISCELL
  standard tap *
  page84_i39
#ISCELL
  standard offpage *
  page84_i4
#ISCELL
  standard tap *
  page84_i40
#ISCELL
  standard tap *
  page84_i41
#ISCELL
  standard tap *
  page84_i42
#ISCELL
  standard tap *
  page84_i43
#ISCELL
  standard tap *
  page84_i44
#ISCELL
  standard tap *
  page84_i45
#ISCELL
  standard tap *
  page84_i46
#ISCELL
  standard tap *
  page84_i47
#ISCELL
  standard tap *
  page84_i48
#ISCELL
  standard tap *
  page84_i49
#ISCELL
  standard tap *
  page84_i50
#ISCELL
  standard tap *
  page84_i51
#ISCELL
  standard tap *
  page84_i52
#ISCELL
  standard tap *
  page84_i53
#ISCELL
  standard tap *
  page84_i54
#ISCELL
  standard tap *
  page84_i55
#ISCELL
  standard tap *
  page84_i56
#ISCELL
  standard tap *
  page84_i57
#ISCELL
  standard tap *
  page84_i58
#ISCELL
  standard tap *
  page84_i59
#ISCELL
  standard offpage *
  page84_i6
#ISCELL
  standard tap *
  page84_i60
#ISCELL
  standard tap *
  page84_i61
#ISCELL
  standard tap *
  page84_i62
#ISCELL
  standard tap *
  page84_i63
#ISCELL
  standard tap *
  page84_i64
#ISCELL
  standard tap *
  page84_i65
#ISCELL
  standard tap *
  page84_i66
#ISCELL
  standard tap *
  page84_i67
#ISCELL
  standard tap *
  page84_i68
#ISCELL
  standard tap *
  page84_i69
#ISCELL
  standard offpage *
  page84_i7
#ISCELL
  standard tap *
  page84_i70
#ISCELL
  standard tap *
  page84_i71
#ISCELL
  standard tap *
  page84_i72
#ISCELL
  standard tap *
  page84_i73
#ISCELL
  standard tap *
  page84_i74
#ISCELL
  standard tap *
  page84_i75
#ISCELL
  standard tap *
  page84_i76
#ISCELL
  standard tap *
  page84_i77
#ISCELL
  standard tap *
  page84_i78
#ISCELL
  standard tap *
  page84_i79
#ISCELL
  standard offpage *
  page84_i8
#ISCELL
  standard tap *
  page84_i80
#ISCELL
  standard tap *
  page84_i81
#ISCELL
  standard tap *
  page84_i82
#ISCELL
  standard tap *
  page84_i83
#ISCELL
  standard tap *
  page84_i84
#ISCELL
  standard tap *
  page84_i85
#ISCELL
  standard tap *
  page84_i86
#ISCELL
  standard tap *
  page84_i87
#ISCELL
  standard tap *
  page84_i88
#ISCELL
  standard tap *
  page84_i89
#ISCELL
  standard offpage *
  page84_i9
#ISCELL
  standard tap *
  page84_i90
#ISCELL
  standard tap *
  page84_i91
#ISCELL
  standard tap *
  page84_i92
#ISCELL
  standard tap *
  page84_i93
#ISCELL
  standard tap *
  page84_i94
#ISCELL
  standard tap *
  page84_i95
#ISCELL
  standard tap *
  page84_i96
#ISCELL
  standard tap *
  page84_i97
#ISCELL
  standard tap *
  page84_i98
#ISCELL
  standard tap *
  page84_i99
#ISCELL
  logical_power cad_note *
  *
#ISCELL
  pure_quanta quanta_title_block_c *
  *
#CELL
  pure_quanta q_res *
  page85_i1
#ISCELL
  standard offpage *
  page85_i10
#ISCELL
  standard tap *
  page85_i100
#ISCELL
  standard tap *
  page85_i101
#ISCELL
  standard tap *
  page85_i102
#ISCELL
  standard tap *
  page85_i103
#ISCELL
  standard tap *
  page85_i104
#ISCELL
  standard tap *
  page85_i105
#ISCELL
  standard tap *
  page85_i106
#ISCELL
  standard tap *
  page85_i107
#ISCELL
  standard tap *
  page85_i108
#ISCELL
  standard tap *
  page85_i109
#ISCELL
  logical_power vcc_core *
  page85_i11
#ISCELL
  standard tap *
  page85_i110
#ISCELL
  standard tap *
  page85_i111
#ISCELL
  standard offpage *
  page85_i112
#ISCELL
  standard tap *
  page85_i113
#ISCELL
  standard tap *
  page85_i114
#ISCELL
  standard tap *
  page85_i115
#ISCELL
  standard tap *
  page85_i116
#ISCELL
  standard tap *
  page85_i117
#ISCELL
  standard tap *
  page85_i118
#ISCELL
  logical_power universal_gnd *
  page85_i119
#ISCELL
  standard offpage *
  page85_i12
#ISCELL
  logical_power universal_gnd *
  page85_i120
#CELL
  pure_quanta q_cap *
  page85_i121
#ISCELL
  logical_power vcc_core *
  page85_i122
#ISCELL
  standard offpage *
  page85_i123
#CELL
  pure_quanta q_cap *
  page85_i125
#ISCELL
  logical_power vcc_core *
  page85_i126
#CELL
  pure_quanta q_cap *
  page85_i127
#ISCELL
  standard tap *
  page85_i128
#ISCELL
  standard tap *
  page85_i129
#ISCELL
  standard offpage *
  page85_i13
#ISCELL
  standard tap *
  page85_i130
#ISCELL
  standard tap *
  page85_i131
#ISCELL
  standard tap *
  page85_i132
#ISCELL
  standard tap *
  page85_i133
#ISCELL
  standard tap *
  page85_i134
#ISCELL
  standard tap *
  page85_i135
#ISCELL
  standard tap *
  page85_i136
#ISCELL
  standard tap *
  page85_i137
#ISCELL
  standard tap *
  page85_i138
#ISCELL
  standard tap *
  page85_i139
#ISCELL
  standard offpage *
  page85_i14
#ISCELL
  standard tap *
  page85_i140
#ISCELL
  standard tap *
  page85_i141
#ISCELL
  standard tap *
  page85_i142
#ISCELL
  standard tap *
  page85_i143
#ISCELL
  standard tap *
  page85_i144
#ISCELL
  standard tap *
  page85_i145
#ISCELL
  standard tap *
  page85_i146
#ISCELL
  standard tap *
  page85_i147
#ISCELL
  standard tap *
  page85_i148
#ISCELL
  standard tap *
  page85_i149
#ISCELL
  standard offpage *
  page85_i15
#ISCELL
  standard tap *
  page85_i150
#ISCELL
  standard tap *
  page85_i151
#ISCELL
  standard tap *
  page85_i152
#ISCELL
  standard tap *
  page85_i153
#ISCELL
  standard tap *
  page85_i154
#ISCELL
  standard tap *
  page85_i155
#ISCELL
  standard tap *
  page85_i156
#ISCELL
  standard tap *
  page85_i157
#ISCELL
  standard tap *
  page85_i158
#ISCELL
  standard tap *
  page85_i159
#ISCELL
  standard offpage *
  page85_i16
#ISCELL
  standard tap *
  page85_i160
#ISCELL
  standard tap *
  page85_i161
#ISCELL
  standard tap *
  page85_i162
#ISCELL
  standard tap *
  page85_i163
#ISCELL
  standard tap *
  page85_i164
#ISCELL
  standard offpage *
  page85_i165
#ISCELL
  standard offpage *
  page85_i166
#ISCELL
  standard offpage *
  page85_i167
#ISCELL
  standard tap *
  page85_i168
#ISCELL
  standard tap *
  page85_i169
#ISCELL
  standard offpage *
  page85_i17
#ISCELL
  standard tap *
  page85_i170
#ISCELL
  standard offpage *
  page85_i171
#ISCELL
  standard offpage *
  page85_i172
#ISCELL
  logical_power universal_gnd *
  page85_i173
#CELL
  pure_quanta sconn288_adr50017p087cc *
  page85_i174
#ISCELL
  logical_power universal_gnd *
  page85_i175
#ISCELL
  logical_power vcc_core *
  page85_i176
#ISCELL
  standard offpage *
  page85_i177
#CELL
  pure_quanta sconn288_adr50017p087cc *
  page85_i178
#ISCELL
  standard offpage *
  page85_i179
#ISCELL
  standard offpage *
  page85_i18
#CELL
  pure_quanta q_res *
  page85_i180
#ISCELL
  standard offpage *
  page85_i19
#ISCELL
  logical_power universal_gnd *
  page85_i2
#ISCELL
  standard offpage *
  page85_i20
#ISCELL
  standard offpage *
  page85_i21
#ISCELL
  standard offpage *
  page85_i22
#CELL
  pure_quanta sconn288_adr50017p087cc *
  page85_i23
#ISCELL
  standard tap *
  page85_i24
#ISCELL
  standard tap *
  page85_i25
#ISCELL
  standard tap *
  page85_i26
#ISCELL
  standard tap *
  page85_i27
#ISCELL
  standard tap *
  page85_i28
#ISCELL
  standard tap *
  page85_i29
#ISCELL
  standard offpage *
  page85_i3
#ISCELL
  standard tap *
  page85_i30
#ISCELL
  standard tap *
  page85_i31
#ISCELL
  standard tap *
  page85_i32
#ISCELL
  standard tap *
  page85_i33
#ISCELL
  standard tap *
  page85_i34
#ISCELL
  standard tap *
  page85_i35
#ISCELL
  standard tap *
  page85_i36
#ISCELL
  standard tap *
  page85_i37
#ISCELL
  standard tap *
  page85_i38
#ISCELL
  standard tap *
  page85_i39
#ISCELL
  standard offpage *
  page85_i4
#ISCELL
  standard tap *
  page85_i40
#ISCELL
  standard tap *
  page85_i41
#ISCELL
  standard tap *
  page85_i42
#ISCELL
  standard tap *
  page85_i43
#ISCELL
  standard tap *
  page85_i44
#ISCELL
  standard tap *
  page85_i45
#ISCELL
  standard tap *
  page85_i46
#ISCELL
  standard tap *
  page85_i47
#ISCELL
  standard tap *
  page85_i48
#ISCELL
  standard tap *
  page85_i49
#ISCELL
  standard offpage *
  page85_i5
#ISCELL
  standard tap *
  page85_i50
#ISCELL
  standard tap *
  page85_i51
#ISCELL
  standard tap *
  page85_i52
#ISCELL
  standard tap *
  page85_i53
#ISCELL
  standard tap *
  page85_i54
#ISCELL
  standard tap *
  page85_i55
#ISCELL
  standard tap *
  page85_i56
#ISCELL
  standard tap *
  page85_i57
#ISCELL
  standard tap *
  page85_i58
#ISCELL
  standard tap *
  page85_i59
#ISCELL
  standard tap *
  page85_i60
#ISCELL
  standard tap *
  page85_i61
#ISCELL
  standard tap *
  page85_i62
#ISCELL
  standard tap *
  page85_i63
#ISCELL
  standard tap *
  page85_i64
#ISCELL
  standard tap *
  page85_i65
#ISCELL
  standard tap *
  page85_i66
#ISCELL
  standard tap *
  page85_i67
#ISCELL
  standard tap *
  page85_i68
#ISCELL
  standard tap *
  page85_i69
#ISCELL
  standard offpage *
  page85_i7
#ISCELL
  standard tap *
  page85_i70
#ISCELL
  standard tap *
  page85_i71
#ISCELL
  standard tap *
  page85_i72
#ISCELL
  standard tap *
  page85_i73
#ISCELL
  standard tap *
  page85_i74
#ISCELL
  standard tap *
  page85_i75
#ISCELL
  standard tap *
  page85_i76
#ISCELL
  standard tap *
  page85_i77
#ISCELL
  standard tap *
  page85_i78
#ISCELL
  standard tap *
  page85_i79
#ISCELL
  standard offpage *
  page85_i8
#ISCELL
  standard tap *
  page85_i80
#ISCELL
  standard tap *
  page85_i81
#ISCELL
  standard tap *
  page85_i82
#ISCELL
  standard tap *
  page85_i83
#ISCELL
  standard tap *
  page85_i84
#ISCELL
  standard tap *
  page85_i85
#ISCELL
  standard tap *
  page85_i86
#ISCELL
  standard tap *
  page85_i87
#ISCELL
  standard tap *
  page85_i88
#ISCELL
  standard tap *
  page85_i89
#ISCELL
  standard offpage *
  page85_i9
#ISCELL
  standard tap *
  page85_i90
#ISCELL
  standard tap *
  page85_i91
#ISCELL
  standard tap *
  page85_i92
#ISCELL
  standard tap *
  page85_i93
#ISCELL
  standard tap *
  page85_i94
#ISCELL
  standard tap *
  page85_i95
#ISCELL
  standard tap *
  page85_i96
#ISCELL
  standard tap *
  page85_i97
#ISCELL
  standard tap *
  page85_i98
#ISCELL
  standard tap *
  page85_i99
#ISCELL
  logical_power cad_note *
  *
#ISCELL
  pure_quanta quanta_title_block_c *
  *
#ISCELL
  standard offpage *
  page86_i1
#ISCELL
  standard offpage *
  page86_i10
#ISCELL
  standard tap *
  page86_i100
#ISCELL
  standard tap *
  page86_i101
#ISCELL
  standard tap *
  page86_i102
#ISCELL
  standard tap *
  page86_i103
#ISCELL
  standard tap *
  page86_i104
#ISCELL
  standard tap *
  page86_i105
#ISCELL
  standard tap *
  page86_i106
#ISCELL
  standard tap *
  page86_i107
#ISCELL
  standard tap *
  page86_i108
#ISCELL
  standard tap *
  page86_i109
#ISCELL
  standard offpage *
  page86_i11
#ISCELL
  standard tap *
  page86_i110
#ISCELL
  standard tap *
  page86_i111
#ISCELL
  standard tap *
  page86_i112
#ISCELL
  standard tap *
  page86_i113
#ISCELL
  standard tap *
  page86_i114
#ISCELL
  standard tap *
  page86_i115
#ISCELL
  standard tap *
  page86_i116
#ISCELL
  standard tap *
  page86_i117
#ISCELL
  standard tap *
  page86_i118
#ISCELL
  logical_power universal_gnd *
  page86_i119
#ISCELL
  logical_power vcc_core *
  page86_i12
#CELL
  pure_quanta q_cap *
  page86_i120
#CELL
  pure_quanta q_cap *
  page86_i121
#ISCELL
  logical_power universal_gnd *
  page86_i122
#CELL
  pure_quanta q_cap *
  page86_i123
#ISCELL
  logical_power vcc_core *
  page86_i124
#ISCELL
  standard offpage *
  page86_i126
#ISCELL
  standard offpage *
  page86_i127
#ISCELL
  logical_power vcc_core *
  page86_i128
#ISCELL
  standard tap *
  page86_i129
#ISCELL
  standard offpage *
  page86_i13
#ISCELL
  standard tap *
  page86_i130
#ISCELL
  standard tap *
  page86_i131
#ISCELL
  standard tap *
  page86_i132
#ISCELL
  standard tap *
  page86_i133
#ISCELL
  standard tap *
  page86_i134
#ISCELL
  standard tap *
  page86_i135
#ISCELL
  standard tap *
  page86_i136
#ISCELL
  standard tap *
  page86_i137
#ISCELL
  standard tap *
  page86_i138
#ISCELL
  standard tap *
  page86_i139
#ISCELL
  standard offpage *
  page86_i14
#ISCELL
  standard tap *
  page86_i140
#ISCELL
  standard tap *
  page86_i141
#ISCELL
  standard tap *
  page86_i142
#ISCELL
  standard tap *
  page86_i143
#ISCELL
  standard tap *
  page86_i144
#ISCELL
  standard tap *
  page86_i145
#ISCELL
  standard tap *
  page86_i146
#ISCELL
  standard tap *
  page86_i147
#ISCELL
  standard tap *
  page86_i148
#ISCELL
  standard tap *
  page86_i149
#ISCELL
  standard offpage *
  page86_i15
#ISCELL
  standard tap *
  page86_i150
#ISCELL
  standard tap *
  page86_i151
#ISCELL
  standard tap *
  page86_i152
#ISCELL
  standard tap *
  page86_i153
#ISCELL
  standard tap *
  page86_i154
#ISCELL
  standard tap *
  page86_i155
#ISCELL
  standard tap *
  page86_i156
#ISCELL
  standard tap *
  page86_i157
#ISCELL
  standard tap *
  page86_i158
#ISCELL
  standard tap *
  page86_i159
#ISCELL
  standard offpage *
  page86_i16
#ISCELL
  standard tap *
  page86_i160
#ISCELL
  standard tap *
  page86_i161
#ISCELL
  standard tap *
  page86_i162
#ISCELL
  standard tap *
  page86_i163
#ISCELL
  standard tap *
  page86_i164
#ISCELL
  standard tap *
  page86_i165
#ISCELL
  standard tap *
  page86_i166
#ISCELL
  standard tap *
  page86_i167
#ISCELL
  standard tap *
  page86_i168
#ISCELL
  standard offpage *
  page86_i169
#ISCELL
  standard offpage *
  page86_i17
#ISCELL
  standard offpage *
  page86_i170
#ISCELL
  standard offpage *
  page86_i171
#ISCELL
  standard offpage *
  page86_i172
#ISCELL
  logical_power universal_gnd *
  page86_i173
#CELL
  pure_quanta sconn288_adr50017p130cc *
  page86_i174
#ISCELL
  logical_power universal_gnd *
  page86_i175
#ISCELL
  logical_power vcc_core *
  page86_i176
#ISCELL
  standard offpage *
  page86_i177
#CELL
  pure_quanta sconn288_adr50017p130cc *
  page86_i178
#ISCELL
  standard offpage *
  page86_i179
#ISCELL
  standard offpage *
  page86_i18
#CELL
  pure_quanta q_res *
  page86_i180
#ISCELL
  standard offpage *
  page86_i19
#ISCELL
  logical_power universal_gnd *
  page86_i2
#ISCELL
  standard offpage *
  page86_i20
#ISCELL
  standard offpage *
  page86_i21
#ISCELL
  standard offpage *
  page86_i22
#ISCELL
  standard offpage *
  page86_i23
#CELL
  pure_quanta sconn288_adr50017p130cc *
  page86_i24
#ISCELL
  standard tap *
  page86_i25
#ISCELL
  standard tap *
  page86_i26
#ISCELL
  standard tap *
  page86_i27
#ISCELL
  standard tap *
  page86_i28
#ISCELL
  standard tap *
  page86_i29
#CELL
  pure_quanta q_res *
  page86_i3
#ISCELL
  standard tap *
  page86_i30
#ISCELL
  standard tap *
  page86_i31
#ISCELL
  standard tap *
  page86_i32
#ISCELL
  standard tap *
  page86_i33
#ISCELL
  standard tap *
  page86_i34
#ISCELL
  standard tap *
  page86_i35
#ISCELL
  standard tap *
  page86_i36
#ISCELL
  standard tap *
  page86_i37
#ISCELL
  standard tap *
  page86_i38
#ISCELL
  standard tap *
  page86_i39
#ISCELL
  standard offpage *
  page86_i4
#ISCELL
  standard tap *
  page86_i40
#ISCELL
  standard tap *
  page86_i41
#ISCELL
  standard tap *
  page86_i42
#ISCELL
  standard tap *
  page86_i43
#ISCELL
  standard tap *
  page86_i44
#ISCELL
  standard tap *
  page86_i45
#ISCELL
  standard tap *
  page86_i46
#ISCELL
  standard tap *
  page86_i47
#ISCELL
  standard tap *
  page86_i48
#ISCELL
  standard tap *
  page86_i49
#ISCELL
  standard offpage *
  page86_i5
#ISCELL
  standard tap *
  page86_i50
#ISCELL
  standard tap *
  page86_i51
#ISCELL
  standard tap *
  page86_i52
#ISCELL
  standard tap *
  page86_i53
#ISCELL
  standard tap *
  page86_i54
#ISCELL
  standard tap *
  page86_i55
#ISCELL
  standard tap *
  page86_i56
#ISCELL
  standard tap *
  page86_i57
#ISCELL
  standard tap *
  page86_i58
#ISCELL
  standard tap *
  page86_i59
#ISCELL
  standard tap *
  page86_i60
#ISCELL
  standard tap *
  page86_i61
#ISCELL
  standard tap *
  page86_i62
#ISCELL
  standard tap *
  page86_i63
#ISCELL
  standard tap *
  page86_i64
#ISCELL
  standard tap *
  page86_i65
#ISCELL
  standard tap *
  page86_i66
#ISCELL
  standard tap *
  page86_i67
#ISCELL
  standard tap *
  page86_i68
#ISCELL
  standard tap *
  page86_i69
#ISCELL
  standard offpage *
  page86_i7
#ISCELL
  standard tap *
  page86_i70
#ISCELL
  standard tap *
  page86_i71
#ISCELL
  standard tap *
  page86_i72
#ISCELL
  standard tap *
  page86_i73
#ISCELL
  standard tap *
  page86_i74
#ISCELL
  standard tap *
  page86_i75
#ISCELL
  standard tap *
  page86_i76
#ISCELL
  standard tap *
  page86_i77
#ISCELL
  standard tap *
  page86_i78
#ISCELL
  standard tap *
  page86_i79
#ISCELL
  standard offpage *
  page86_i8
#ISCELL
  standard tap *
  page86_i80
#ISCELL
  standard tap *
  page86_i81
#ISCELL
  standard tap *
  page86_i82
#ISCELL
  standard tap *
  page86_i83
#ISCELL
  standard tap *
  page86_i84
#ISCELL
  standard tap *
  page86_i85
#ISCELL
  standard tap *
  page86_i86
#ISCELL
  standard tap *
  page86_i87
#ISCELL
  standard tap *
  page86_i88
#ISCELL
  standard tap *
  page86_i89
#ISCELL
  standard offpage *
  page86_i9
#ISCELL
  standard tap *
  page86_i90
#ISCELL
  standard tap *
  page86_i91
#ISCELL
  standard tap *
  page86_i92
#ISCELL
  standard tap *
  page86_i93
#ISCELL
  standard tap *
  page86_i94
#ISCELL
  standard tap *
  page86_i95
#ISCELL
  standard tap *
  page86_i96
#ISCELL
  standard tap *
  page86_i97
#ISCELL
  standard tap *
  page86_i98
#ISCELL
  standard tap *
  page86_i99
#ISCELL
  logical_power cad_note *
  *
#ISCELL
  pure_quanta quanta_title_block_c *
  *
#ISCELL
  standard offpage *
  page87_i1
#ISCELL
  standard offpage *
  page87_i10
#ISCELL
  standard tap *
  page87_i100
#ISCELL
  standard tap *
  page87_i101
#ISCELL
  standard tap *
  page87_i102
#ISCELL
  standard tap *
  page87_i103
#ISCELL
  standard offpage *
  page87_i104
#ISCELL
  standard tap *
  page87_i105
#ISCELL
  standard tap *
  page87_i106
#ISCELL
  standard tap *
  page87_i107
#ISCELL
  standard tap *
  page87_i108
#ISCELL
  standard tap *
  page87_i109
#ISCELL
  standard offpage *
  page87_i11
#ISCELL
  standard tap *
  page87_i110
#ISCELL
  standard tap *
  page87_i111
#ISCELL
  standard tap *
  page87_i112
#ISCELL
  standard tap *
  page87_i113
#ISCELL
  standard tap *
  page87_i114
#ISCELL
  standard tap *
  page87_i115
#ISCELL
  standard tap *
  page87_i116
#ISCELL
  standard tap *
  page87_i117
#ISCELL
  standard tap *
  page87_i118
#ISCELL
  logical_power universal_gnd *
  page87_i119
#ISCELL
  standard offpage *
  page87_i12
#CELL
  pure_quanta q_cap *
  page87_i120
#ISCELL
  logical_power vcc_core *
  page87_i121
#ISCELL
  standard offpage *
  page87_i122
#CELL
  pure_quanta q_cap *
  page87_i124
#ISCELL
  logical_power vcc_core *
  page87_i125
#ISCELL
  logical_power universal_gnd *
  page87_i126
#CELL
  pure_quanta q_cap *
  page87_i127
#ISCELL
  logical_power universal_gnd *
  page87_i128
#ISCELL
  standard tap *
  page87_i129
#ISCELL
  standard offpage *
  page87_i13
#ISCELL
  standard tap *
  page87_i130
#ISCELL
  standard tap *
  page87_i131
#ISCELL
  standard tap *
  page87_i132
#ISCELL
  standard tap *
  page87_i133
#ISCELL
  standard tap *
  page87_i134
#ISCELL
  standard tap *
  page87_i135
#ISCELL
  standard tap *
  page87_i136
#ISCELL
  standard tap *
  page87_i137
#ISCELL
  standard tap *
  page87_i138
#ISCELL
  standard tap *
  page87_i139
#ISCELL
  standard offpage *
  page87_i14
#ISCELL
  standard tap *
  page87_i140
#ISCELL
  standard tap *
  page87_i141
#ISCELL
  standard tap *
  page87_i142
#ISCELL
  standard tap *
  page87_i143
#ISCELL
  standard tap *
  page87_i144
#ISCELL
  standard tap *
  page87_i145
#ISCELL
  standard tap *
  page87_i146
#ISCELL
  standard tap *
  page87_i147
#ISCELL
  standard tap *
  page87_i148
#ISCELL
  standard tap *
  page87_i149
#ISCELL
  standard offpage *
  page87_i15
#ISCELL
  standard tap *
  page87_i150
#ISCELL
  standard tap *
  page87_i151
#ISCELL
  standard tap *
  page87_i152
#ISCELL
  standard tap *
  page87_i153
#ISCELL
  standard tap *
  page87_i154
#ISCELL
  standard tap *
  page87_i155
#ISCELL
  standard tap *
  page87_i156
#ISCELL
  standard tap *
  page87_i157
#ISCELL
  standard tap *
  page87_i158
#ISCELL
  standard tap *
  page87_i159
#ISCELL
  standard offpage *
  page87_i16
#ISCELL
  standard tap *
  page87_i160
#ISCELL
  standard tap *
  page87_i161
#ISCELL
  standard offpage *
  page87_i162
#ISCELL
  standard offpage *
  page87_i163
#ISCELL
  standard offpage *
  page87_i164
#ISCELL
  standard tap *
  page87_i165
#ISCELL
  standard tap *
  page87_i166
#ISCELL
  standard tap *
  page87_i167
#ISCELL
  standard tap *
  page87_i168
#ISCELL
  standard tap *
  page87_i169
#ISCELL
  standard offpage *
  page87_i17
#ISCELL
  standard tap *
  page87_i170
#ISCELL
  standard tap *
  page87_i171
#ISCELL
  standard offpage *
  page87_i172
#ISCELL
  standard offpage *
  page87_i173
#ISCELL
  logical_power vcc_core *
  page87_i174
#CELL
  pure_quanta sconn288_adr50017p087cc *
  page87_i175
#ISCELL
  logical_power universal_gnd *
  page87_i176
#ISCELL
  standard offpage *
  page87_i177
#CELL
  pure_quanta sconn288_adr50017p087cc *
  page87_i178
#ISCELL
  standard offpage *
  page87_i179
#ISCELL
  standard offpage *
  page87_i18
#CELL
  pure_quanta q_res *
  page87_i180
#ISCELL
  standard offpage *
  page87_i19
#ISCELL
  standard offpage *
  page87_i2
#ISCELL
  logical_power vcc_core *
  page87_i20
#ISCELL
  standard tap *
  page87_i21
#ISCELL
  standard tap *
  page87_i22
#ISCELL
  standard tap *
  page87_i23
#ISCELL
  standard tap *
  page87_i24
#ISCELL
  standard tap *
  page87_i25
#ISCELL
  standard tap *
  page87_i26
#ISCELL
  standard tap *
  page87_i27
#ISCELL
  standard tap *
  page87_i28
#ISCELL
  standard tap *
  page87_i29
#ISCELL
  standard offpage *
  page87_i3
#ISCELL
  standard tap *
  page87_i30
#ISCELL
  standard tap *
  page87_i31
#ISCELL
  standard tap *
  page87_i32
#ISCELL
  standard tap *
  page87_i33
#ISCELL
  standard tap *
  page87_i34
#ISCELL
  standard tap *
  page87_i35
#ISCELL
  standard tap *
  page87_i36
#ISCELL
  standard tap *
  page87_i37
#ISCELL
  standard tap *
  page87_i38
#ISCELL
  standard tap *
  page87_i39
#ISCELL
  standard tap *
  page87_i40
#ISCELL
  standard tap *
  page87_i41
#ISCELL
  standard tap *
  page87_i42
#ISCELL
  standard tap *
  page87_i43
#ISCELL
  logical_power universal_gnd *
  page87_i44
#CELL
  pure_quanta q_res *
  page87_i45
#CELL
  pure_quanta sconn288_adr50017p087cc *
  page87_i46
#ISCELL
  standard tap *
  page87_i47
#ISCELL
  standard tap *
  page87_i48
#ISCELL
  standard tap *
  page87_i49
#ISCELL
  standard offpage *
  page87_i5
#ISCELL
  standard tap *
  page87_i50
#ISCELL
  standard tap *
  page87_i51
#ISCELL
  standard tap *
  page87_i52
#ISCELL
  standard tap *
  page87_i53
#ISCELL
  standard tap *
  page87_i54
#ISCELL
  standard tap *
  page87_i55
#ISCELL
  standard tap *
  page87_i56
#ISCELL
  standard tap *
  page87_i57
#ISCELL
  standard tap *
  page87_i58
#ISCELL
  standard tap *
  page87_i59
#ISCELL
  standard offpage *
  page87_i6
#ISCELL
  standard tap *
  page87_i60
#ISCELL
  standard tap *
  page87_i61
#ISCELL
  standard tap *
  page87_i62
#ISCELL
  standard tap *
  page87_i63
#ISCELL
  standard tap *
  page87_i64
#ISCELL
  standard tap *
  page87_i65
#ISCELL
  standard tap *
  page87_i66
#ISCELL
  standard tap *
  page87_i67
#ISCELL
  standard tap *
  page87_i68
#ISCELL
  standard tap *
  page87_i69
#ISCELL
  standard offpage *
  page87_i7
#ISCELL
  standard tap *
  page87_i70
#ISCELL
  standard tap *
  page87_i71
#ISCELL
  standard tap *
  page87_i72
#ISCELL
  standard tap *
  page87_i73
#ISCELL
  standard tap *
  page87_i74
#ISCELL
  standard tap *
  page87_i75
#ISCELL
  standard tap *
  page87_i76
#ISCELL
  standard tap *
  page87_i77
#ISCELL
  standard tap *
  page87_i78
#ISCELL
  standard tap *
  page87_i79
#ISCELL
  standard offpage *
  page87_i8
#ISCELL
  standard tap *
  page87_i80
#ISCELL
  standard tap *
  page87_i81
#ISCELL
  standard tap *
  page87_i82
#ISCELL
  standard tap *
  page87_i83
#ISCELL
  standard tap *
  page87_i84
#ISCELL
  standard tap *
  page87_i85
#ISCELL
  standard tap *
  page87_i86
#ISCELL
  standard tap *
  page87_i87
#ISCELL
  standard tap *
  page87_i88
#ISCELL
  standard tap *
  page87_i89
#ISCELL
  standard offpage *
  page87_i9
#ISCELL
  standard tap *
  page87_i90
#ISCELL
  standard tap *
  page87_i91
#ISCELL
  standard tap *
  page87_i92
#ISCELL
  standard tap *
  page87_i93
#ISCELL
  standard tap *
  page87_i94
#ISCELL
  standard tap *
  page87_i95
#ISCELL
  standard tap *
  page87_i96
#ISCELL
  standard tap *
  page87_i97
#ISCELL
  standard tap *
  page87_i98
#ISCELL
  standard tap *
  page87_i99
#ISCELL
  logical_power cad_note *
  *
#ISCELL
  pure_quanta quanta_title_block_c *
  *
#ISCELL
  logical_power universal_gnd *
  page88_i1
#ISCELL
  standard offpage *
  page88_i10
#ISCELL
  standard tap *
  page88_i100
#ISCELL
  standard tap *
  page88_i101
#ISCELL
  standard tap *
  page88_i102
#ISCELL
  standard tap *
  page88_i103
#ISCELL
  standard tap *
  page88_i104
#ISCELL
  standard tap *
  page88_i105
#ISCELL
  standard tap *
  page88_i106
#ISCELL
  standard tap *
  page88_i107
#ISCELL
  standard tap *
  page88_i108
#ISCELL
  standard tap *
  page88_i109
#ISCELL
  logical_power vcc_core *
  page88_i11
#ISCELL
  standard tap *
  page88_i110
#ISCELL
  standard tap *
  page88_i111
#ISCELL
  standard tap *
  page88_i112
#ISCELL
  standard tap *
  page88_i113
#ISCELL
  standard offpage *
  page88_i114
#ISCELL
  standard offpage *
  page88_i115
#ISCELL
  standard tap *
  page88_i116
#ISCELL
  standard tap *
  page88_i117
#ISCELL
  standard tap *
  page88_i118
#ISCELL
  standard tap *
  page88_i119
#CELL
  pure_quanta sconn288_adr50017p130cc *
  page88_i12
#ISCELL
  standard offpage *
  page88_i120
#ISCELL
  logical_power universal_gnd *
  page88_i121
#ISCELL
  logical_power universal_gnd *
  page88_i122
#CELL
  pure_quanta q_cap *
  page88_i123
#ISCELL
  logical_power vcc_core *
  page88_i124
#CELL
  pure_quanta q_cap *
  page88_i126
#ISCELL
  logical_power vcc_core *
  page88_i127
#ISCELL
  standard tap *
  page88_i128
#ISCELL
  standard tap *
  page88_i129
#ISCELL
  standard tap *
  page88_i13
#ISCELL
  standard tap *
  page88_i130
#ISCELL
  standard tap *
  page88_i131
#ISCELL
  standard tap *
  page88_i132
#ISCELL
  standard tap *
  page88_i133
#ISCELL
  standard tap *
  page88_i134
#ISCELL
  standard tap *
  page88_i135
#ISCELL
  standard tap *
  page88_i136
#ISCELL
  standard tap *
  page88_i137
#ISCELL
  standard tap *
  page88_i138
#ISCELL
  standard tap *
  page88_i139
#ISCELL
  standard tap *
  page88_i14
#ISCELL
  standard tap *
  page88_i140
#ISCELL
  standard tap *
  page88_i141
#ISCELL
  standard tap *
  page88_i142
#ISCELL
  standard tap *
  page88_i143
#ISCELL
  standard tap *
  page88_i144
#ISCELL
  standard tap *
  page88_i145
#ISCELL
  standard tap *
  page88_i146
#ISCELL
  standard tap *
  page88_i147
#ISCELL
  standard tap *
  page88_i148
#ISCELL
  standard tap *
  page88_i149
#ISCELL
  standard offpage *
  page88_i15
#ISCELL
  standard tap *
  page88_i150
#ISCELL
  standard tap *
  page88_i151
#ISCELL
  standard tap *
  page88_i152
#ISCELL
  standard tap *
  page88_i153
#ISCELL
  standard tap *
  page88_i154
#ISCELL
  standard tap *
  page88_i155
#ISCELL
  standard tap *
  page88_i156
#ISCELL
  standard tap *
  page88_i157
#ISCELL
  standard tap *
  page88_i158
#ISCELL
  standard tap *
  page88_i159
#ISCELL
  standard offpage *
  page88_i16
#ISCELL
  standard tap *
  page88_i160
#ISCELL
  standard tap *
  page88_i161
#ISCELL
  standard tap *
  page88_i162
#ISCELL
  standard tap *
  page88_i163
#ISCELL
  standard tap *
  page88_i164
#ISCELL
  standard tap *
  page88_i165
#CELL
  pure_quanta q_cap *
  page88_i166
#ISCELL
  logical_power universal_gnd *
  page88_i167
#CELL
  pure_quanta sconn288_adr50017p130cc *
  page88_i168
#ISCELL
  standard offpage *
  page88_i169
#ISCELL
  standard offpage *
  page88_i17
#ISCELL
  standard offpage *
  page88_i170
#ISCELL
  standard offpage *
  page88_i171
#ISCELL
  standard tap *
  page88_i172
#ISCELL
  standard tap *
  page88_i173
#ISCELL
  standard offpage *
  page88_i174
#ISCELL
  logical_power vcc_core *
  page88_i175
#ISCELL
  logical_power universal_gnd *
  page88_i176
#ISCELL
  standard offpage *
  page88_i177
#CELL
  pure_quanta sconn288_adr50017p130cc *
  page88_i178
#ISCELL
  standard offpage *
  page88_i179
#ISCELL
  standard offpage *
  page88_i18
#CELL
  pure_quanta q_res *
  page88_i180
#ISCELL
  standard offpage *
  page88_i19
#CELL
  pure_quanta q_res *
  page88_i2
#ISCELL
  standard offpage *
  page88_i20
#ISCELL
  standard offpage *
  page88_i21
#ISCELL
  standard offpage *
  page88_i22
#ISCELL
  standard offpage *
  page88_i23
#ISCELL
  standard offpage *
  page88_i24
#ISCELL
  standard offpage *
  page88_i25
#ISCELL
  standard tap *
  page88_i26
#ISCELL
  standard tap *
  page88_i27
#ISCELL
  standard tap *
  page88_i28
#ISCELL
  standard tap *
  page88_i29
#ISCELL
  standard offpage *
  page88_i3
#ISCELL
  standard tap *
  page88_i30
#ISCELL
  standard tap *
  page88_i31
#ISCELL
  standard tap *
  page88_i32
#ISCELL
  standard tap *
  page88_i33
#ISCELL
  standard tap *
  page88_i34
#ISCELL
  standard tap *
  page88_i35
#ISCELL
  standard tap *
  page88_i36
#ISCELL
  standard tap *
  page88_i37
#ISCELL
  standard tap *
  page88_i38
#ISCELL
  standard tap *
  page88_i39
#ISCELL
  standard offpage *
  page88_i4
#ISCELL
  standard tap *
  page88_i40
#ISCELL
  standard tap *
  page88_i41
#ISCELL
  standard tap *
  page88_i42
#ISCELL
  standard tap *
  page88_i43
#ISCELL
  standard tap *
  page88_i44
#ISCELL
  standard tap *
  page88_i45
#ISCELL
  standard tap *
  page88_i46
#ISCELL
  standard tap *
  page88_i47
#ISCELL
  standard tap *
  page88_i48
#ISCELL
  standard tap *
  page88_i49
#ISCELL
  standard offpage *
  page88_i5
#ISCELL
  standard tap *
  page88_i50
#ISCELL
  standard tap *
  page88_i51
#ISCELL
  standard tap *
  page88_i52
#ISCELL
  standard tap *
  page88_i53
#ISCELL
  standard tap *
  page88_i54
#ISCELL
  standard tap *
  page88_i55
#ISCELL
  standard tap *
  page88_i56
#ISCELL
  standard tap *
  page88_i57
#ISCELL
  standard tap *
  page88_i58
#ISCELL
  standard tap *
  page88_i59
#ISCELL
  standard tap *
  page88_i60
#ISCELL
  standard tap *
  page88_i61
#ISCELL
  standard tap *
  page88_i62
#ISCELL
  standard tap *
  page88_i63
#ISCELL
  standard tap *
  page88_i64
#ISCELL
  standard tap *
  page88_i65
#ISCELL
  standard tap *
  page88_i66
#ISCELL
  standard tap *
  page88_i67
#ISCELL
  standard tap *
  page88_i68
#ISCELL
  standard tap *
  page88_i69
#ISCELL
  standard offpage *
  page88_i7
#ISCELL
  standard tap *
  page88_i70
#ISCELL
  standard tap *
  page88_i71
#ISCELL
  standard tap *
  page88_i72
#ISCELL
  standard tap *
  page88_i73
#ISCELL
  standard tap *
  page88_i74
#ISCELL
  standard tap *
  page88_i75
#ISCELL
  standard tap *
  page88_i76
#ISCELL
  standard tap *
  page88_i77
#ISCELL
  standard tap *
  page88_i78
#ISCELL
  standard tap *
  page88_i79
#ISCELL
  standard offpage *
  page88_i8
#ISCELL
  standard tap *
  page88_i80
#ISCELL
  standard tap *
  page88_i81
#ISCELL
  standard tap *
  page88_i82
#ISCELL
  standard tap *
  page88_i83
#ISCELL
  standard tap *
  page88_i84
#ISCELL
  standard tap *
  page88_i85
#ISCELL
  standard tap *
  page88_i86
#ISCELL
  standard tap *
  page88_i87
#ISCELL
  standard tap *
  page88_i88
#ISCELL
  standard tap *
  page88_i89
#ISCELL
  standard offpage *
  page88_i9
#ISCELL
  standard tap *
  page88_i90
#ISCELL
  standard tap *
  page88_i91
#ISCELL
  standard tap *
  page88_i92
#ISCELL
  standard tap *
  page88_i93
#ISCELL
  standard tap *
  page88_i94
#ISCELL
  standard tap *
  page88_i95
#ISCELL
  standard tap *
  page88_i96
#ISCELL
  standard tap *
  page88_i97
#ISCELL
  standard tap *
  page88_i98
#ISCELL
  standard tap *
  page88_i99
#ISCELL
  logical_power cad_note *
  *
#ISCELL
  pure_quanta quanta_title_block_c *
  *
#ISCELL
  logical_power universal_gnd *
  page89_i1
#ISCELL
  standard offpage *
  page89_i10
#ISCELL
  standard tap *
  page89_i100
#ISCELL
  standard tap *
  page89_i101
#ISCELL
  standard tap *
  page89_i102
#ISCELL
  standard tap *
  page89_i103
#ISCELL
  standard tap *
  page89_i104
#ISCELL
  standard tap *
  page89_i105
#ISCELL
  standard tap *
  page89_i106
#ISCELL
  standard tap *
  page89_i107
#ISCELL
  standard tap *
  page89_i108
#ISCELL
  standard tap *
  page89_i109
#ISCELL
  logical_power vcc_core *
  page89_i11
#ISCELL
  standard tap *
  page89_i110
#ISCELL
  standard tap *
  page89_i111
#ISCELL
  standard offpage *
  page89_i112
#ISCELL
  standard tap *
  page89_i113
#ISCELL
  standard tap *
  page89_i114
#ISCELL
  standard tap *
  page89_i115
#ISCELL
  standard tap *
  page89_i116
#ISCELL
  standard tap *
  page89_i117
#ISCELL
  standard tap *
  page89_i118
#ISCELL
  logical_power universal_gnd *
  page89_i119
#ISCELL
  standard tap *
  page89_i12
#ISCELL
  logical_power universal_gnd *
  page89_i120
#CELL
  pure_quanta q_cap *
  page89_i121
#ISCELL
  logical_power vcc_core *
  page89_i122
#ISCELL
  standard offpage *
  page89_i123
#CELL
  pure_quanta q_cap *
  page89_i125
#ISCELL
  logical_power vcc_core *
  page89_i126
#CELL
  pure_quanta q_cap *
  page89_i127
#ISCELL
  logical_power universal_gnd *
  page89_i128
#ISCELL
  standard tap *
  page89_i129
#ISCELL
  standard offpage *
  page89_i13
#ISCELL
  standard tap *
  page89_i130
#ISCELL
  standard tap *
  page89_i131
#ISCELL
  standard tap *
  page89_i132
#ISCELL
  standard tap *
  page89_i133
#ISCELL
  standard tap *
  page89_i134
#ISCELL
  standard tap *
  page89_i135
#ISCELL
  standard tap *
  page89_i136
#ISCELL
  standard tap *
  page89_i137
#ISCELL
  standard tap *
  page89_i138
#ISCELL
  standard tap *
  page89_i139
#ISCELL
  standard offpage *
  page89_i14
#ISCELL
  standard tap *
  page89_i140
#ISCELL
  standard tap *
  page89_i141
#ISCELL
  standard tap *
  page89_i142
#ISCELL
  standard tap *
  page89_i143
#ISCELL
  standard tap *
  page89_i144
#ISCELL
  standard tap *
  page89_i145
#ISCELL
  standard tap *
  page89_i146
#ISCELL
  standard tap *
  page89_i147
#ISCELL
  standard tap *
  page89_i148
#ISCELL
  standard tap *
  page89_i149
#ISCELL
  standard offpage *
  page89_i15
#ISCELL
  standard tap *
  page89_i150
#ISCELL
  standard tap *
  page89_i151
#ISCELL
  standard tap *
  page89_i152
#ISCELL
  standard tap *
  page89_i153
#ISCELL
  standard tap *
  page89_i154
#ISCELL
  standard tap *
  page89_i155
#ISCELL
  standard tap *
  page89_i156
#ISCELL
  standard tap *
  page89_i157
#ISCELL
  standard tap *
  page89_i158
#ISCELL
  standard tap *
  page89_i159
#ISCELL
  standard offpage *
  page89_i16
#ISCELL
  standard tap *
  page89_i160
#ISCELL
  standard tap *
  page89_i161
#ISCELL
  standard tap *
  page89_i162
#ISCELL
  standard tap *
  page89_i163
#ISCELL
  standard tap *
  page89_i164
#ISCELL
  standard tap *
  page89_i165
#ISCELL
  standard offpage *
  page89_i166
#ISCELL
  standard offpage *
  page89_i167
#ISCELL
  standard offpage *
  page89_i168
#ISCELL
  standard tap *
  page89_i169
#ISCELL
  standard offpage *
  page89_i17
#ISCELL
  standard tap *
  page89_i170
#ISCELL
  standard tap *
  page89_i171
#ISCELL
  standard offpage *
  page89_i172
#ISCELL
  standard offpage *
  page89_i173
#ISCELL
  logical_power vcc_core *
  page89_i174
#CELL
  pure_quanta sconn288_adr50017p087cc *
  page89_i175
#ISCELL
  logical_power universal_gnd *
  page89_i176
#ISCELL
  standard offpage *
  page89_i177
#CELL
  pure_quanta sconn288_adr50017p087cc *
  page89_i178
#ISCELL
  standard offpage *
  page89_i179
#ISCELL
  standard offpage *
  page89_i18
#CELL
  pure_quanta q_res *
  page89_i180
#ISCELL
  standard offpage *
  page89_i19
#CELL
  pure_quanta q_res *
  page89_i2
#ISCELL
  standard offpage *
  page89_i20
#ISCELL
  standard offpage *
  page89_i21
#ISCELL
  standard offpage *
  page89_i22
#ISCELL
  standard offpage *
  page89_i23
#ISCELL
  standard tap *
  page89_i24
#ISCELL
  standard tap *
  page89_i25
#ISCELL
  standard tap *
  page89_i26
#ISCELL
  standard tap *
  page89_i27
#ISCELL
  standard tap *
  page89_i28
#ISCELL
  standard tap *
  page89_i29
#ISCELL
  standard offpage *
  page89_i3
#ISCELL
  standard tap *
  page89_i30
#ISCELL
  standard tap *
  page89_i31
#ISCELL
  standard tap *
  page89_i32
#ISCELL
  standard tap *
  page89_i33
#ISCELL
  standard tap *
  page89_i34
#ISCELL
  standard tap *
  page89_i35
#ISCELL
  standard tap *
  page89_i36
#ISCELL
  standard tap *
  page89_i37
#ISCELL
  standard tap *
  page89_i38
#ISCELL
  standard tap *
  page89_i39
#ISCELL
  standard offpage *
  page89_i4
#ISCELL
  standard tap *
  page89_i40
#ISCELL
  standard tap *
  page89_i41
#ISCELL
  standard tap *
  page89_i42
#ISCELL
  standard tap *
  page89_i43
#ISCELL
  standard tap *
  page89_i44
#ISCELL
  standard tap *
  page89_i45
#ISCELL
  standard tap *
  page89_i46
#ISCELL
  standard tap *
  page89_i47
#ISCELL
  standard tap *
  page89_i48
#ISCELL
  standard tap *
  page89_i49
#ISCELL
  standard offpage *
  page89_i5
#CELL
  pure_quanta sconn288_adr50017p087cc *
  page89_i50
#ISCELL
  standard tap *
  page89_i51
#ISCELL
  standard tap *
  page89_i52
#ISCELL
  standard tap *
  page89_i53
#ISCELL
  standard tap *
  page89_i54
#ISCELL
  standard tap *
  page89_i55
#ISCELL
  standard tap *
  page89_i56
#ISCELL
  standard tap *
  page89_i57
#ISCELL
  standard tap *
  page89_i58
#ISCELL
  standard tap *
  page89_i59
#ISCELL
  standard tap *
  page89_i60
#ISCELL
  standard tap *
  page89_i61
#ISCELL
  standard tap *
  page89_i62
#ISCELL
  standard tap *
  page89_i63
#ISCELL
  standard tap *
  page89_i64
#ISCELL
  standard tap *
  page89_i65
#ISCELL
  standard tap *
  page89_i66
#ISCELL
  standard tap *
  page89_i67
#ISCELL
  standard tap *
  page89_i68
#ISCELL
  standard tap *
  page89_i69
#ISCELL
  standard offpage *
  page89_i7
#ISCELL
  standard tap *
  page89_i70
#ISCELL
  standard tap *
  page89_i71
#ISCELL
  standard tap *
  page89_i72
#ISCELL
  standard tap *
  page89_i73
#ISCELL
  standard tap *
  page89_i74
#ISCELL
  standard tap *
  page89_i75
#ISCELL
  standard tap *
  page89_i76
#ISCELL
  standard tap *
  page89_i77
#ISCELL
  standard tap *
  page89_i78
#ISCELL
  standard tap *
  page89_i79
#ISCELL
  standard offpage *
  page89_i8
#ISCELL
  standard tap *
  page89_i80
#ISCELL
  standard tap *
  page89_i81
#ISCELL
  standard tap *
  page89_i82
#ISCELL
  standard tap *
  page89_i83
#ISCELL
  standard tap *
  page89_i84
#ISCELL
  standard tap *
  page89_i85
#ISCELL
  standard tap *
  page89_i86
#ISCELL
  standard tap *
  page89_i87
#ISCELL
  standard tap *
  page89_i88
#ISCELL
  standard tap *
  page89_i89
#ISCELL
  standard offpage *
  page89_i9
#ISCELL
  standard tap *
  page89_i90
#ISCELL
  standard tap *
  page89_i91
#ISCELL
  standard tap *
  page89_i92
#ISCELL
  standard tap *
  page89_i93
#ISCELL
  standard tap *
  page89_i94
#ISCELL
  standard tap *
  page89_i95
#ISCELL
  standard tap *
  page89_i96
#ISCELL
  standard tap *
  page89_i97
#ISCELL
  standard tap *
  page89_i98
#ISCELL
  standard tap *
  page89_i99
#ISCELL
  logical_power cad_note *
  *
#ISCELL
  pure_quanta quanta_title_block_c *
  *
#ISCELL
  logical_power universal_gnd *
  page90_i1
#ISCELL
  standard offpage *
  page90_i10
#ISCELL
  standard tap *
  page90_i100
#ISCELL
  standard tap *
  page90_i101
#ISCELL
  standard tap *
  page90_i102
#ISCELL
  standard tap *
  page90_i103
#ISCELL
  standard tap *
  page90_i104
#ISCELL
  standard tap *
  page90_i105
#ISCELL
  standard tap *
  page90_i106
#ISCELL
  standard tap *
  page90_i107
#ISCELL
  standard tap *
  page90_i108
#ISCELL
  standard offpage *
  page90_i109
#CELL
  pure_quanta q_res *
  page90_i11
#ISCELL
  standard tap *
  page90_i110
#ISCELL
  standard tap *
  page90_i111
#ISCELL
  standard tap *
  page90_i112
#ISCELL
  standard tap *
  page90_i113
#ISCELL
  standard tap *
  page90_i114
#ISCELL
  standard tap *
  page90_i115
#ISCELL
  standard tap *
  page90_i116
#ISCELL
  standard tap *
  page90_i117
#ISCELL
  standard tap *
  page90_i118
#ISCELL
  standard tap *
  page90_i119
#CELL
  pure_quanta sconn288_adr50017p130cc *
  page90_i12
#ISCELL
  logical_power vcc_core *
  page90_i120
#ISCELL
  logical_power universal_gnd *
  page90_i121
#CELL
  pure_quanta q_cap *
  page90_i122
#CELL
  pure_quanta q_cap *
  page90_i123
#ISCELL
  logical_power vcc_core *
  page90_i124
#ISCELL
  standard offpage *
  page90_i125
#ISCELL
  standard tap *
  page90_i127
#ISCELL
  standard tap *
  page90_i128
#ISCELL
  standard tap *
  page90_i129
#ISCELL
  standard offpage *
  page90_i13
#ISCELL
  standard tap *
  page90_i130
#ISCELL
  standard tap *
  page90_i131
#ISCELL
  standard tap *
  page90_i132
#ISCELL
  standard tap *
  page90_i133
#ISCELL
  standard tap *
  page90_i134
#ISCELL
  standard tap *
  page90_i135
#ISCELL
  standard tap *
  page90_i136
#ISCELL
  standard tap *
  page90_i137
#ISCELL
  standard tap *
  page90_i138
#ISCELL
  standard tap *
  page90_i139
#ISCELL
  logical_power vcc_core *
  page90_i14
#ISCELL
  standard tap *
  page90_i140
#ISCELL
  standard tap *
  page90_i141
#ISCELL
  standard tap *
  page90_i142
#ISCELL
  standard tap *
  page90_i143
#ISCELL
  logical_power universal_gnd *
  page90_i144
#CELL
  pure_quanta q_cap *
  page90_i145
#ISCELL
  logical_power universal_gnd *
  page90_i146
#CELL
  pure_quanta sconn288_adr50017p130cc *
  page90_i147
#ISCELL
  standard tap *
  page90_i148
#ISCELL
  standard tap *
  page90_i149
#ISCELL
  standard offpage *
  page90_i15
#ISCELL
  standard tap *
  page90_i150
#ISCELL
  standard tap *
  page90_i151
#ISCELL
  standard tap *
  page90_i152
#ISCELL
  standard tap *
  page90_i153
#ISCELL
  standard tap *
  page90_i154
#ISCELL
  standard tap *
  page90_i155
#ISCELL
  standard tap *
  page90_i156
#ISCELL
  standard tap *
  page90_i157
#ISCELL
  standard tap *
  page90_i158
#ISCELL
  standard tap *
  page90_i159
#ISCELL
  standard offpage *
  page90_i16
#ISCELL
  standard tap *
  page90_i160
#ISCELL
  standard tap *
  page90_i161
#ISCELL
  standard tap *
  page90_i162
#ISCELL
  standard tap *
  page90_i163
#ISCELL
  standard tap *
  page90_i164
#ISCELL
  standard tap *
  page90_i165
#ISCELL
  standard offpage *
  page90_i166
#ISCELL
  standard offpage *
  page90_i167
#ISCELL
  standard offpage *
  page90_i168
#ISCELL
  standard tap *
  page90_i169
#ISCELL
  standard offpage *
  page90_i17
#ISCELL
  standard tap *
  page90_i170
#ISCELL
  standard tap *
  page90_i171
#ISCELL
  standard tap *
  page90_i172
#ISCELL
  standard tap *
  page90_i173
#ISCELL
  standard offpage *
  page90_i174
#ISCELL
  standard offpage *
  page90_i175
#ISCELL
  logical_power vcc_core *
  page90_i176
#ISCELL
  logical_power universal_gnd *
  page90_i177
#CELL
  pure_quanta sconn288_adr50017p130cc *
  page90_i178
#CELL
  pure_quanta q_res *
  page90_i179
#ISCELL
  standard offpage *
  page90_i18
#ISCELL
  standard offpage *
  page90_i180
#ISCELL
  standard offpage *
  page90_i19
#ISCELL
  standard offpage *
  page90_i2
#ISCELL
  standard offpage *
  page90_i20
#ISCELL
  standard offpage *
  page90_i21
#ISCELL
  standard offpage *
  page90_i22
#ISCELL
  standard offpage *
  page90_i23
#ISCELL
  standard offpage *
  page90_i24
#ISCELL
  standard tap *
  page90_i25
#ISCELL
  standard tap *
  page90_i26
#ISCELL
  standard tap *
  page90_i27
#ISCELL
  standard tap *
  page90_i28
#ISCELL
  standard tap *
  page90_i29
#ISCELL
  standard offpage *
  page90_i3
#ISCELL
  standard tap *
  page90_i30
#ISCELL
  standard tap *
  page90_i31
#ISCELL
  standard tap *
  page90_i32
#ISCELL
  standard tap *
  page90_i33
#ISCELL
  standard tap *
  page90_i34
#ISCELL
  standard tap *
  page90_i35
#ISCELL
  standard tap *
  page90_i36
#ISCELL
  standard tap *
  page90_i37
#ISCELL
  standard tap *
  page90_i38
#ISCELL
  standard tap *
  page90_i39
#ISCELL
  standard offpage *
  page90_i4
#ISCELL
  standard tap *
  page90_i40
#ISCELL
  standard tap *
  page90_i41
#ISCELL
  standard tap *
  page90_i42
#ISCELL
  standard tap *
  page90_i43
#ISCELL
  standard tap *
  page90_i44
#ISCELL
  standard tap *
  page90_i45
#ISCELL
  standard tap *
  page90_i46
#ISCELL
  standard tap *
  page90_i47
#ISCELL
  standard tap *
  page90_i48
#ISCELL
  standard tap *
  page90_i49
#ISCELL
  standard offpage *
  page90_i5
#ISCELL
  standard tap *
  page90_i50
#ISCELL
  standard tap *
  page90_i51
#ISCELL
  standard tap *
  page90_i52
#ISCELL
  standard tap *
  page90_i53
#ISCELL
  standard tap *
  page90_i54
#ISCELL
  standard tap *
  page90_i55
#ISCELL
  standard tap *
  page90_i56
#ISCELL
  standard tap *
  page90_i57
#ISCELL
  standard tap *
  page90_i58
#ISCELL
  standard tap *
  page90_i59
#ISCELL
  standard tap *
  page90_i60
#ISCELL
  standard tap *
  page90_i61
#ISCELL
  standard tap *
  page90_i62
#ISCELL
  standard tap *
  page90_i63
#ISCELL
  standard tap *
  page90_i64
#ISCELL
  standard tap *
  page90_i65
#ISCELL
  standard tap *
  page90_i66
#ISCELL
  standard tap *
  page90_i67
#ISCELL
  standard tap *
  page90_i68
#ISCELL
  standard tap *
  page90_i69
#ISCELL
  standard offpage *
  page90_i7
#ISCELL
  standard tap *
  page90_i70
#ISCELL
  standard tap *
  page90_i71
#ISCELL
  standard tap *
  page90_i72
#ISCELL
  standard tap *
  page90_i73
#ISCELL
  standard tap *
  page90_i74
#ISCELL
  standard tap *
  page90_i75
#ISCELL
  standard tap *
  page90_i76
#ISCELL
  standard tap *
  page90_i77
#ISCELL
  standard tap *
  page90_i78
#ISCELL
  standard tap *
  page90_i79
#ISCELL
  standard offpage *
  page90_i8
#ISCELL
  standard tap *
  page90_i80
#ISCELL
  standard tap *
  page90_i81
#ISCELL
  standard tap *
  page90_i82
#ISCELL
  standard tap *
  page90_i83
#ISCELL
  standard tap *
  page90_i84
#ISCELL
  standard tap *
  page90_i85
#ISCELL
  standard tap *
  page90_i86
#ISCELL
  standard tap *
  page90_i87
#ISCELL
  standard tap *
  page90_i88
#ISCELL
  standard tap *
  page90_i89
#ISCELL
  standard offpage *
  page90_i9
#ISCELL
  standard tap *
  page90_i90
#ISCELL
  standard tap *
  page90_i91
#ISCELL
  standard tap *
  page90_i92
#ISCELL
  standard tap *
  page90_i93
#ISCELL
  standard tap *
  page90_i94
#ISCELL
  standard tap *
  page90_i95
#ISCELL
  standard tap *
  page90_i96
#ISCELL
  standard tap *
  page90_i97
#ISCELL
  standard tap *
  page90_i98
#ISCELL
  standard tap *
  page90_i99
#ISCELL
  logical_power cad_note *
  *
#ISCELL
  pure_quanta quanta_title_block_c *
  *
#ISCELL
  logical_power universal_gnd *
  page91_i1
#ISCELL
  standard offpage *
  page91_i10
#ISCELL
  standard tap *
  page91_i100
#ISCELL
  standard tap *
  page91_i101
#ISCELL
  standard tap *
  page91_i102
#ISCELL
  standard tap *
  page91_i103
#ISCELL
  standard tap *
  page91_i104
#ISCELL
  standard tap *
  page91_i105
#ISCELL
  standard tap *
  page91_i106
#ISCELL
  standard tap *
  page91_i107
#ISCELL
  standard tap *
  page91_i108
#ISCELL
  standard tap *
  page91_i109
#ISCELL
  standard offpage *
  page91_i11
#ISCELL
  standard tap *
  page91_i110
#ISCELL
  standard tap *
  page91_i111
#ISCELL
  standard tap *
  page91_i112
#ISCELL
  standard offpage *
  page91_i113
#ISCELL
  standard tap *
  page91_i114
#ISCELL
  standard tap *
  page91_i115
#ISCELL
  standard tap *
  page91_i116
#ISCELL
  standard tap *
  page91_i117
#ISCELL
  standard tap *
  page91_i118
#ISCELL
  standard tap *
  page91_i119
#ISCELL
  logical_power vcc_core *
  page91_i12
#ISCELL
  logical_power universal_gnd *
  page91_i120
#ISCELL
  logical_power universal_gnd *
  page91_i121
#ISCELL
  logical_power vcc_core *
  page91_i122
#CELL
  pure_quanta q_cap *
  page91_i123
#CELL
  pure_quanta q_cap *
  page91_i124
#ISCELL
  logical_power vcc_core *
  page91_i125
#ISCELL
  standard offpage *
  page91_i126
#ISCELL
  standard tap *
  page91_i128
#ISCELL
  standard tap *
  page91_i129
#CELL
  pure_quanta sconn288_adr50017p087cc *
  page91_i13
#ISCELL
  standard tap *
  page91_i130
#ISCELL
  standard tap *
  page91_i131
#ISCELL
  standard tap *
  page91_i132
#ISCELL
  standard tap *
  page91_i133
#ISCELL
  standard tap *
  page91_i134
#ISCELL
  standard tap *
  page91_i135
#ISCELL
  standard tap *
  page91_i136
#ISCELL
  standard tap *
  page91_i137
#ISCELL
  standard tap *
  page91_i138
#ISCELL
  standard tap *
  page91_i139
#ISCELL
  standard tap *
  page91_i14
#ISCELL
  standard tap *
  page91_i140
#ISCELL
  standard tap *
  page91_i141
#ISCELL
  standard tap *
  page91_i142
#ISCELL
  standard tap *
  page91_i143
#ISCELL
  standard tap *
  page91_i144
#ISCELL
  standard tap *
  page91_i145
#CELL
  pure_quanta q_cap *
  page91_i146
#ISCELL
  logical_power universal_gnd *
  page91_i147
#CELL
  pure_quanta sconn288_adr50017p087cc *
  page91_i148
#ISCELL
  standard tap *
  page91_i149
#ISCELL
  standard offpage *
  page91_i15
#ISCELL
  standard tap *
  page91_i150
#ISCELL
  standard tap *
  page91_i151
#ISCELL
  standard tap *
  page91_i152
#ISCELL
  standard tap *
  page91_i153
#ISCELL
  standard tap *
  page91_i154
#ISCELL
  standard tap *
  page91_i155
#ISCELL
  standard tap *
  page91_i156
#ISCELL
  standard tap *
  page91_i157
#ISCELL
  standard tap *
  page91_i158
#ISCELL
  standard tap *
  page91_i159
#ISCELL
  standard offpage *
  page91_i16
#ISCELL
  standard tap *
  page91_i160
#ISCELL
  standard tap *
  page91_i161
#ISCELL
  standard tap *
  page91_i162
#ISCELL
  standard tap *
  page91_i163
#ISCELL
  standard tap *
  page91_i164
#ISCELL
  standard tap *
  page91_i165
#ISCELL
  standard tap *
  page91_i166
#ISCELL
  standard tap *
  page91_i167
#ISCELL
  standard offpage *
  page91_i168
#ISCELL
  standard offpage *
  page91_i169
#ISCELL
  standard offpage *
  page91_i17
#ISCELL
  standard offpage *
  page91_i170
#ISCELL
  standard tap *
  page91_i171
#ISCELL
  standard tap *
  page91_i172
#ISCELL
  standard tap *
  page91_i173
#ISCELL
  standard offpage *
  page91_i174
#ISCELL
  standard offpage *
  page91_i175
#ISCELL
  logical_power vcc_core *
  page91_i176
#ISCELL
  logical_power universal_gnd *
  page91_i177
#CELL
  pure_quanta sconn288_adr50017p087cc *
  page91_i178
#CELL
  pure_quanta q_res *
  page91_i179
#ISCELL
  standard offpage *
  page91_i18
#ISCELL
  standard offpage *
  page91_i180
#ISCELL
  standard offpage *
  page91_i19
#CELL
  pure_quanta q_res *
  page91_i2
#ISCELL
  standard offpage *
  page91_i20
#ISCELL
  standard offpage *
  page91_i21
#ISCELL
  standard offpage *
  page91_i22
#ISCELL
  standard offpage *
  page91_i23
#ISCELL
  standard offpage *
  page91_i24
#ISCELL
  standard offpage *
  page91_i25
#ISCELL
  standard tap *
  page91_i26
#ISCELL
  standard tap *
  page91_i27
#ISCELL
  standard tap *
  page91_i28
#ISCELL
  standard tap *
  page91_i29
#ISCELL
  standard offpage *
  page91_i3
#ISCELL
  standard tap *
  page91_i30
#ISCELL
  standard tap *
  page91_i31
#ISCELL
  standard tap *
  page91_i32
#ISCELL
  standard tap *
  page91_i33
#ISCELL
  standard tap *
  page91_i34
#ISCELL
  standard tap *
  page91_i35
#ISCELL
  standard tap *
  page91_i36
#ISCELL
  standard tap *
  page91_i37
#ISCELL
  standard tap *
  page91_i38
#ISCELL
  standard tap *
  page91_i39
#ISCELL
  standard offpage *
  page91_i4
#ISCELL
  standard tap *
  page91_i40
#ISCELL
  standard tap *
  page91_i41
#ISCELL
  standard tap *
  page91_i42
#ISCELL
  standard tap *
  page91_i43
#ISCELL
  standard tap *
  page91_i44
#ISCELL
  standard tap *
  page91_i45
#ISCELL
  standard tap *
  page91_i46
#ISCELL
  standard tap *
  page91_i47
#ISCELL
  standard tap *
  page91_i48
#ISCELL
  standard tap *
  page91_i49
#ISCELL
  standard offpage *
  page91_i5
#ISCELL
  standard tap *
  page91_i50
#ISCELL
  standard tap *
  page91_i51
#ISCELL
  standard tap *
  page91_i52
#ISCELL
  standard tap *
  page91_i53
#ISCELL
  standard tap *
  page91_i54
#ISCELL
  standard tap *
  page91_i55
#ISCELL
  standard tap *
  page91_i56
#ISCELL
  standard tap *
  page91_i57
#ISCELL
  standard tap *
  page91_i58
#ISCELL
  standard tap *
  page91_i59
#ISCELL
  standard offpage *
  page91_i6
#ISCELL
  standard tap *
  page91_i60
#ISCELL
  standard tap *
  page91_i61
#ISCELL
  standard tap *
  page91_i62
#ISCELL
  standard tap *
  page91_i63
#ISCELL
  standard tap *
  page91_i64
#ISCELL
  standard tap *
  page91_i65
#ISCELL
  standard tap *
  page91_i66
#ISCELL
  standard tap *
  page91_i67
#ISCELL
  standard tap *
  page91_i68
#ISCELL
  standard tap *
  page91_i69
#ISCELL
  standard tap *
  page91_i70
#ISCELL
  standard tap *
  page91_i71
#ISCELL
  standard tap *
  page91_i72
#ISCELL
  standard tap *
  page91_i73
#ISCELL
  standard tap *
  page91_i74
#ISCELL
  standard tap *
  page91_i75
#ISCELL
  standard tap *
  page91_i76
#ISCELL
  standard tap *
  page91_i77
#ISCELL
  standard tap *
  page91_i78
#ISCELL
  standard tap *
  page91_i79
#ISCELL
  standard offpage *
  page91_i8
#ISCELL
  standard tap *
  page91_i80
#ISCELL
  standard tap *
  page91_i81
#ISCELL
  standard tap *
  page91_i82
#ISCELL
  standard tap *
  page91_i83
#ISCELL
  standard tap *
  page91_i84
#ISCELL
  standard tap *
  page91_i85
#ISCELL
  standard tap *
  page91_i86
#ISCELL
  standard tap *
  page91_i87
#ISCELL
  standard tap *
  page91_i88
#ISCELL
  standard tap *
  page91_i89
#ISCELL
  standard offpage *
  page91_i9
#ISCELL
  standard tap *
  page91_i90
#ISCELL
  standard tap *
  page91_i91
#ISCELL
  standard tap *
  page91_i92
#ISCELL
  standard tap *
  page91_i93
#ISCELL
  standard tap *
  page91_i94
#ISCELL
  standard tap *
  page91_i95
#ISCELL
  standard tap *
  page91_i96
#ISCELL
  standard tap *
  page91_i97
#ISCELL
  standard tap *
  page91_i98
#ISCELL
  standard tap *
  page91_i99
#ISCELL
  logical_power cad_note *
  *
#ISCELL
  pure_quanta quanta_title_block_c *
  *
#ISCELL
  logical_power universal_gnd *
  page92_i1
#ISCELL
  standard offpage *
  page92_i10
#ISCELL
  standard tap *
  page92_i100
#ISCELL
  standard tap *
  page92_i101
#ISCELL
  standard tap *
  page92_i102
#ISCELL
  standard tap *
  page92_i103
#ISCELL
  standard tap *
  page92_i104
#ISCELL
  standard tap *
  page92_i105
#ISCELL
  standard tap *
  page92_i106
#ISCELL
  standard tap *
  page92_i107
#ISCELL
  standard tap *
  page92_i108
#ISCELL
  standard tap *
  page92_i109
#ISCELL
  standard offpage *
  page92_i11
#ISCELL
  standard tap *
  page92_i110
#ISCELL
  standard tap *
  page92_i111
#ISCELL
  standard tap *
  page92_i112
#ISCELL
  standard tap *
  page92_i113
#ISCELL
  standard tap *
  page92_i114
#ISCELL
  standard tap *
  page92_i115
#ISCELL
  standard tap *
  page92_i116
#ISCELL
  standard tap *
  page92_i117
#ISCELL
  standard tap *
  page92_i118
#ISCELL
  standard tap *
  page92_i119
#ISCELL
  logical_power vcc_core *
  page92_i12
#ISCELL
  logical_power universal_gnd *
  page92_i120
#ISCELL
  logical_power universal_gnd *
  page92_i121
#CELL
  pure_quanta q_cap *
  page92_i122
#ISCELL
  logical_power vcc_core *
  page92_i123
#ISCELL
  standard offpage *
  page92_i124
#ISCELL
  standard offpage *
  page92_i125
#CELL
  pure_quanta q_cap *
  page92_i127
#ISCELL
  logical_power vcc_core *
  page92_i128
#ISCELL
  standard tap *
  page92_i129
#ISCELL
  standard offpage *
  page92_i13
#CELL
  pure_quanta q_cap *
  page92_i130
#ISCELL
  standard tap *
  page92_i131
#ISCELL
  standard tap *
  page92_i132
#ISCELL
  standard tap *
  page92_i133
#ISCELL
  standard tap *
  page92_i134
#ISCELL
  standard tap *
  page92_i135
#ISCELL
  standard tap *
  page92_i136
#ISCELL
  standard tap *
  page92_i137
#ISCELL
  standard tap *
  page92_i138
#ISCELL
  standard tap *
  page92_i139
#ISCELL
  standard offpage *
  page92_i14
#ISCELL
  standard tap *
  page92_i140
#ISCELL
  standard tap *
  page92_i141
#ISCELL
  standard tap *
  page92_i142
#ISCELL
  standard tap *
  page92_i143
#ISCELL
  standard tap *
  page92_i144
#ISCELL
  standard tap *
  page92_i145
#ISCELL
  standard tap *
  page92_i146
#ISCELL
  standard tap *
  page92_i147
#ISCELL
  standard tap *
  page92_i148
#ISCELL
  standard tap *
  page92_i149
#ISCELL
  standard offpage *
  page92_i15
#ISCELL
  standard tap *
  page92_i150
#ISCELL
  standard tap *
  page92_i151
#ISCELL
  standard tap *
  page92_i152
#ISCELL
  standard tap *
  page92_i153
#ISCELL
  standard tap *
  page92_i154
#ISCELL
  standard tap *
  page92_i155
#ISCELL
  standard tap *
  page92_i156
#ISCELL
  standard tap *
  page92_i157
#ISCELL
  standard tap *
  page92_i158
#ISCELL
  standard tap *
  page92_i159
#ISCELL
  standard offpage *
  page92_i16
#ISCELL
  standard tap *
  page92_i160
#ISCELL
  standard tap *
  page92_i161
#ISCELL
  standard tap *
  page92_i162
#ISCELL
  standard tap *
  page92_i163
#ISCELL
  standard tap *
  page92_i164
#ISCELL
  standard tap *
  page92_i165
#ISCELL
  standard tap *
  page92_i166
#ISCELL
  standard tap *
  page92_i167
#ISCELL
  standard tap *
  page92_i168
#ISCELL
  standard tap *
  page92_i169
#ISCELL
  standard offpage *
  page92_i17
#ISCELL
  standard offpage *
  page92_i170
#ISCELL
  standard offpage *
  page92_i171
#ISCELL
  standard offpage *
  page92_i172
#ISCELL
  standard offpage *
  page92_i173
#ISCELL
  logical_power universal_gnd *
  page92_i174
#CELL
  pure_quanta sconn288_adr50017p130cc *
  page92_i175
#ISCELL
  logical_power universal_gnd *
  page92_i176
#ISCELL
  logical_power vcc_core *
  page92_i177
#CELL
  pure_quanta sconn288_adr50017p130cc *
  page92_i178
#CELL
  pure_quanta q_res *
  page92_i179
#ISCELL
  standard offpage *
  page92_i18
#ISCELL
  standard offpage *
  page92_i180
#ISCELL
  standard offpage *
  page92_i19
#CELL
  pure_quanta q_res *
  page92_i2
#ISCELL
  standard offpage *
  page92_i20
#ISCELL
  standard offpage *
  page92_i21
#ISCELL
  standard offpage *
  page92_i22
#ISCELL
  standard offpage *
  page92_i23
#ISCELL
  standard offpage *
  page92_i24
#CELL
  pure_quanta sconn288_adr50017p130cc *
  page92_i25
#ISCELL
  standard tap *
  page92_i26
#ISCELL
  standard tap *
  page92_i27
#ISCELL
  standard tap *
  page92_i28
#ISCELL
  standard tap *
  page92_i29
#ISCELL
  standard offpage *
  page92_i3
#ISCELL
  standard tap *
  page92_i30
#ISCELL
  standard tap *
  page92_i31
#ISCELL
  standard tap *
  page92_i32
#ISCELL
  standard tap *
  page92_i33
#ISCELL
  standard tap *
  page92_i34
#ISCELL
  standard tap *
  page92_i35
#ISCELL
  standard tap *
  page92_i36
#ISCELL
  standard tap *
  page92_i37
#ISCELL
  standard tap *
  page92_i38
#ISCELL
  standard tap *
  page92_i39
#ISCELL
  standard offpage *
  page92_i4
#ISCELL
  standard tap *
  page92_i40
#ISCELL
  standard tap *
  page92_i41
#ISCELL
  standard tap *
  page92_i42
#ISCELL
  standard tap *
  page92_i43
#ISCELL
  standard tap *
  page92_i44
#ISCELL
  standard tap *
  page92_i45
#ISCELL
  standard tap *
  page92_i46
#ISCELL
  standard tap *
  page92_i47
#ISCELL
  standard tap *
  page92_i48
#ISCELL
  standard tap *
  page92_i49
#ISCELL
  standard offpage *
  page92_i5
#ISCELL
  standard tap *
  page92_i50
#ISCELL
  standard tap *
  page92_i51
#ISCELL
  standard tap *
  page92_i52
#ISCELL
  standard tap *
  page92_i53
#ISCELL
  standard tap *
  page92_i54
#ISCELL
  standard tap *
  page92_i55
#ISCELL
  standard tap *
  page92_i56
#ISCELL
  standard tap *
  page92_i57
#ISCELL
  standard tap *
  page92_i58
#ISCELL
  standard tap *
  page92_i59
#ISCELL
  standard offpage *
  page92_i6
#ISCELL
  standard tap *
  page92_i60
#ISCELL
  standard tap *
  page92_i61
#ISCELL
  standard tap *
  page92_i62
#ISCELL
  standard tap *
  page92_i63
#ISCELL
  standard tap *
  page92_i64
#ISCELL
  standard tap *
  page92_i65
#ISCELL
  standard tap *
  page92_i66
#ISCELL
  standard tap *
  page92_i67
#ISCELL
  standard tap *
  page92_i68
#ISCELL
  standard tap *
  page92_i69
#ISCELL
  standard offpage *
  page92_i7
#ISCELL
  standard tap *
  page92_i70
#ISCELL
  standard tap *
  page92_i71
#ISCELL
  standard tap *
  page92_i72
#ISCELL
  standard tap *
  page92_i73
#ISCELL
  standard tap *
  page92_i74
#ISCELL
  standard tap *
  page92_i75
#ISCELL
  standard tap *
  page92_i76
#ISCELL
  standard tap *
  page92_i77
#ISCELL
  standard tap *
  page92_i78
#ISCELL
  standard tap *
  page92_i79
#ISCELL
  standard tap *
  page92_i80
#ISCELL
  standard tap *
  page92_i81
#ISCELL
  standard tap *
  page92_i82
#ISCELL
  standard tap *
  page92_i83
#ISCELL
  standard tap *
  page92_i84
#ISCELL
  standard tap *
  page92_i85
#ISCELL
  standard tap *
  page92_i86
#ISCELL
  standard tap *
  page92_i87
#ISCELL
  standard tap *
  page92_i88
#ISCELL
  standard tap *
  page92_i89
#ISCELL
  standard offpage *
  page92_i9
#ISCELL
  standard tap *
  page92_i90
#ISCELL
  standard tap *
  page92_i91
#ISCELL
  standard tap *
  page92_i92
#ISCELL
  standard tap *
  page92_i93
#ISCELL
  standard tap *
  page92_i94
#ISCELL
  standard tap *
  page92_i95
#ISCELL
  standard tap *
  page92_i96
#ISCELL
  standard tap *
  page92_i97
#ISCELL
  standard tap *
  page92_i98
#ISCELL
  standard tap *
  page92_i99
#ISCELL
  logical_power cad_note *
  *
#ISCELL
  pure_quanta quanta_title_block_c *
  *
#ISCELL
  logical_power universal_gnd *
  page93_i1
#ISCELL
  standard offpage *
  page93_i10
#ISCELL
  standard tap *
  page93_i100
#ISCELL
  standard tap *
  page93_i101
#ISCELL
  standard tap *
  page93_i102
#ISCELL
  standard tap *
  page93_i103
#ISCELL
  standard tap *
  page93_i104
#ISCELL
  standard tap *
  page93_i105
#ISCELL
  standard tap *
  page93_i106
#ISCELL
  standard tap *
  page93_i107
#ISCELL
  standard tap *
  page93_i108
#ISCELL
  standard tap *
  page93_i109
#ISCELL
  standard offpage *
  page93_i11
#ISCELL
  standard tap *
  page93_i110
#ISCELL
  standard tap *
  page93_i111
#ISCELL
  standard tap *
  page93_i112
#ISCELL
  standard tap *
  page93_i113
#ISCELL
  standard tap *
  page93_i114
#ISCELL
  standard tap *
  page93_i115
#ISCELL
  standard tap *
  page93_i116
#ISCELL
  standard offpage *
  page93_i117
#ISCELL
  standard tap *
  page93_i118
#ISCELL
  standard tap *
  page93_i119
#ISCELL
  logical_power vcc_core *
  page93_i12
#ISCELL
  logical_power universal_gnd *
  page93_i120
#ISCELL
  logical_power universal_gnd *
  page93_i121
#CELL
  pure_quanta q_cap *
  page93_i122
#ISCELL
  logical_power vcc_core *
  page93_i123
#ISCELL
  standard offpage *
  page93_i124
#CELL
  pure_quanta q_cap *
  page93_i126
#ISCELL
  logical_power vcc_core *
  page93_i127
#CELL
  pure_quanta q_cap *
  page93_i128
#ISCELL
  standard tap *
  page93_i129
#ISCELL
  standard offpage *
  page93_i13
#ISCELL
  standard tap *
  page93_i130
#ISCELL
  standard tap *
  page93_i131
#ISCELL
  standard tap *
  page93_i132
#ISCELL
  standard tap *
  page93_i133
#ISCELL
  standard tap *
  page93_i134
#ISCELL
  standard tap *
  page93_i135
#ISCELL
  standard tap *
  page93_i136
#ISCELL
  standard tap *
  page93_i137
#ISCELL
  standard tap *
  page93_i138
#ISCELL
  standard tap *
  page93_i139
#ISCELL
  standard offpage *
  page93_i14
#ISCELL
  standard tap *
  page93_i140
#ISCELL
  standard tap *
  page93_i141
#ISCELL
  standard tap *
  page93_i142
#ISCELL
  standard tap *
  page93_i143
#ISCELL
  standard tap *
  page93_i144
#ISCELL
  standard tap *
  page93_i145
#ISCELL
  standard tap *
  page93_i146
#ISCELL
  standard tap *
  page93_i147
#ISCELL
  standard tap *
  page93_i148
#ISCELL
  standard tap *
  page93_i149
#ISCELL
  standard offpage *
  page93_i15
#ISCELL
  standard tap *
  page93_i150
#ISCELL
  standard tap *
  page93_i151
#ISCELL
  standard tap *
  page93_i152
#ISCELL
  standard tap *
  page93_i153
#ISCELL
  standard tap *
  page93_i154
#ISCELL
  standard tap *
  page93_i155
#ISCELL
  standard tap *
  page93_i156
#ISCELL
  standard tap *
  page93_i157
#ISCELL
  standard tap *
  page93_i158
#ISCELL
  standard tap *
  page93_i159
#ISCELL
  standard offpage *
  page93_i16
#ISCELL
  standard tap *
  page93_i160
#ISCELL
  standard tap *
  page93_i161
#ISCELL
  standard tap *
  page93_i162
#ISCELL
  standard tap *
  page93_i163
#ISCELL
  standard tap *
  page93_i164
#ISCELL
  standard tap *
  page93_i165
#ISCELL
  standard tap *
  page93_i166
#ISCELL
  standard tap *
  page93_i167
#ISCELL
  standard offpage *
  page93_i168
#ISCELL
  standard offpage *
  page93_i169
#ISCELL
  standard offpage *
  page93_i17
#ISCELL
  standard offpage *
  page93_i170
#ISCELL
  standard offpage *
  page93_i171
#ISCELL
  standard tap *
  page93_i172
#ISCELL
  standard offpage *
  page93_i173
#ISCELL
  logical_power universal_gnd *
  page93_i174
#CELL
  pure_quanta sconn288_adr50017p087cc *
  page93_i175
#ISCELL
  logical_power universal_gnd *
  page93_i176
#ISCELL
  logical_power vcc_core *
  page93_i177
#CELL
  pure_quanta sconn288_adr50017p087cc *
  page93_i178
#CELL
  pure_quanta q_res *
  page93_i179
#ISCELL
  standard offpage *
  page93_i18
#ISCELL
  standard offpage *
  page93_i180
#ISCELL
  standard offpage *
  page93_i19
#CELL
  pure_quanta q_res *
  page93_i2
#ISCELL
  standard offpage *
  page93_i20
#ISCELL
  standard offpage *
  page93_i21
#ISCELL
  standard offpage *
  page93_i22
#ISCELL
  standard offpage *
  page93_i23
#CELL
  pure_quanta sconn288_adr50017p087cc *
  page93_i24
#ISCELL
  standard tap *
  page93_i25
#ISCELL
  standard tap *
  page93_i26
#ISCELL
  standard tap *
  page93_i27
#ISCELL
  standard tap *
  page93_i28
#ISCELL
  standard tap *
  page93_i29
#ISCELL
  standard offpage *
  page93_i3
#ISCELL
  standard tap *
  page93_i30
#ISCELL
  standard tap *
  page93_i31
#ISCELL
  standard tap *
  page93_i32
#ISCELL
  standard tap *
  page93_i33
#ISCELL
  standard tap *
  page93_i34
#ISCELL
  standard tap *
  page93_i35
#ISCELL
  standard tap *
  page93_i36
#ISCELL
  standard tap *
  page93_i37
#ISCELL
  standard tap *
  page93_i38
#ISCELL
  standard tap *
  page93_i39
#ISCELL
  standard offpage *
  page93_i4
#ISCELL
  standard tap *
  page93_i40
#ISCELL
  standard tap *
  page93_i41
#ISCELL
  standard tap *
  page93_i42
#ISCELL
  standard tap *
  page93_i43
#ISCELL
  standard tap *
  page93_i44
#ISCELL
  standard tap *
  page93_i45
#ISCELL
  standard tap *
  page93_i46
#ISCELL
  standard tap *
  page93_i47
#ISCELL
  standard tap *
  page93_i48
#ISCELL
  standard tap *
  page93_i49
#ISCELL
  standard offpage *
  page93_i5
#ISCELL
  standard tap *
  page93_i50
#ISCELL
  standard tap *
  page93_i51
#ISCELL
  standard tap *
  page93_i52
#ISCELL
  standard tap *
  page93_i53
#ISCELL
  standard tap *
  page93_i54
#ISCELL
  standard tap *
  page93_i55
#ISCELL
  standard tap *
  page93_i56
#ISCELL
  standard tap *
  page93_i57
#ISCELL
  standard tap *
  page93_i58
#ISCELL
  standard tap *
  page93_i59
#ISCELL
  standard offpage *
  page93_i6
#ISCELL
  standard tap *
  page93_i60
#ISCELL
  standard tap *
  page93_i61
#ISCELL
  standard tap *
  page93_i62
#ISCELL
  standard tap *
  page93_i63
#ISCELL
  standard tap *
  page93_i64
#ISCELL
  standard tap *
  page93_i65
#ISCELL
  standard tap *
  page93_i66
#ISCELL
  standard tap *
  page93_i67
#ISCELL
  standard tap *
  page93_i68
#ISCELL
  standard tap *
  page93_i69
#ISCELL
  standard tap *
  page93_i70
#ISCELL
  standard tap *
  page93_i71
#ISCELL
  standard tap *
  page93_i72
#ISCELL
  standard tap *
  page93_i73
#ISCELL
  standard tap *
  page93_i74
#ISCELL
  standard tap *
  page93_i75
#ISCELL
  standard tap *
  page93_i76
#ISCELL
  standard tap *
  page93_i77
#ISCELL
  standard tap *
  page93_i78
#ISCELL
  standard tap *
  page93_i79
#ISCELL
  standard offpage *
  page93_i8
#ISCELL
  standard tap *
  page93_i80
#ISCELL
  standard tap *
  page93_i81
#ISCELL
  standard tap *
  page93_i82
#ISCELL
  standard tap *
  page93_i83
#ISCELL
  standard tap *
  page93_i84
#ISCELL
  standard tap *
  page93_i85
#ISCELL
  standard tap *
  page93_i86
#ISCELL
  standard tap *
  page93_i87
#ISCELL
  standard tap *
  page93_i88
#ISCELL
  standard tap *
  page93_i89
#ISCELL
  standard offpage *
  page93_i9
#ISCELL
  standard tap *
  page93_i90
#ISCELL
  standard tap *
  page93_i91
#ISCELL
  standard tap *
  page93_i92
#ISCELL
  standard tap *
  page93_i93
#ISCELL
  standard tap *
  page93_i94
#ISCELL
  standard tap *
  page93_i95
#ISCELL
  standard tap *
  page93_i96
#ISCELL
  standard tap *
  page93_i97
#ISCELL
  standard tap *
  page93_i98
#ISCELL
  standard tap *
  page93_i99
#ISCELL
  logical_power cad_note *
  *
#ISCELL
  pure_quanta quanta_title_block_c *
  *
#ISCELL
  standard offpage *
  page94_i1
#CELL
  pure_quanta q_res *
  page94_i10
#ISCELL
  standard tap *
  page94_i100
#ISCELL
  standard tap *
  page94_i101
#ISCELL
  standard tap *
  page94_i102
#ISCELL
  standard tap *
  page94_i103
#ISCELL
  standard tap *
  page94_i104
#ISCELL
  standard offpage *
  page94_i105
#ISCELL
  standard offpage *
  page94_i106
#ISCELL
  standard tap *
  page94_i107
#ISCELL
  standard tap *
  page94_i108
#ISCELL
  standard tap *
  page94_i109
#CELL
  pure_quanta sconn288_adr50017p130cc *
  page94_i11
#ISCELL
  standard tap *
  page94_i110
#ISCELL
  standard tap *
  page94_i111
#ISCELL
  standard tap *
  page94_i112
#ISCELL
  standard tap *
  page94_i113
#ISCELL
  standard tap *
  page94_i114
#ISCELL
  standard tap *
  page94_i115
#ISCELL
  standard tap *
  page94_i116
#ISCELL
  standard tap *
  page94_i117
#ISCELL
  standard tap *
  page94_i118
#ISCELL
  standard tap *
  page94_i119
#ISCELL
  standard offpage *
  page94_i12
#ISCELL
  standard tap *
  page94_i120
#ISCELL
  standard offpage *
  page94_i121
#ISCELL
  logical_power universal_gnd *
  page94_i122
#CELL
  pure_quanta q_cap *
  page94_i123
#ISCELL
  logical_power vcc_core *
  page94_i124
#CELL
  pure_quanta q_cap *
  page94_i125
#ISCELL
  logical_power vcc_core *
  page94_i126
#ISCELL
  standard tap *
  page94_i128
#ISCELL
  standard tap *
  page94_i129
#ISCELL
  standard offpage *
  page94_i13
#ISCELL
  standard tap *
  page94_i130
#ISCELL
  standard tap *
  page94_i131
#ISCELL
  standard tap *
  page94_i132
#ISCELL
  standard tap *
  page94_i133
#ISCELL
  standard tap *
  page94_i134
#ISCELL
  standard tap *
  page94_i135
#ISCELL
  standard tap *
  page94_i136
#ISCELL
  standard tap *
  page94_i137
#ISCELL
  standard tap *
  page94_i138
#ISCELL
  standard tap *
  page94_i139
#ISCELL
  standard offpage *
  page94_i14
#ISCELL
  standard tap *
  page94_i140
#ISCELL
  standard tap *
  page94_i141
#ISCELL
  standard tap *
  page94_i142
#ISCELL
  standard tap *
  page94_i143
#ISCELL
  standard tap *
  page94_i144
#ISCELL
  standard tap *
  page94_i145
#ISCELL
  standard tap *
  page94_i146
#ISCELL
  standard tap *
  page94_i147
#ISCELL
  standard tap *
  page94_i148
#ISCELL
  standard tap *
  page94_i149
#ISCELL
  standard offpage *
  page94_i15
#ISCELL
  standard tap *
  page94_i150
#ISCELL
  standard tap *
  page94_i151
#ISCELL
  standard tap *
  page94_i152
#ISCELL
  standard tap *
  page94_i153
#ISCELL
  standard tap *
  page94_i154
#ISCELL
  standard tap *
  page94_i155
#ISCELL
  standard tap *
  page94_i156
#ISCELL
  standard tap *
  page94_i157
#ISCELL
  standard tap *
  page94_i158
#ISCELL
  standard tap *
  page94_i159
#ISCELL
  logical_power vcc_core *
  page94_i16
#ISCELL
  standard tap *
  page94_i160
#ISCELL
  logical_power universal_gnd *
  page94_i161
#CELL
  pure_quanta q_cap *
  page94_i162
#ISCELL
  logical_power universal_gnd *
  page94_i163
#CELL
  pure_quanta sconn288_adr50017p130cc *
  page94_i164
#ISCELL
  standard offpage *
  page94_i165
#ISCELL
  standard offpage *
  page94_i166
#ISCELL
  standard tap *
  page94_i167
#ISCELL
  standard tap *
  page94_i168
#ISCELL
  standard tap *
  page94_i169
#ISCELL
  standard offpage *
  page94_i17
#ISCELL
  standard tap *
  page94_i170
#ISCELL
  standard tap *
  page94_i171
#ISCELL
  standard tap *
  page94_i172
#ISCELL
  standard tap *
  page94_i173
#ISCELL
  standard offpage *
  page94_i174
#ISCELL
  standard offpage *
  page94_i175
#ISCELL
  logical_power vcc_core *
  page94_i176
#ISCELL
  logical_power universal_gnd *
  page94_i177
#CELL
  pure_quanta sconn288_adr50017p130cc *
  page94_i178
#CELL
  pure_quanta q_res *
  page94_i179
#ISCELL
  standard offpage *
  page94_i18
#ISCELL
  standard offpage *
  page94_i180
#ISCELL
  standard offpage *
  page94_i19
#ISCELL
  standard offpage *
  page94_i2
#ISCELL
  standard offpage *
  page94_i20
#ISCELL
  standard offpage *
  page94_i21
#ISCELL
  standard offpage *
  page94_i22
#ISCELL
  standard offpage *
  page94_i23
#ISCELL
  standard offpage *
  page94_i24
#ISCELL
  standard tap *
  page94_i25
#ISCELL
  standard tap *
  page94_i26
#ISCELL
  standard tap *
  page94_i27
#ISCELL
  standard tap *
  page94_i28
#ISCELL
  standard tap *
  page94_i29
#ISCELL
  standard offpage *
  page94_i3
#ISCELL
  standard tap *
  page94_i30
#ISCELL
  standard tap *
  page94_i31
#ISCELL
  standard tap *
  page94_i32
#ISCELL
  standard tap *
  page94_i33
#ISCELL
  standard tap *
  page94_i34
#ISCELL
  standard tap *
  page94_i35
#ISCELL
  standard tap *
  page94_i36
#ISCELL
  standard tap *
  page94_i37
#ISCELL
  standard tap *
  page94_i38
#ISCELL
  standard tap *
  page94_i39
#ISCELL
  standard offpage *
  page94_i4
#ISCELL
  standard tap *
  page94_i40
#ISCELL
  standard tap *
  page94_i41
#ISCELL
  standard tap *
  page94_i42
#ISCELL
  standard tap *
  page94_i43
#ISCELL
  standard tap *
  page94_i44
#ISCELL
  standard tap *
  page94_i45
#ISCELL
  standard tap *
  page94_i46
#ISCELL
  standard tap *
  page94_i47
#ISCELL
  standard tap *
  page94_i48
#ISCELL
  standard tap *
  page94_i49
#ISCELL
  standard tap *
  page94_i50
#ISCELL
  standard tap *
  page94_i51
#ISCELL
  standard tap *
  page94_i52
#ISCELL
  standard tap *
  page94_i53
#ISCELL
  standard tap *
  page94_i54
#ISCELL
  standard tap *
  page94_i55
#ISCELL
  standard tap *
  page94_i56
#ISCELL
  standard tap *
  page94_i57
#ISCELL
  standard tap *
  page94_i58
#ISCELL
  standard tap *
  page94_i59
#ISCELL
  standard offpage *
  page94_i6
#ISCELL
  standard tap *
  page94_i60
#ISCELL
  standard tap *
  page94_i61
#ISCELL
  standard tap *
  page94_i62
#ISCELL
  standard tap *
  page94_i63
#ISCELL
  standard tap *
  page94_i64
#ISCELL
  standard tap *
  page94_i65
#ISCELL
  standard tap *
  page94_i66
#ISCELL
  standard tap *
  page94_i67
#ISCELL
  standard tap *
  page94_i68
#ISCELL
  standard tap *
  page94_i69
#ISCELL
  standard offpage *
  page94_i7
#ISCELL
  standard tap *
  page94_i70
#ISCELL
  standard tap *
  page94_i71
#ISCELL
  standard tap *
  page94_i72
#ISCELL
  standard tap *
  page94_i73
#ISCELL
  standard tap *
  page94_i74
#ISCELL
  standard tap *
  page94_i75
#ISCELL
  standard tap *
  page94_i76
#ISCELL
  standard tap *
  page94_i77
#ISCELL
  standard tap *
  page94_i78
#ISCELL
  standard tap *
  page94_i79
#ISCELL
  standard offpage *
  page94_i8
#ISCELL
  standard tap *
  page94_i80
#ISCELL
  standard tap *
  page94_i81
#ISCELL
  standard tap *
  page94_i82
#ISCELL
  standard tap *
  page94_i83
#ISCELL
  standard tap *
  page94_i84
#ISCELL
  standard tap *
  page94_i85
#ISCELL
  standard tap *
  page94_i86
#ISCELL
  standard tap *
  page94_i87
#ISCELL
  standard tap *
  page94_i88
#ISCELL
  standard tap *
  page94_i89
#ISCELL
  logical_power universal_gnd *
  page94_i9
#ISCELL
  standard tap *
  page94_i90
#ISCELL
  standard tap *
  page94_i91
#ISCELL
  standard tap *
  page94_i92
#ISCELL
  standard tap *
  page94_i93
#ISCELL
  standard tap *
  page94_i94
#ISCELL
  standard tap *
  page94_i95
#ISCELL
  standard tap *
  page94_i96
#ISCELL
  standard tap *
  page94_i97
#ISCELL
  standard tap *
  page94_i98
#ISCELL
  standard tap *
  page94_i99
#ISCELL
  logical_power cad_note *
  *
#ISCELL
  pure_quanta quanta_title_block_c *
  *
#ISCELL
  standard offpage *
  page95_i1
#ISCELL
  standard offpage *
  page95_i10
#ISCELL
  standard tap *
  page95_i100
#ISCELL
  standard tap *
  page95_i101
#ISCELL
  standard tap *
  page95_i102
#ISCELL
  standard tap *
  page95_i103
#ISCELL
  standard tap *
  page95_i104
#ISCELL
  standard offpage *
  page95_i105
#ISCELL
  standard tap *
  page95_i106
#ISCELL
  standard tap *
  page95_i107
#ISCELL
  standard tap *
  page95_i108
#ISCELL
  standard tap *
  page95_i109
#ISCELL
  standard offpage *
  page95_i11
#ISCELL
  standard tap *
  page95_i110
#ISCELL
  standard tap *
  page95_i111
#ISCELL
  standard tap *
  page95_i112
#ISCELL
  standard tap *
  page95_i113
#ISCELL
  standard tap *
  page95_i114
#ISCELL
  standard tap *
  page95_i115
#ISCELL
  standard tap *
  page95_i116
#ISCELL
  standard tap *
  page95_i117
#ISCELL
  standard tap *
  page95_i118
#ISCELL
  standard tap *
  page95_i119
#ISCELL
  standard offpage *
  page95_i12
#ISCELL
  logical_power universal_gnd *
  page95_i120
#CELL
  pure_quanta q_cap *
  page95_i121
#ISCELL
  logical_power vcc_core *
  page95_i122
#ISCELL
  standard offpage *
  page95_i123
#CELL
  pure_quanta q_cap *
  page95_i125
#ISCELL
  logical_power vcc_core *
  page95_i126
#ISCELL
  logical_power universal_gnd *
  page95_i127
#CELL
  pure_quanta q_cap *
  page95_i128
#ISCELL
  logical_power universal_gnd *
  page95_i129
#ISCELL
  standard offpage *
  page95_i13
#ISCELL
  standard tap *
  page95_i130
#ISCELL
  standard tap *
  page95_i131
#ISCELL
  standard tap *
  page95_i132
#ISCELL
  standard tap *
  page95_i133
#ISCELL
  standard tap *
  page95_i134
#ISCELL
  standard tap *
  page95_i135
#ISCELL
  standard tap *
  page95_i136
#ISCELL
  standard tap *
  page95_i137
#ISCELL
  standard tap *
  page95_i138
#ISCELL
  standard tap *
  page95_i139
#ISCELL
  standard offpage *
  page95_i14
#ISCELL
  standard tap *
  page95_i140
#ISCELL
  standard tap *
  page95_i141
#ISCELL
  standard tap *
  page95_i142
#ISCELL
  standard tap *
  page95_i143
#ISCELL
  standard tap *
  page95_i144
#ISCELL
  standard tap *
  page95_i145
#ISCELL
  standard tap *
  page95_i146
#ISCELL
  standard tap *
  page95_i147
#ISCELL
  standard tap *
  page95_i148
#ISCELL
  standard tap *
  page95_i149
#ISCELL
  standard offpage *
  page95_i15
#ISCELL
  standard tap *
  page95_i150
#ISCELL
  standard tap *
  page95_i151
#ISCELL
  standard tap *
  page95_i152
#ISCELL
  standard tap *
  page95_i153
#ISCELL
  standard tap *
  page95_i154
#ISCELL
  standard tap *
  page95_i155
#ISCELL
  standard tap *
  page95_i156
#ISCELL
  standard tap *
  page95_i157
#ISCELL
  standard tap *
  page95_i158
#ISCELL
  standard tap *
  page95_i159
#ISCELL
  standard offpage *
  page95_i16
#ISCELL
  standard tap *
  page95_i160
#ISCELL
  standard tap *
  page95_i161
#ISCELL
  standard tap *
  page95_i162
#ISCELL
  standard offpage *
  page95_i163
#ISCELL
  standard offpage *
  page95_i164
#ISCELL
  standard offpage *
  page95_i165
#ISCELL
  standard tap *
  page95_i166
#ISCELL
  standard tap *
  page95_i167
#ISCELL
  standard tap *
  page95_i168
#ISCELL
  standard tap *
  page95_i169
#ISCELL
  standard offpage *
  page95_i17
#ISCELL
  standard tap *
  page95_i170
#ISCELL
  standard tap *
  page95_i171
#ISCELL
  standard tap *
  page95_i172
#ISCELL
  standard offpage *
  page95_i173
#ISCELL
  standard offpage *
  page95_i174
#ISCELL
  logical_power vcc_core *
  page95_i175
#CELL
  pure_quanta sconn288_adr50017p087cc *
  page95_i176
#ISCELL
  logical_power universal_gnd *
  page95_i177
#CELL
  pure_quanta sconn288_adr50017p087cc *
  page95_i178
#CELL
  pure_quanta q_res *
  page95_i179
#ISCELL
  standard offpage *
  page95_i18
#ISCELL
  standard offpage *
  page95_i180
#ISCELL
  standard offpage *
  page95_i19
#ISCELL
  standard offpage *
  page95_i2
#ISCELL
  standard offpage *
  page95_i20
#ISCELL
  logical_power vcc_core *
  page95_i21
#ISCELL
  standard tap *
  page95_i22
#ISCELL
  standard tap *
  page95_i23
#ISCELL
  standard tap *
  page95_i24
#ISCELL
  standard tap *
  page95_i25
#ISCELL
  standard tap *
  page95_i26
#ISCELL
  standard tap *
  page95_i27
#ISCELL
  standard tap *
  page95_i28
#ISCELL
  standard tap *
  page95_i29
#ISCELL
  standard offpage *
  page95_i3
#ISCELL
  standard tap *
  page95_i30
#ISCELL
  standard tap *
  page95_i31
#ISCELL
  standard tap *
  page95_i32
#ISCELL
  standard tap *
  page95_i33
#ISCELL
  standard tap *
  page95_i34
#ISCELL
  standard tap *
  page95_i35
#ISCELL
  standard tap *
  page95_i36
#ISCELL
  standard tap *
  page95_i37
#ISCELL
  standard tap *
  page95_i38
#ISCELL
  standard tap *
  page95_i39
#ISCELL
  standard offpage *
  page95_i4
#ISCELL
  standard tap *
  page95_i40
#ISCELL
  standard tap *
  page95_i41
#ISCELL
  standard tap *
  page95_i42
#ISCELL
  standard tap *
  page95_i43
#ISCELL
  standard tap *
  page95_i44
#ISCELL
  logical_power universal_gnd *
  page95_i45
#CELL
  pure_quanta q_res *
  page95_i46
#CELL
  pure_quanta sconn288_adr50017p087cc *
  page95_i47
#ISCELL
  standard tap *
  page95_i48
#ISCELL
  standard tap *
  page95_i49
#ISCELL
  standard tap *
  page95_i50
#ISCELL
  standard tap *
  page95_i51
#ISCELL
  standard tap *
  page95_i52
#ISCELL
  standard tap *
  page95_i53
#ISCELL
  standard tap *
  page95_i54
#ISCELL
  standard tap *
  page95_i55
#ISCELL
  standard tap *
  page95_i56
#ISCELL
  standard tap *
  page95_i57
#ISCELL
  standard tap *
  page95_i58
#ISCELL
  standard tap *
  page95_i59
#ISCELL
  standard offpage *
  page95_i6
#ISCELL
  standard tap *
  page95_i60
#ISCELL
  standard tap *
  page95_i61
#ISCELL
  standard tap *
  page95_i62
#ISCELL
  standard tap *
  page95_i63
#ISCELL
  standard tap *
  page95_i64
#ISCELL
  standard tap *
  page95_i65
#ISCELL
  standard tap *
  page95_i66
#ISCELL
  standard tap *
  page95_i67
#ISCELL
  standard tap *
  page95_i68
#ISCELL
  standard tap *
  page95_i69
#ISCELL
  standard offpage *
  page95_i7
#ISCELL
  standard tap *
  page95_i70
#ISCELL
  standard tap *
  page95_i71
#ISCELL
  standard tap *
  page95_i72
#ISCELL
  standard tap *
  page95_i73
#ISCELL
  standard tap *
  page95_i74
#ISCELL
  standard tap *
  page95_i75
#ISCELL
  standard tap *
  page95_i76
#ISCELL
  standard tap *
  page95_i77
#ISCELL
  standard tap *
  page95_i78
#ISCELL
  standard tap *
  page95_i79
#ISCELL
  standard offpage *
  page95_i8
#ISCELL
  standard tap *
  page95_i80
#ISCELL
  standard tap *
  page95_i81
#ISCELL
  standard tap *
  page95_i82
#ISCELL
  standard tap *
  page95_i83
#ISCELL
  standard tap *
  page95_i84
#ISCELL
  standard tap *
  page95_i85
#ISCELL
  standard tap *
  page95_i86
#ISCELL
  standard tap *
  page95_i87
#ISCELL
  standard tap *
  page95_i88
#ISCELL
  standard tap *
  page95_i89
#ISCELL
  standard offpage *
  page95_i9
#ISCELL
  standard tap *
  page95_i90
#ISCELL
  standard tap *
  page95_i91
#ISCELL
  standard tap *
  page95_i92
#ISCELL
  standard tap *
  page95_i93
#ISCELL
  standard tap *
  page95_i94
#ISCELL
  standard tap *
  page95_i95
#ISCELL
  standard tap *
  page95_i96
#ISCELL
  standard tap *
  page95_i97
#ISCELL
  standard tap *
  page95_i98
#ISCELL
  standard tap *
  page95_i99
#ISCELL
  logical_power cad_note *
  *
#ISCELL
  pure_quanta quanta_title_block_c *
  *
#ISCELL
  logical_power universal_gnd *
  page96_i1
#ISCELL
  standard offpage *
  page96_i10
#ISCELL
  standard tap *
  page96_i100
#ISCELL
  standard tap *
  page96_i101
#ISCELL
  standard tap *
  page96_i102
#ISCELL
  standard tap *
  page96_i103
#ISCELL
  standard tap *
  page96_i104
#ISCELL
  standard tap *
  page96_i105
#ISCELL
  standard tap *
  page96_i106
#ISCELL
  standard offpage *
  page96_i107
#ISCELL
  standard tap *
  page96_i108
#ISCELL
  standard tap *
  page96_i109
#ISCELL
  standard offpage *
  page96_i11
#ISCELL
  standard tap *
  page96_i110
#ISCELL
  standard tap *
  page96_i111
#ISCELL
  standard tap *
  page96_i112
#ISCELL
  standard tap *
  page96_i113
#ISCELL
  standard tap *
  page96_i114
#ISCELL
  standard tap *
  page96_i115
#ISCELL
  standard tap *
  page96_i116
#ISCELL
  standard tap *
  page96_i117
#ISCELL
  standard tap *
  page96_i118
#ISCELL
  standard tap *
  page96_i119
#ISCELL
  standard offpage *
  page96_i12
#ISCELL
  logical_power universal_gnd *
  page96_i120
#CELL
  pure_quanta q_cap *
  page96_i121
#ISCELL
  logical_power vcc_core *
  page96_i122
#ISCELL
  standard offpage *
  page96_i123
#CELL
  pure_quanta q_cap *
  page96_i125
#ISCELL
  logical_power vcc_core *
  page96_i126
#CELL
  pure_quanta q_cap *
  page96_i127
#ISCELL
  logical_power universal_gnd *
  page96_i128
#ISCELL
  logical_power universal_gnd *
  page96_i129
#ISCELL
  standard offpage *
  page96_i13
#ISCELL
  standard tap *
  page96_i130
#ISCELL
  standard tap *
  page96_i131
#ISCELL
  standard tap *
  page96_i132
#ISCELL
  standard tap *
  page96_i133
#ISCELL
  standard tap *
  page96_i134
#ISCELL
  standard tap *
  page96_i135
#ISCELL
  standard tap *
  page96_i136
#ISCELL
  standard tap *
  page96_i137
#ISCELL
  standard tap *
  page96_i138
#ISCELL
  standard tap *
  page96_i139
#ISCELL
  standard offpage *
  page96_i14
#ISCELL
  standard tap *
  page96_i140
#ISCELL
  standard tap *
  page96_i141
#ISCELL
  standard tap *
  page96_i142
#ISCELL
  standard tap *
  page96_i143
#ISCELL
  standard tap *
  page96_i144
#ISCELL
  standard tap *
  page96_i145
#ISCELL
  standard tap *
  page96_i146
#ISCELL
  standard tap *
  page96_i147
#ISCELL
  standard tap *
  page96_i148
#ISCELL
  standard tap *
  page96_i149
#ISCELL
  standard offpage *
  page96_i15
#ISCELL
  standard tap *
  page96_i150
#ISCELL
  standard tap *
  page96_i151
#ISCELL
  standard tap *
  page96_i152
#ISCELL
  standard tap *
  page96_i153
#ISCELL
  standard tap *
  page96_i154
#ISCELL
  standard tap *
  page96_i155
#ISCELL
  standard tap *
  page96_i156
#ISCELL
  standard tap *
  page96_i157
#ISCELL
  standard tap *
  page96_i158
#ISCELL
  standard tap *
  page96_i159
#ISCELL
  standard offpage *
  page96_i16
#ISCELL
  standard tap *
  page96_i160
#ISCELL
  standard tap *
  page96_i161
#ISCELL
  standard tap *
  page96_i162
#ISCELL
  standard tap *
  page96_i163
#ISCELL
  standard offpage *
  page96_i164
#ISCELL
  standard offpage *
  page96_i165
#ISCELL
  standard offpage *
  page96_i166
#ISCELL
  standard tap *
  page96_i167
#ISCELL
  standard tap *
  page96_i168
#ISCELL
  standard tap *
  page96_i169
#ISCELL
  standard offpage *
  page96_i17
#ISCELL
  standard tap *
  page96_i170
#ISCELL
  standard tap *
  page96_i171
#ISCELL
  standard tap *
  page96_i172
#ISCELL
  standard offpage *
  page96_i173
#ISCELL
  standard offpage *
  page96_i174
#ISCELL
  logical_power vcc_core *
  page96_i175
#CELL
  pure_quanta sconn288_adr50017p130cc *
  page96_i176
#ISCELL
  logical_power universal_gnd *
  page96_i177
#CELL
  pure_quanta sconn288_adr50017p130cc *
  page96_i178
#CELL
  pure_quanta q_res *
  page96_i179
#ISCELL
  standard offpage *
  page96_i18
#ISCELL
  standard offpage *
  page96_i180
#ISCELL
  standard offpage *
  page96_i19
#ISCELL
  standard offpage *
  page96_i2
#ISCELL
  standard offpage *
  page96_i20
#ISCELL
  standard offpage *
  page96_i21
#ISCELL
  logical_power vcc_core *
  page96_i22
#ISCELL
  standard tap *
  page96_i23
#ISCELL
  standard tap *
  page96_i24
#ISCELL
  standard tap *
  page96_i25
#ISCELL
  standard tap *
  page96_i26
#ISCELL
  standard tap *
  page96_i27
#ISCELL
  standard tap *
  page96_i28
#ISCELL
  standard tap *
  page96_i29
#ISCELL
  standard offpage *
  page96_i3
#ISCELL
  standard tap *
  page96_i30
#ISCELL
  standard tap *
  page96_i31
#ISCELL
  standard tap *
  page96_i32
#ISCELL
  standard tap *
  page96_i33
#ISCELL
  standard tap *
  page96_i34
#ISCELL
  standard tap *
  page96_i35
#ISCELL
  standard tap *
  page96_i36
#ISCELL
  standard tap *
  page96_i37
#ISCELL
  standard tap *
  page96_i38
#ISCELL
  standard tap *
  page96_i39
#ISCELL
  standard offpage *
  page96_i4
#ISCELL
  standard tap *
  page96_i40
#ISCELL
  standard tap *
  page96_i41
#ISCELL
  standard tap *
  page96_i42
#ISCELL
  standard tap *
  page96_i43
#ISCELL
  standard tap *
  page96_i44
#ISCELL
  standard tap *
  page96_i45
#ISCELL
  standard tap *
  page96_i46
#CELL
  pure_quanta q_res *
  page96_i47
#CELL
  pure_quanta sconn288_adr50017p130cc *
  page96_i48
#ISCELL
  standard tap *
  page96_i49
#ISCELL
  standard offpage *
  page96_i5
#ISCELL
  standard tap *
  page96_i50
#ISCELL
  standard tap *
  page96_i51
#ISCELL
  standard tap *
  page96_i52
#ISCELL
  standard tap *
  page96_i53
#ISCELL
  standard tap *
  page96_i54
#ISCELL
  standard tap *
  page96_i55
#ISCELL
  standard tap *
  page96_i56
#ISCELL
  standard tap *
  page96_i57
#ISCELL
  standard tap *
  page96_i58
#ISCELL
  standard tap *
  page96_i59
#ISCELL
  standard tap *
  page96_i60
#ISCELL
  standard tap *
  page96_i61
#ISCELL
  standard tap *
  page96_i62
#ISCELL
  standard tap *
  page96_i63
#ISCELL
  standard tap *
  page96_i64
#ISCELL
  standard tap *
  page96_i65
#ISCELL
  standard tap *
  page96_i66
#ISCELL
  standard tap *
  page96_i67
#ISCELL
  standard tap *
  page96_i68
#ISCELL
  standard tap *
  page96_i69
#ISCELL
  standard offpage *
  page96_i7
#ISCELL
  standard tap *
  page96_i70
#ISCELL
  standard tap *
  page96_i71
#ISCELL
  standard tap *
  page96_i72
#ISCELL
  standard tap *
  page96_i73
#ISCELL
  standard tap *
  page96_i74
#ISCELL
  standard tap *
  page96_i75
#ISCELL
  standard tap *
  page96_i76
#ISCELL
  standard tap *
  page96_i77
#ISCELL
  standard tap *
  page96_i78
#ISCELL
  standard tap *
  page96_i79
#ISCELL
  standard offpage *
  page96_i8
#ISCELL
  standard tap *
  page96_i80
#ISCELL
  standard tap *
  page96_i81
#ISCELL
  standard tap *
  page96_i82
#ISCELL
  standard tap *
  page96_i83
#ISCELL
  standard tap *
  page96_i84
#ISCELL
  standard tap *
  page96_i85
#ISCELL
  standard tap *
  page96_i86
#ISCELL
  standard tap *
  page96_i87
#ISCELL
  standard tap *
  page96_i88
#ISCELL
  standard tap *
  page96_i89
#ISCELL
  standard offpage *
  page96_i9
#ISCELL
  standard tap *
  page96_i90
#ISCELL
  standard tap *
  page96_i91
#ISCELL
  standard tap *
  page96_i92
#ISCELL
  standard tap *
  page96_i93
#ISCELL
  standard tap *
  page96_i94
#ISCELL
  standard tap *
  page96_i95
#ISCELL
  standard tap *
  page96_i96
#ISCELL
  standard tap *
  page96_i97
#ISCELL
  standard tap *
  page96_i98
#ISCELL
  standard tap *
  page96_i99
#ISCELL
  logical_power cad_note *
  *
#ISCELL
  pure_quanta quanta_title_block_c *
  *
#ISCELL
  standard offpage *
  page97_i1
#ISCELL
  standard tap *
  page97_i100
#ISCELL
  standard tap *
  page97_i101
#ISCELL
  standard tap *
  page97_i102
#ISCELL
  standard tap *
  page97_i103
#ISCELL
  standard offpage *
  page97_i104
#ISCELL
  standard tap *
  page97_i105
#ISCELL
  standard tap *
  page97_i106
#ISCELL
  standard tap *
  page97_i107
#ISCELL
  standard tap *
  page97_i108
#ISCELL
  standard tap *
  page97_i109
#ISCELL
  standard offpage *
  page97_i11
#ISCELL
  standard tap *
  page97_i110
#ISCELL
  standard tap *
  page97_i111
#ISCELL
  standard tap *
  page97_i112
#ISCELL
  standard tap *
  page97_i113
#ISCELL
  standard tap *
  page97_i114
#ISCELL
  standard tap *
  page97_i115
#ISCELL
  standard tap *
  page97_i116
#ISCELL
  standard tap *
  page97_i117
#ISCELL
  standard tap *
  page97_i118
#ISCELL
  standard tap *
  page97_i119
#ISCELL
  standard offpage *
  page97_i12
#ISCELL
  standard tap *
  page97_i120
#ISCELL
  standard tap *
  page97_i121
#ISCELL
  standard tap *
  page97_i122
#ISCELL
  standard tap *
  page97_i123
#ISCELL
  standard tap *
  page97_i124
#ISCELL
  standard tap *
  page97_i125
#ISCELL
  standard tap *
  page97_i126
#ISCELL
  standard tap *
  page97_i127
#ISCELL
  standard tap *
  page97_i128
#ISCELL
  standard tap *
  page97_i129
#ISCELL
  standard offpage *
  page97_i13
#ISCELL
  standard tap *
  page97_i130
#ISCELL
  standard offpage *
  page97_i131
#ISCELL
  standard tap *
  page97_i133
#ISCELL
  standard tap *
  page97_i134
#ISCELL
  standard tap *
  page97_i135
#ISCELL
  standard tap *
  page97_i136
#ISCELL
  standard tap *
  page97_i137
#ISCELL
  standard tap *
  page97_i138
#ISCELL
  standard tap *
  page97_i139
#ISCELL
  standard offpage *
  page97_i14
#ISCELL
  standard tap *
  page97_i140
#ISCELL
  standard tap *
  page97_i141
#ISCELL
  standard tap *
  page97_i142
#ISCELL
  standard tap *
  page97_i143
#ISCELL
  standard tap *
  page97_i144
#ISCELL
  standard tap *
  page97_i145
#ISCELL
  standard tap *
  page97_i146
#ISCELL
  standard tap *
  page97_i147
#ISCELL
  standard tap *
  page97_i148
#ISCELL
  standard tap *
  page97_i149
#ISCELL
  standard offpage *
  page97_i15
#ISCELL
  standard tap *
  page97_i150
#ISCELL
  standard tap *
  page97_i151
#ISCELL
  standard tap *
  page97_i152
#ISCELL
  standard tap *
  page97_i153
#ISCELL
  standard tap *
  page97_i154
#ISCELL
  standard tap *
  page97_i155
#ISCELL
  standard tap *
  page97_i156
#ISCELL
  standard tap *
  page97_i157
#ISCELL
  standard tap *
  page97_i158
#ISCELL
  standard tap *
  page97_i159
#ISCELL
  standard offpage *
  page97_i16
#ISCELL
  standard tap *
  page97_i160
#ISCELL
  standard tap *
  page97_i161
#ISCELL
  standard tap *
  page97_i162
#ISCELL
  standard tap *
  page97_i163
#ISCELL
  standard tap *
  page97_i164
#ISCELL
  standard tap *
  page97_i165
#ISCELL
  standard tap *
  page97_i166
#ISCELL
  standard tap *
  page97_i167
#ISCELL
  standard tap *
  page97_i168
#ISCELL
  standard tap *
  page97_i169
#ISCELL
  standard offpage *
  page97_i17
#ISCELL
  standard tap *
  page97_i170
#ISCELL
  standard tap *
  page97_i171
#ISCELL
  standard tap *
  page97_i172
#ISCELL
  standard offpage *
  page97_i173
#ISCELL
  standard offpage *
  page97_i174
#ISCELL
  standard offpage *
  page97_i175
#ISCELL
  standard offpage *
  page97_i176
#ISCELL
  logical_power vcc_core *
  page97_i177
#CELL
  pure_quanta sconn288_adr50017p087cc *
  page97_i178
#CELL
  pure_quanta q_res *
  page97_i179
#ISCELL
  standard offpage *
  page97_i18
#ISCELL
  standard offpage *
  page97_i180
#ISCELL
  standard offpage *
  page97_i19
#ISCELL
  standard offpage *
  page97_i2
#ISCELL
  standard offpage *
  page97_i20
#ISCELL
  standard offpage *
  page97_i21
#ISCELL
  standard offpage *
  page97_i22
#ISCELL
  standard offpage *
  page97_i23
#ISCELL
  standard offpage *
  page97_i24
#ISCELL
  logical_power vcc_core *
  page97_i25
#ISCELL
  standard tap *
  page97_i26
#ISCELL
  standard tap *
  page97_i27
#ISCELL
  standard tap *
  page97_i28
#ISCELL
  standard tap *
  page97_i29
#ISCELL
  standard offpage *
  page97_i3
#ISCELL
  standard tap *
  page97_i30
#ISCELL
  standard tap *
  page97_i31
#ISCELL
  standard tap *
  page97_i32
#ISCELL
  standard tap *
  page97_i33
#ISCELL
  standard tap *
  page97_i34
#ISCELL
  standard tap *
  page97_i35
#ISCELL
  standard tap *
  page97_i36
#ISCELL
  standard tap *
  page97_i37
#ISCELL
  standard tap *
  page97_i38
#ISCELL
  standard tap *
  page97_i39
#ISCELL
  logical_power universal_gnd *
  page97_i4
#ISCELL
  standard tap *
  page97_i40
#ISCELL
  standard tap *
  page97_i41
#ISCELL
  standard tap *
  page97_i42
#ISCELL
  standard tap *
  page97_i43
#ISCELL
  standard tap *
  page97_i44
#ISCELL
  standard tap *
  page97_i45
#ISCELL
  standard tap *
  page97_i46
#ISCELL
  standard tap *
  page97_i47
#ISCELL
  standard tap *
  page97_i48
#ISCELL
  standard tap *
  page97_i49
#CELL
  pure_quanta q_res *
  page97_i5
#ISCELL
  standard tap *
  page97_i50
#ISCELL
  standard tap *
  page97_i51
#ISCELL
  standard tap *
  page97_i52
#ISCELL
  standard tap *
  page97_i53
#ISCELL
  standard tap *
  page97_i54
#ISCELL
  standard tap *
  page97_i55
#CELL
  pure_quanta q_cap *
  page97_i56
#ISCELL
  logical_power universal_gnd *
  page97_i57
#ISCELL
  logical_power vcc_core *
  page97_i58
#CELL
  pure_quanta q_cap *
  page97_i59
#CELL
  pure_quanta sconn288_adr50017p087cc *
  page97_i6
#ISCELL
  logical_power vcc_core *
  page97_i60
#ISCELL
  logical_power universal_gnd *
  page97_i61
#CELL
  pure_quanta q_cap *
  page97_i62
#ISCELL
  logical_power universal_gnd *
  page97_i63
#CELL
  pure_quanta sconn288_adr50017p087cc *
  page97_i64
#ISCELL
  logical_power universal_gnd *
  page97_i65
#ISCELL
  standard tap *
  page97_i66
#ISCELL
  standard tap *
  page97_i67
#ISCELL
  standard tap *
  page97_i68
#ISCELL
  standard tap *
  page97_i69
#ISCELL
  standard offpage *
  page97_i7
#ISCELL
  standard tap *
  page97_i70
#ISCELL
  standard tap *
  page97_i71
#ISCELL
  standard tap *
  page97_i72
#ISCELL
  standard tap *
  page97_i73
#ISCELL
  standard tap *
  page97_i74
#ISCELL
  standard tap *
  page97_i75
#ISCELL
  standard tap *
  page97_i76
#ISCELL
  standard tap *
  page97_i77
#ISCELL
  standard tap *
  page97_i78
#ISCELL
  standard tap *
  page97_i79
#ISCELL
  standard offpage *
  page97_i8
#ISCELL
  standard tap *
  page97_i80
#ISCELL
  standard tap *
  page97_i81
#ISCELL
  standard tap *
  page97_i82
#ISCELL
  standard tap *
  page97_i83
#ISCELL
  standard tap *
  page97_i84
#ISCELL
  standard tap *
  page97_i85
#ISCELL
  standard tap *
  page97_i86
#ISCELL
  standard tap *
  page97_i87
#ISCELL
  standard tap *
  page97_i88
#ISCELL
  standard tap *
  page97_i89
#ISCELL
  standard offpage *
  page97_i9
#ISCELL
  standard tap *
  page97_i90
#ISCELL
  standard tap *
  page97_i91
#ISCELL
  standard tap *
  page97_i92
#ISCELL
  standard tap *
  page97_i93
#ISCELL
  standard tap *
  page97_i94
#ISCELL
  standard tap *
  page97_i95
#ISCELL
  standard tap *
  page97_i96
#ISCELL
  standard tap *
  page97_i97
#ISCELL
  standard tap *
  page97_i98
#ISCELL
  standard tap *
  page97_i99
#ISCELL
  logical_power cad_note *
  *
#ISCELL
  pure_quanta quanta_title_block_c *
  *
#ISCELL
  logical_power universal_gnd *
  page98_i1
#ISCELL
  standard offpage *
  page98_i10
#ISCELL
  standard tap *
  page98_i100
#ISCELL
  standard tap *
  page98_i101
#ISCELL
  standard tap *
  page98_i102
#ISCELL
  standard tap *
  page98_i103
#ISCELL
  standard tap *
  page98_i104
#ISCELL
  standard tap *
  page98_i105
#ISCELL
  standard tap *
  page98_i106
#ISCELL
  standard tap *
  page98_i107
#ISCELL
  standard tap *
  page98_i108
#ISCELL
  standard offpage *
  page98_i109
#CELL
  pure_quanta q_res *
  page98_i11
#ISCELL
  standard tap *
  page98_i110
#ISCELL
  standard tap *
  page98_i111
#ISCELL
  standard tap *
  page98_i112
#ISCELL
  standard tap *
  page98_i113
#ISCELL
  standard tap *
  page98_i114
#ISCELL
  standard tap *
  page98_i115
#ISCELL
  standard tap *
  page98_i116
#ISCELL
  standard tap *
  page98_i117
#ISCELL
  standard tap *
  page98_i118
#ISCELL
  standard tap *
  page98_i119
#CELL
  pure_quanta sconn288_adr50017p130cc *
  page98_i12
#ISCELL
  logical_power vcc_core *
  page98_i120
#ISCELL
  logical_power universal_gnd *
  page98_i121
#CELL
  pure_quanta q_cap *
  page98_i122
#CELL
  pure_quanta q_cap *
  page98_i123
#ISCELL
  logical_power vcc_core *
  page98_i124
#ISCELL
  standard offpage *
  page98_i125
#ISCELL
  standard tap *
  page98_i127
#ISCELL
  standard tap *
  page98_i128
#ISCELL
  standard tap *
  page98_i129
#ISCELL
  standard offpage *
  page98_i13
#ISCELL
  standard tap *
  page98_i130
#ISCELL
  standard tap *
  page98_i131
#ISCELL
  standard tap *
  page98_i132
#ISCELL
  standard tap *
  page98_i133
#ISCELL
  standard tap *
  page98_i134
#ISCELL
  standard tap *
  page98_i135
#ISCELL
  standard tap *
  page98_i136
#ISCELL
  standard tap *
  page98_i137
#ISCELL
  standard tap *
  page98_i138
#ISCELL
  standard tap *
  page98_i139
#ISCELL
  logical_power vcc_core *
  page98_i14
#ISCELL
  standard tap *
  page98_i140
#ISCELL
  standard tap *
  page98_i141
#ISCELL
  standard tap *
  page98_i142
#ISCELL
  standard tap *
  page98_i143
#ISCELL
  logical_power universal_gnd *
  page98_i144
#CELL
  pure_quanta q_cap *
  page98_i145
#ISCELL
  logical_power universal_gnd *
  page98_i146
#CELL
  pure_quanta sconn288_adr50017p130cc *
  page98_i147
#ISCELL
  standard tap *
  page98_i148
#ISCELL
  standard tap *
  page98_i149
#ISCELL
  standard offpage *
  page98_i15
#ISCELL
  standard tap *
  page98_i150
#ISCELL
  standard tap *
  page98_i151
#ISCELL
  standard tap *
  page98_i152
#ISCELL
  standard tap *
  page98_i153
#ISCELL
  standard tap *
  page98_i154
#ISCELL
  standard tap *
  page98_i155
#ISCELL
  standard tap *
  page98_i156
#ISCELL
  standard tap *
  page98_i157
#ISCELL
  standard tap *
  page98_i158
#ISCELL
  standard tap *
  page98_i159
#ISCELL
  standard offpage *
  page98_i16
#ISCELL
  standard tap *
  page98_i160
#ISCELL
  standard tap *
  page98_i161
#ISCELL
  standard tap *
  page98_i162
#ISCELL
  standard tap *
  page98_i163
#ISCELL
  standard tap *
  page98_i164
#ISCELL
  standard tap *
  page98_i165
#ISCELL
  standard offpage *
  page98_i166
#ISCELL
  standard offpage *
  page98_i167
#ISCELL
  standard offpage *
  page98_i168
#ISCELL
  standard tap *
  page98_i169
#ISCELL
  standard offpage *
  page98_i17
#ISCELL
  standard tap *
  page98_i170
#ISCELL
  standard tap *
  page98_i171
#ISCELL
  standard tap *
  page98_i172
#ISCELL
  standard tap *
  page98_i173
#ISCELL
  standard offpage *
  page98_i174
#ISCELL
  standard offpage *
  page98_i175
#ISCELL
  logical_power vcc_core *
  page98_i176
#ISCELL
  logical_power universal_gnd *
  page98_i177
#CELL
  pure_quanta sconn288_adr50017p130cc *
  page98_i178
#CELL
  pure_quanta q_res *
  page98_i179
#ISCELL
  standard offpage *
  page98_i18
#ISCELL
  standard offpage *
  page98_i180
#ISCELL
  standard offpage *
  page98_i19
#ISCELL
  standard offpage *
  page98_i2
#ISCELL
  standard offpage *
  page98_i20
#ISCELL
  standard offpage *
  page98_i21
#ISCELL
  standard offpage *
  page98_i22
#ISCELL
  standard offpage *
  page98_i23
#ISCELL
  standard offpage *
  page98_i24
#ISCELL
  standard tap *
  page98_i25
#ISCELL
  standard tap *
  page98_i26
#ISCELL
  standard tap *
  page98_i27
#ISCELL
  standard tap *
  page98_i28
#ISCELL
  standard tap *
  page98_i29
#ISCELL
  standard offpage *
  page98_i3
#ISCELL
  standard tap *
  page98_i30
#ISCELL
  standard tap *
  page98_i31
#ISCELL
  standard tap *
  page98_i32
#ISCELL
  standard tap *
  page98_i33
#ISCELL
  standard tap *
  page98_i34
#ISCELL
  standard tap *
  page98_i35
#ISCELL
  standard tap *
  page98_i36
#ISCELL
  standard tap *
  page98_i37
#ISCELL
  standard tap *
  page98_i38
#ISCELL
  standard tap *
  page98_i39
#ISCELL
  standard offpage *
  page98_i4
#ISCELL
  standard tap *
  page98_i40
#ISCELL
  standard tap *
  page98_i41
#ISCELL
  standard tap *
  page98_i42
#ISCELL
  standard tap *
  page98_i43
#ISCELL
  standard tap *
  page98_i44
#ISCELL
  standard tap *
  page98_i45
#ISCELL
  standard tap *
  page98_i46
#ISCELL
  standard tap *
  page98_i47
#ISCELL
  standard tap *
  page98_i48
#ISCELL
  standard tap *
  page98_i49
#ISCELL
  standard offpage *
  page98_i5
#ISCELL
  standard tap *
  page98_i50
#ISCELL
  standard tap *
  page98_i51
#ISCELL
  standard tap *
  page98_i52
#ISCELL
  standard tap *
  page98_i53
#ISCELL
  standard tap *
  page98_i54
#ISCELL
  standard tap *
  page98_i55
#ISCELL
  standard tap *
  page98_i56
#ISCELL
  standard tap *
  page98_i57
#ISCELL
  standard tap *
  page98_i58
#ISCELL
  standard tap *
  page98_i59
#ISCELL
  standard tap *
  page98_i60
#ISCELL
  standard tap *
  page98_i61
#ISCELL
  standard tap *
  page98_i62
#ISCELL
  standard tap *
  page98_i63
#ISCELL
  standard tap *
  page98_i64
#ISCELL
  standard tap *
  page98_i65
#ISCELL
  standard tap *
  page98_i66
#ISCELL
  standard tap *
  page98_i67
#ISCELL
  standard tap *
  page98_i68
#ISCELL
  standard tap *
  page98_i69
#ISCELL
  standard offpage *
  page98_i7
#ISCELL
  standard tap *
  page98_i70
#ISCELL
  standard tap *
  page98_i71
#ISCELL
  standard tap *
  page98_i72
#ISCELL
  standard tap *
  page98_i73
#ISCELL
  standard tap *
  page98_i74
#ISCELL
  standard tap *
  page98_i75
#ISCELL
  standard tap *
  page98_i76
#ISCELL
  standard tap *
  page98_i77
#ISCELL
  standard tap *
  page98_i78
#ISCELL
  standard tap *
  page98_i79
#ISCELL
  standard offpage *
  page98_i8
#ISCELL
  standard tap *
  page98_i80
#ISCELL
  standard tap *
  page98_i81
#ISCELL
  standard tap *
  page98_i82
#ISCELL
  standard tap *
  page98_i83
#ISCELL
  standard tap *
  page98_i84
#ISCELL
  standard tap *
  page98_i85
#ISCELL
  standard tap *
  page98_i86
#ISCELL
  standard tap *
  page98_i87
#ISCELL
  standard tap *
  page98_i88
#ISCELL
  standard tap *
  page98_i89
#ISCELL
  standard offpage *
  page98_i9
#ISCELL
  standard tap *
  page98_i90
#ISCELL
  standard tap *
  page98_i91
#ISCELL
  standard tap *
  page98_i92
#ISCELL
  standard tap *
  page98_i93
#ISCELL
  standard tap *
  page98_i94
#ISCELL
  standard tap *
  page98_i95
#ISCELL
  standard tap *
  page98_i96
#ISCELL
  standard tap *
  page98_i97
#ISCELL
  standard tap *
  page98_i98
#ISCELL
  standard tap *
  page98_i99
#ISCELL
  logical_power cad_note *
  *
#ISCELL
  pure_quanta quanta_title_block_c *
  *
#ISCELL
  logical_power universal_gnd *
  page99_i1
#ISCELL
  standard offpage *
  page99_i10
#ISCELL
  standard tap *
  page99_i100
#ISCELL
  standard tap *
  page99_i101
#ISCELL
  standard tap *
  page99_i102
#ISCELL
  standard tap *
  page99_i103
#ISCELL
  standard tap *
  page99_i104
#ISCELL
  standard tap *
  page99_i105
#ISCELL
  standard tap *
  page99_i106
#ISCELL
  standard tap *
  page99_i107
#ISCELL
  standard tap *
  page99_i108
#ISCELL
  standard tap *
  page99_i109
#ISCELL
  standard offpage *
  page99_i11
#ISCELL
  standard tap *
  page99_i110
#ISCELL
  standard tap *
  page99_i111
#ISCELL
  standard tap *
  page99_i112
#ISCELL
  standard offpage *
  page99_i113
#ISCELL
  standard tap *
  page99_i114
#ISCELL
  standard tap *
  page99_i115
#ISCELL
  standard tap *
  page99_i116
#ISCELL
  standard tap *
  page99_i117
#ISCELL
  standard tap *
  page99_i118
#ISCELL
  standard tap *
  page99_i119
#ISCELL
  logical_power vcc_core *
  page99_i12
#ISCELL
  logical_power universal_gnd *
  page99_i120
#ISCELL
  logical_power universal_gnd *
  page99_i121
#CELL
  pure_quanta q_cap *
  page99_i122
#ISCELL
  logical_power vcc_core *
  page99_i123
#ISCELL
  standard offpage *
  page99_i124
#CELL
  pure_quanta q_cap *
  page99_i126
#ISCELL
  logical_power vcc_core *
  page99_i127
#CELL
  pure_quanta q_cap *
  page99_i128
#ISCELL
  standard tap *
  page99_i129
#ISCELL
  standard offpage *
  page99_i13
#ISCELL
  standard tap *
  page99_i130
#ISCELL
  standard tap *
  page99_i131
#ISCELL
  standard tap *
  page99_i132
#ISCELL
  standard tap *
  page99_i133
#ISCELL
  standard tap *
  page99_i134
#ISCELL
  standard tap *
  page99_i135
#ISCELL
  standard tap *
  page99_i136
#ISCELL
  standard tap *
  page99_i137
#ISCELL
  standard tap *
  page99_i138
#ISCELL
  standard tap *
  page99_i139
#ISCELL
  standard offpage *
  page99_i14
#ISCELL
  standard tap *
  page99_i140
#ISCELL
  standard tap *
  page99_i141
#ISCELL
  standard tap *
  page99_i142
#ISCELL
  standard tap *
  page99_i143
#ISCELL
  standard tap *
  page99_i144
#ISCELL
  standard tap *
  page99_i145
#ISCELL
  standard tap *
  page99_i146
#ISCELL
  standard tap *
  page99_i147
#ISCELL
  standard tap *
  page99_i148
#ISCELL
  standard tap *
  page99_i149
#ISCELL
  standard offpage *
  page99_i15
#ISCELL
  standard tap *
  page99_i150
#ISCELL
  standard tap *
  page99_i151
#ISCELL
  standard tap *
  page99_i152
#ISCELL
  standard tap *
  page99_i153
#ISCELL
  standard tap *
  page99_i154
#ISCELL
  standard tap *
  page99_i155
#ISCELL
  standard tap *
  page99_i156
#ISCELL
  standard tap *
  page99_i157
#ISCELL
  standard tap *
  page99_i158
#ISCELL
  standard tap *
  page99_i159
#ISCELL
  standard offpage *
  page99_i16
#ISCELL
  standard tap *
  page99_i160
#ISCELL
  standard tap *
  page99_i161
#ISCELL
  standard tap *
  page99_i162
#ISCELL
  standard tap *
  page99_i163
#ISCELL
  standard tap *
  page99_i164
#ISCELL
  standard tap *
  page99_i165
#ISCELL
  standard offpage *
  page99_i166
#ISCELL
  standard offpage *
  page99_i167
#ISCELL
  standard offpage *
  page99_i168
#ISCELL
  standard tap *
  page99_i169
#ISCELL
  standard offpage *
  page99_i17
#ISCELL
  standard tap *
  page99_i170
#ISCELL
  standard tap *
  page99_i171
#ISCELL
  standard offpage *
  page99_i172
#ISCELL
  standard offpage *
  page99_i173
#ISCELL
  logical_power universal_gnd *
  page99_i174
#CELL
  pure_quanta sconn288_adr50017p087cc *
  page99_i175
#ISCELL
  logical_power universal_gnd *
  page99_i176
#ISCELL
  logical_power vcc_core *
  page99_i177
#CELL
  pure_quanta sconn288_adr50017p087cc *
  page99_i178
#ISCELL
  standard offpage *
  page99_i179
#ISCELL
  standard offpage *
  page99_i18
#CELL
  pure_quanta q_res *
  page99_i180
#ISCELL
  standard offpage *
  page99_i19
#CELL
  pure_quanta q_res *
  page99_i2
#ISCELL
  standard offpage *
  page99_i20
#ISCELL
  standard offpage *
  page99_i21
#ISCELL
  standard offpage *
  page99_i22
#ISCELL
  standard offpage *
  page99_i23
#CELL
  pure_quanta sconn288_adr50017p087cc *
  page99_i24
#ISCELL
  standard tap *
  page99_i25
#ISCELL
  standard tap *
  page99_i26
#ISCELL
  standard tap *
  page99_i27
#ISCELL
  standard tap *
  page99_i28
#ISCELL
  standard tap *
  page99_i29
#ISCELL
  standard offpage *
  page99_i3
#ISCELL
  standard tap *
  page99_i30
#ISCELL
  standard tap *
  page99_i31
#ISCELL
  standard tap *
  page99_i32
#ISCELL
  standard tap *
  page99_i33
#ISCELL
  standard tap *
  page99_i34
#ISCELL
  standard tap *
  page99_i35
#ISCELL
  standard tap *
  page99_i36
#ISCELL
  standard tap *
  page99_i37
#ISCELL
  standard tap *
  page99_i38
#ISCELL
  standard tap *
  page99_i39
#ISCELL
  standard offpage *
  page99_i4
#ISCELL
  standard tap *
  page99_i40
#ISCELL
  standard tap *
  page99_i41
#ISCELL
  standard tap *
  page99_i42
#ISCELL
  standard tap *
  page99_i43
#ISCELL
  standard tap *
  page99_i44
#ISCELL
  standard tap *
  page99_i45
#ISCELL
  standard tap *
  page99_i46
#ISCELL
  standard tap *
  page99_i47
#ISCELL
  standard tap *
  page99_i48
#ISCELL
  standard tap *
  page99_i49
#ISCELL
  standard offpage *
  page99_i5
#ISCELL
  standard tap *
  page99_i50
#ISCELL
  standard tap *
  page99_i51
#ISCELL
  standard tap *
  page99_i52
#ISCELL
  standard tap *
  page99_i53
#ISCELL
  standard tap *
  page99_i54
#ISCELL
  standard tap *
  page99_i55
#ISCELL
  standard tap *
  page99_i56
#ISCELL
  standard tap *
  page99_i57
#ISCELL
  standard tap *
  page99_i58
#ISCELL
  standard tap *
  page99_i59
#ISCELL
  standard offpage *
  page99_i6
#ISCELL
  standard tap *
  page99_i60
#ISCELL
  standard tap *
  page99_i61
#ISCELL
  standard tap *
  page99_i62
#ISCELL
  standard tap *
  page99_i63
#ISCELL
  standard tap *
  page99_i64
#ISCELL
  standard tap *
  page99_i65
#ISCELL
  standard tap *
  page99_i66
#ISCELL
  standard tap *
  page99_i67
#ISCELL
  standard tap *
  page99_i68
#ISCELL
  standard tap *
  page99_i69
#ISCELL
  standard offpage *
  page99_i7
#ISCELL
  standard tap *
  page99_i70
#ISCELL
  standard tap *
  page99_i71
#ISCELL
  standard tap *
  page99_i72
#ISCELL
  standard tap *
  page99_i73
#ISCELL
  standard tap *
  page99_i74
#ISCELL
  standard tap *
  page99_i75
#ISCELL
  standard tap *
  page99_i76
#ISCELL
  standard tap *
  page99_i77
#ISCELL
  standard tap *
  page99_i78
#ISCELL
  standard tap *
  page99_i79
#ISCELL
  standard offpage *
  page99_i8
#ISCELL
  standard tap *
  page99_i80
#ISCELL
  standard tap *
  page99_i81
#ISCELL
  standard tap *
  page99_i82
#ISCELL
  standard tap *
  page99_i83
#ISCELL
  standard tap *
  page99_i84
#ISCELL
  standard tap *
  page99_i85
#ISCELL
  standard tap *
  page99_i86
#ISCELL
  standard tap *
  page99_i87
#ISCELL
  standard tap *
  page99_i88
#ISCELL
  standard tap *
  page99_i89
#ISCELL
  standard tap *
  page99_i90
#ISCELL
  standard tap *
  page99_i91
#ISCELL
  standard tap *
  page99_i92
#ISCELL
  standard tap *
  page99_i93
#ISCELL
  standard tap *
  page99_i94
#ISCELL
  standard tap *
  page99_i95
#ISCELL
  standard tap *
  page99_i96
#ISCELL
  standard tap *
  page99_i97
#ISCELL
  standard tap *
  page99_i98
#ISCELL
  standard tap *
  page99_i99
#ISCELL
  logical_power cad_note *
  *
#ISCELL
  pure_quanta quanta_title_block_c *
  *
#ISCELL
  standard offpage *
  page100_i1
#ISCELL
  standard offpage *
  page100_i10
#ISCELL
  standard tap *
  page100_i100
#ISCELL
  standard tap *
  page100_i101
#ISCELL
  standard tap *
  page100_i102
#ISCELL
  standard tap *
  page100_i103
#ISCELL
  standard tap *
  page100_i104
#ISCELL
  standard tap *
  page100_i105
#ISCELL
  standard tap *
  page100_i106
#ISCELL
  standard tap *
  page100_i107
#ISCELL
  standard tap *
  page100_i108
#ISCELL
  standard tap *
  page100_i109
#ISCELL
  standard offpage *
  page100_i11
#ISCELL
  standard tap *
  page100_i110
#ISCELL
  standard tap *
  page100_i111
#ISCELL
  standard tap *
  page100_i112
#ISCELL
  standard tap *
  page100_i113
#ISCELL
  standard tap *
  page100_i114
#ISCELL
  standard tap *
  page100_i115
#ISCELL
  standard tap *
  page100_i116
#ISCELL
  standard tap *
  page100_i117
#ISCELL
  standard tap *
  page100_i118
#ISCELL
  standard tap *
  page100_i119
#ISCELL
  standard offpage *
  page100_i12
#ISCELL
  logical_power universal_gnd *
  page100_i120
#CELL
  pure_quanta q_cap *
  page100_i121
#CELL
  pure_quanta q_cap *
  page100_i122
#ISCELL
  logical_power universal_gnd *
  page100_i123
#CELL
  pure_quanta q_cap *
  page100_i124
#ISCELL
  logical_power vcc_core *
  page100_i125
#ISCELL
  standard offpage *
  page100_i127
#ISCELL
  standard offpage *
  page100_i128
#ISCELL
  logical_power vcc_core *
  page100_i129
#ISCELL
  logical_power vcc_core *
  page100_i13
#ISCELL
  standard tap *
  page100_i130
#ISCELL
  standard tap *
  page100_i131
#ISCELL
  standard tap *
  page100_i132
#ISCELL
  standard tap *
  page100_i133
#ISCELL
  standard tap *
  page100_i134
#ISCELL
  standard tap *
  page100_i135
#ISCELL
  standard tap *
  page100_i136
#ISCELL
  standard tap *
  page100_i137
#ISCELL
  standard tap *
  page100_i138
#ISCELL
  standard tap *
  page100_i139
#ISCELL
  standard offpage *
  page100_i14
#ISCELL
  standard tap *
  page100_i140
#ISCELL
  standard tap *
  page100_i141
#ISCELL
  standard tap *
  page100_i142
#ISCELL
  standard tap *
  page100_i143
#ISCELL
  standard tap *
  page100_i144
#ISCELL
  standard tap *
  page100_i145
#ISCELL
  standard tap *
  page100_i146
#ISCELL
  standard tap *
  page100_i147
#ISCELL
  standard tap *
  page100_i148
#ISCELL
  standard tap *
  page100_i149
#ISCELL
  standard offpage *
  page100_i15
#ISCELL
  standard tap *
  page100_i150
#ISCELL
  standard tap *
  page100_i151
#ISCELL
  standard tap *
  page100_i152
#ISCELL
  standard tap *
  page100_i153
#ISCELL
  standard tap *
  page100_i154
#ISCELL
  standard tap *
  page100_i155
#ISCELL
  standard tap *
  page100_i156
#ISCELL
  standard tap *
  page100_i157
#ISCELL
  standard tap *
  page100_i158
#ISCELL
  standard tap *
  page100_i159
#ISCELL
  standard offpage *
  page100_i16
#ISCELL
  standard tap *
  page100_i160
#ISCELL
  standard tap *
  page100_i161
#ISCELL
  standard tap *
  page100_i162
#ISCELL
  standard tap *
  page100_i163
#ISCELL
  standard tap *
  page100_i164
#ISCELL
  standard tap *
  page100_i165
#ISCELL
  standard tap *
  page100_i166
#ISCELL
  standard tap *
  page100_i167
#ISCELL
  standard tap *
  page100_i168
#ISCELL
  standard tap *
  page100_i169
#ISCELL
  standard offpage *
  page100_i17
#ISCELL
  standard offpage *
  page100_i170
#ISCELL
  standard offpage *
  page100_i171
#ISCELL
  standard offpage *
  page100_i172
#ISCELL
  standard offpage *
  page100_i173
#ISCELL
  logical_power universal_gnd *
  page100_i174
#CELL
  pure_quanta sconn288_adr50017p130cc *
  page100_i175
#ISCELL
  logical_power universal_gnd *
  page100_i176
#ISCELL
  logical_power vcc_core *
  page100_i177
#CELL
  pure_quanta sconn288_adr50017p130cc *
  page100_i178
#ISCELL
  standard offpage *
  page100_i179
#ISCELL
  standard offpage *
  page100_i18
#CELL
  pure_quanta q_res *
  page100_i180
#ISCELL
  standard offpage *
  page100_i19
#ISCELL
  logical_power universal_gnd *
  page100_i2
#ISCELL
  standard offpage *
  page100_i20
#ISCELL
  standard offpage *
  page100_i21
#ISCELL
  standard offpage *
  page100_i22
#ISCELL
  standard offpage *
  page100_i23
#ISCELL
  standard offpage *
  page100_i24
#CELL
  pure_quanta sconn288_adr50017p130cc *
  page100_i25
#ISCELL
  standard tap *
  page100_i26
#ISCELL
  standard tap *
  page100_i27
#ISCELL
  standard tap *
  page100_i28
#ISCELL
  standard tap *
  page100_i29
#CELL
  pure_quanta q_res *
  page100_i3
#ISCELL
  standard tap *
  page100_i30
#ISCELL
  standard tap *
  page100_i31
#ISCELL
  standard tap *
  page100_i32
#ISCELL
  standard tap *
  page100_i33
#ISCELL
  standard tap *
  page100_i34
#ISCELL
  standard tap *
  page100_i35
#ISCELL
  standard tap *
  page100_i36
#ISCELL
  standard tap *
  page100_i37
#ISCELL
  standard tap *
  page100_i38
#ISCELL
  standard tap *
  page100_i39
#ISCELL
  standard offpage *
  page100_i4
#ISCELL
  standard tap *
  page100_i40
#ISCELL
  standard tap *
  page100_i41
#ISCELL
  standard tap *
  page100_i42
#ISCELL
  standard tap *
  page100_i43
#ISCELL
  standard tap *
  page100_i44
#ISCELL
  standard tap *
  page100_i45
#ISCELL
  standard tap *
  page100_i46
#ISCELL
  standard tap *
  page100_i47
#ISCELL
  standard tap *
  page100_i48
#ISCELL
  standard tap *
  page100_i49
#ISCELL
  standard offpage *
  page100_i5
#ISCELL
  standard tap *
  page100_i50
#ISCELL
  standard tap *
  page100_i51
#ISCELL
  standard tap *
  page100_i52
#ISCELL
  standard tap *
  page100_i53
#ISCELL
  standard tap *
  page100_i54
#ISCELL
  standard tap *
  page100_i55
#ISCELL
  standard tap *
  page100_i56
#ISCELL
  standard tap *
  page100_i57
#ISCELL
  standard tap *
  page100_i58
#ISCELL
  standard tap *
  page100_i59
#ISCELL
  standard offpage *
  page100_i6
#ISCELL
  standard tap *
  page100_i60
#ISCELL
  standard tap *
  page100_i61
#ISCELL
  standard tap *
  page100_i62
#ISCELL
  standard tap *
  page100_i63
#ISCELL
  standard tap *
  page100_i64
#ISCELL
  standard tap *
  page100_i65
#ISCELL
  standard tap *
  page100_i66
#ISCELL
  standard tap *
  page100_i67
#ISCELL
  standard tap *
  page100_i68
#ISCELL
  standard tap *
  page100_i69
#ISCELL
  standard tap *
  page100_i70
#ISCELL
  standard tap *
  page100_i71
#ISCELL
  standard tap *
  page100_i72
#ISCELL
  standard tap *
  page100_i73
#ISCELL
  standard tap *
  page100_i74
#ISCELL
  standard tap *
  page100_i75
#ISCELL
  standard tap *
  page100_i76
#ISCELL
  standard tap *
  page100_i77
#ISCELL
  standard tap *
  page100_i78
#ISCELL
  standard tap *
  page100_i79
#ISCELL
  standard offpage *
  page100_i8
#ISCELL
  standard tap *
  page100_i80
#ISCELL
  standard tap *
  page100_i81
#ISCELL
  standard tap *
  page100_i82
#ISCELL
  standard tap *
  page100_i83
#ISCELL
  standard tap *
  page100_i84
#ISCELL
  standard tap *
  page100_i85
#ISCELL
  standard tap *
  page100_i86
#ISCELL
  standard tap *
  page100_i87
#ISCELL
  standard tap *
  page100_i88
#ISCELL
  standard tap *
  page100_i89
#ISCELL
  standard offpage *
  page100_i9
#ISCELL
  standard tap *
  page100_i90
#ISCELL
  standard tap *
  page100_i91
#ISCELL
  standard tap *
  page100_i92
#ISCELL
  standard tap *
  page100_i93
#ISCELL
  standard tap *
  page100_i94
#ISCELL
  standard tap *
  page100_i95
#ISCELL
  standard tap *
  page100_i96
#ISCELL
  standard tap *
  page100_i97
#ISCELL
  standard tap *
  page100_i98
#ISCELL
  standard tap *
  page100_i99
#ISCELL
  logical_power cad_note *
  *
#ISCELL
  pure_quanta quanta_title_block_c *
  *
#ISCELL
  standard offpage *
  page101_i1
#ISCELL
  standard offpage *
  page101_i10
#ISCELL
  standard tap *
  page101_i100
#ISCELL
  standard tap *
  page101_i101
#ISCELL
  standard tap *
  page101_i102
#ISCELL
  standard tap *
  page101_i103
#ISCELL
  standard tap *
  page101_i104
#ISCELL
  standard offpage *
  page101_i105
#ISCELL
  standard tap *
  page101_i106
#ISCELL
  standard tap *
  page101_i107
#ISCELL
  standard tap *
  page101_i108
#ISCELL
  standard tap *
  page101_i109
#ISCELL
  standard offpage *
  page101_i11
#ISCELL
  standard tap *
  page101_i110
#ISCELL
  standard tap *
  page101_i111
#ISCELL
  standard tap *
  page101_i112
#ISCELL
  standard tap *
  page101_i113
#ISCELL
  standard tap *
  page101_i114
#ISCELL
  standard tap *
  page101_i115
#ISCELL
  standard tap *
  page101_i116
#ISCELL
  standard tap *
  page101_i117
#ISCELL
  standard tap *
  page101_i118
#ISCELL
  standard tap *
  page101_i119
#ISCELL
  standard offpage *
  page101_i12
#ISCELL
  logical_power universal_gnd *
  page101_i120
#CELL
  pure_quanta q_cap *
  page101_i121
#ISCELL
  logical_power vcc_core *
  page101_i122
#ISCELL
  standard offpage *
  page101_i123
#CELL
  pure_quanta q_cap *
  page101_i125
#ISCELL
  logical_power vcc_core *
  page101_i126
#CELL
  pure_quanta q_cap *
  page101_i127
#ISCELL
  logical_power universal_gnd *
  page101_i128
#ISCELL
  logical_power universal_gnd *
  page101_i129
#ISCELL
  standard offpage *
  page101_i13
#ISCELL
  standard tap *
  page101_i130
#ISCELL
  standard tap *
  page101_i131
#ISCELL
  standard tap *
  page101_i132
#ISCELL
  standard tap *
  page101_i133
#ISCELL
  standard tap *
  page101_i134
#ISCELL
  standard tap *
  page101_i135
#ISCELL
  standard tap *
  page101_i136
#ISCELL
  standard tap *
  page101_i137
#ISCELL
  standard tap *
  page101_i138
#ISCELL
  standard tap *
  page101_i139
#ISCELL
  standard offpage *
  page101_i14
#ISCELL
  standard tap *
  page101_i140
#ISCELL
  standard tap *
  page101_i141
#ISCELL
  standard tap *
  page101_i142
#ISCELL
  standard tap *
  page101_i143
#ISCELL
  standard tap *
  page101_i144
#ISCELL
  standard tap *
  page101_i145
#ISCELL
  standard tap *
  page101_i146
#ISCELL
  standard tap *
  page101_i147
#ISCELL
  standard tap *
  page101_i148
#ISCELL
  standard tap *
  page101_i149
#ISCELL
  standard offpage *
  page101_i15
#ISCELL
  standard tap *
  page101_i150
#ISCELL
  standard tap *
  page101_i151
#ISCELL
  standard tap *
  page101_i152
#ISCELL
  standard tap *
  page101_i153
#ISCELL
  standard tap *
  page101_i154
#ISCELL
  standard tap *
  page101_i155
#ISCELL
  standard tap *
  page101_i156
#ISCELL
  standard tap *
  page101_i157
#ISCELL
  standard tap *
  page101_i158
#ISCELL
  standard tap *
  page101_i159
#ISCELL
  standard offpage *
  page101_i16
#ISCELL
  standard tap *
  page101_i160
#ISCELL
  standard tap *
  page101_i161
#ISCELL
  standard tap *
  page101_i162
#ISCELL
  standard offpage *
  page101_i163
#ISCELL
  standard offpage *
  page101_i164
#ISCELL
  standard offpage *
  page101_i165
#ISCELL
  standard tap *
  page101_i166
#ISCELL
  standard tap *
  page101_i167
#ISCELL
  standard tap *
  page101_i168
#ISCELL
  standard tap *
  page101_i169
#ISCELL
  standard offpage *
  page101_i17
#ISCELL
  standard tap *
  page101_i170
#ISCELL
  standard tap *
  page101_i171
#ISCELL
  standard tap *
  page101_i172
#ISCELL
  standard offpage *
  page101_i173
#ISCELL
  standard offpage *
  page101_i174
#ISCELL
  logical_power vcc_core *
  page101_i175
#CELL
  pure_quanta sconn288_adr50017p087cc *
  page101_i176
#ISCELL
  logical_power universal_gnd *
  page101_i177
#CELL
  pure_quanta sconn288_adr50017p087cc *
  page101_i178
#ISCELL
  standard offpage *
  page101_i179
#ISCELL
  standard offpage *
  page101_i18
#CELL
  pure_quanta q_res *
  page101_i180
#ISCELL
  standard offpage *
  page101_i19
#ISCELL
  standard offpage *
  page101_i2
#ISCELL
  standard offpage *
  page101_i20
#ISCELL
  logical_power vcc_core *
  page101_i21
#ISCELL
  standard tap *
  page101_i22
#ISCELL
  standard tap *
  page101_i23
#ISCELL
  standard tap *
  page101_i24
#ISCELL
  standard tap *
  page101_i25
#ISCELL
  standard tap *
  page101_i26
#ISCELL
  standard tap *
  page101_i27
#ISCELL
  standard tap *
  page101_i28
#ISCELL
  standard tap *
  page101_i29
#ISCELL
  standard offpage *
  page101_i3
#ISCELL
  standard tap *
  page101_i30
#ISCELL
  standard tap *
  page101_i31
#ISCELL
  standard tap *
  page101_i32
#ISCELL
  standard tap *
  page101_i33
#ISCELL
  standard tap *
  page101_i34
#ISCELL
  standard tap *
  page101_i35
#ISCELL
  standard tap *
  page101_i36
#ISCELL
  standard tap *
  page101_i37
#ISCELL
  standard tap *
  page101_i38
#ISCELL
  standard tap *
  page101_i39
#ISCELL
  standard offpage *
  page101_i4
#ISCELL
  standard tap *
  page101_i40
#ISCELL
  standard tap *
  page101_i41
#ISCELL
  standard tap *
  page101_i42
#ISCELL
  standard tap *
  page101_i43
#ISCELL
  standard tap *
  page101_i44
#ISCELL
  logical_power universal_gnd *
  page101_i45
#CELL
  pure_quanta q_res *
  page101_i46
#CELL
  pure_quanta sconn288_adr50017p087cc *
  page101_i47
#ISCELL
  standard tap *
  page101_i48
#ISCELL
  standard tap *
  page101_i49
#ISCELL
  standard tap *
  page101_i50
#ISCELL
  standard tap *
  page101_i51
#ISCELL
  standard tap *
  page101_i52
#ISCELL
  standard tap *
  page101_i53
#ISCELL
  standard tap *
  page101_i54
#ISCELL
  standard tap *
  page101_i55
#ISCELL
  standard tap *
  page101_i56
#ISCELL
  standard tap *
  page101_i57
#ISCELL
  standard tap *
  page101_i58
#ISCELL
  standard tap *
  page101_i59
#ISCELL
  standard offpage *
  page101_i6
#ISCELL
  standard tap *
  page101_i60
#ISCELL
  standard tap *
  page101_i61
#ISCELL
  standard tap *
  page101_i62
#ISCELL
  standard tap *
  page101_i63
#ISCELL
  standard tap *
  page101_i64
#ISCELL
  standard tap *
  page101_i65
#ISCELL
  standard tap *
  page101_i66
#ISCELL
  standard tap *
  page101_i67
#ISCELL
  standard tap *
  page101_i68
#ISCELL
  standard tap *
  page101_i69
#ISCELL
  standard offpage *
  page101_i7
#ISCELL
  standard tap *
  page101_i70
#ISCELL
  standard tap *
  page101_i71
#ISCELL
  standard tap *
  page101_i72
#ISCELL
  standard tap *
  page101_i73
#ISCELL
  standard tap *
  page101_i74
#ISCELL
  standard tap *
  page101_i75
#ISCELL
  standard tap *
  page101_i76
#ISCELL
  standard tap *
  page101_i77
#ISCELL
  standard tap *
  page101_i78
#ISCELL
  standard tap *
  page101_i79
#ISCELL
  standard offpage *
  page101_i8
#ISCELL
  standard tap *
  page101_i80
#ISCELL
  standard tap *
  page101_i81
#ISCELL
  standard tap *
  page101_i82
#ISCELL
  standard tap *
  page101_i83
#ISCELL
  standard tap *
  page101_i84
#ISCELL
  standard tap *
  page101_i85
#ISCELL
  standard tap *
  page101_i86
#ISCELL
  standard tap *
  page101_i87
#ISCELL
  standard tap *
  page101_i88
#ISCELL
  standard tap *
  page101_i89
#ISCELL
  standard offpage *
  page101_i9
#ISCELL
  standard tap *
  page101_i90
#ISCELL
  standard tap *
  page101_i91
#ISCELL
  standard tap *
  page101_i92
#ISCELL
  standard tap *
  page101_i93
#ISCELL
  standard tap *
  page101_i94
#ISCELL
  standard tap *
  page101_i95
#ISCELL
  standard tap *
  page101_i96
#ISCELL
  standard tap *
  page101_i97
#ISCELL
  standard tap *
  page101_i98
#ISCELL
  standard tap *
  page101_i99
#ISCELL
  logical_power cad_note *
  *
#ISCELL
  pure_quanta quanta_title_block_c *
  *
#ISCELL
  logical_power universal_gnd *
  page102_i1
#ISCELL
  standard offpage *
  page102_i10
#ISCELL
  standard tap *
  page102_i100
#ISCELL
  standard tap *
  page102_i101
#ISCELL
  standard tap *
  page102_i102
#ISCELL
  standard tap *
  page102_i103
#ISCELL
  standard tap *
  page102_i104
#ISCELL
  standard tap *
  page102_i105
#ISCELL
  standard tap *
  page102_i106
#ISCELL
  standard tap *
  page102_i107
#ISCELL
  standard tap *
  page102_i108
#ISCELL
  standard tap *
  page102_i109
#ISCELL
  standard offpage *
  page102_i11
#ISCELL
  standard tap *
  page102_i110
#ISCELL
  standard tap *
  page102_i111
#ISCELL
  standard tap *
  page102_i112
#ISCELL
  standard tap *
  page102_i113
#ISCELL
  standard tap *
  page102_i114
#ISCELL
  standard offpage *
  page102_i115
#ISCELL
  standard offpage *
  page102_i116
#ISCELL
  standard tap *
  page102_i117
#ISCELL
  standard tap *
  page102_i118
#ISCELL
  standard tap *
  page102_i119
#ISCELL
  logical_power vcc_core *
  page102_i12
#ISCELL
  standard tap *
  page102_i120
#ISCELL
  standard offpage *
  page102_i121
#ISCELL
  logical_power universal_gnd *
  page102_i122
#ISCELL
  logical_power universal_gnd *
  page102_i123
#CELL
  pure_quanta q_cap *
  page102_i124
#ISCELL
  logical_power vcc_core *
  page102_i125
#CELL
  pure_quanta q_cap *
  page102_i127
#ISCELL
  logical_power vcc_core *
  page102_i128
#ISCELL
  standard tap *
  page102_i129
#CELL
  pure_quanta sconn288_adr50017p130cc *
  page102_i13
#ISCELL
  standard tap *
  page102_i130
#ISCELL
  standard tap *
  page102_i131
#ISCELL
  standard tap *
  page102_i132
#ISCELL
  standard tap *
  page102_i133
#ISCELL
  standard tap *
  page102_i134
#ISCELL
  standard tap *
  page102_i135
#ISCELL
  standard tap *
  page102_i136
#ISCELL
  standard tap *
  page102_i137
#ISCELL
  standard tap *
  page102_i138
#ISCELL
  standard tap *
  page102_i139
#ISCELL
  standard tap *
  page102_i14
#ISCELL
  standard tap *
  page102_i140
#ISCELL
  standard tap *
  page102_i141
#ISCELL
  standard tap *
  page102_i142
#ISCELL
  standard tap *
  page102_i143
#ISCELL
  standard tap *
  page102_i144
#ISCELL
  standard tap *
  page102_i145
#ISCELL
  standard tap *
  page102_i146
#ISCELL
  standard tap *
  page102_i147
#ISCELL
  standard tap *
  page102_i148
#ISCELL
  standard tap *
  page102_i149
#ISCELL
  standard tap *
  page102_i15
#ISCELL
  standard tap *
  page102_i150
#ISCELL
  standard tap *
  page102_i151
#ISCELL
  standard tap *
  page102_i152
#ISCELL
  standard tap *
  page102_i153
#ISCELL
  standard tap *
  page102_i154
#ISCELL
  standard tap *
  page102_i155
#ISCELL
  standard tap *
  page102_i156
#ISCELL
  standard tap *
  page102_i157
#ISCELL
  standard tap *
  page102_i158
#ISCELL
  standard tap *
  page102_i159
#ISCELL
  standard offpage *
  page102_i16
#ISCELL
  standard tap *
  page102_i160
#ISCELL
  standard tap *
  page102_i161
#ISCELL
  standard tap *
  page102_i162
#ISCELL
  standard tap *
  page102_i163
#ISCELL
  standard tap *
  page102_i164
#ISCELL
  standard tap *
  page102_i165
#ISCELL
  standard tap *
  page102_i166
#CELL
  pure_quanta q_cap *
  page102_i167
#ISCELL
  logical_power universal_gnd *
  page102_i168
#CELL
  pure_quanta sconn288_adr50017p130cc *
  page102_i169
#ISCELL
  standard offpage *
  page102_i17
#ISCELL
  standard offpage *
  page102_i170
#ISCELL
  standard offpage *
  page102_i171
#ISCELL
  standard offpage *
  page102_i172
#ISCELL
  standard tap *
  page102_i173
#ISCELL
  standard tap *
  page102_i174
#ISCELL
  standard offpage *
  page102_i175
#ISCELL
  logical_power vcc_core *
  page102_i176
#ISCELL
  logical_power universal_gnd *
  page102_i177
#CELL
  pure_quanta sconn288_adr50017p130cc *
  page102_i178
#ISCELL
  standard offpage *
  page102_i179
#ISCELL
  standard offpage *
  page102_i18
#CELL
  pure_quanta q_res *
  page102_i180
#ISCELL
  standard offpage *
  page102_i19
#CELL
  pure_quanta q_res *
  page102_i2
#ISCELL
  standard offpage *
  page102_i20
#ISCELL
  standard offpage *
  page102_i21
#ISCELL
  standard offpage *
  page102_i22
#ISCELL
  standard offpage *
  page102_i23
#ISCELL
  standard offpage *
  page102_i24
#ISCELL
  standard offpage *
  page102_i25
#ISCELL
  standard offpage *
  page102_i26
#ISCELL
  standard tap *
  page102_i27
#ISCELL
  standard tap *
  page102_i28
#ISCELL
  standard tap *
  page102_i29
#ISCELL
  standard offpage *
  page102_i3
#ISCELL
  standard tap *
  page102_i30
#ISCELL
  standard tap *
  page102_i31
#ISCELL
  standard tap *
  page102_i32
#ISCELL
  standard tap *
  page102_i33
#ISCELL
  standard tap *
  page102_i34
#ISCELL
  standard tap *
  page102_i35
#ISCELL
  standard tap *
  page102_i36
#ISCELL
  standard tap *
  page102_i37
#ISCELL
  standard tap *
  page102_i38
#ISCELL
  standard tap *
  page102_i39
#ISCELL
  standard offpage *
  page102_i4
#ISCELL
  standard tap *
  page102_i40
#ISCELL
  standard tap *
  page102_i41
#ISCELL
  standard tap *
  page102_i42
#ISCELL
  standard tap *
  page102_i43
#ISCELL
  standard tap *
  page102_i44
#ISCELL
  standard tap *
  page102_i45
#ISCELL
  standard tap *
  page102_i46
#ISCELL
  standard tap *
  page102_i47
#ISCELL
  standard tap *
  page102_i48
#ISCELL
  standard tap *
  page102_i49
#ISCELL
  standard offpage *
  page102_i5
#ISCELL
  standard tap *
  page102_i50
#ISCELL
  standard tap *
  page102_i51
#ISCELL
  standard tap *
  page102_i52
#ISCELL
  standard tap *
  page102_i53
#ISCELL
  standard tap *
  page102_i54
#ISCELL
  standard tap *
  page102_i55
#ISCELL
  standard tap *
  page102_i56
#ISCELL
  standard tap *
  page102_i57
#ISCELL
  standard tap *
  page102_i58
#ISCELL
  standard tap *
  page102_i59
#ISCELL
  standard offpage *
  page102_i6
#ISCELL
  standard tap *
  page102_i60
#ISCELL
  standard tap *
  page102_i61
#ISCELL
  standard tap *
  page102_i62
#ISCELL
  standard tap *
  page102_i63
#ISCELL
  standard tap *
  page102_i64
#ISCELL
  standard tap *
  page102_i65
#ISCELL
  standard tap *
  page102_i66
#ISCELL
  standard tap *
  page102_i67
#ISCELL
  standard tap *
  page102_i68
#ISCELL
  standard tap *
  page102_i69
#ISCELL
  standard tap *
  page102_i70
#ISCELL
  standard tap *
  page102_i71
#ISCELL
  standard tap *
  page102_i72
#ISCELL
  standard tap *
  page102_i73
#ISCELL
  standard tap *
  page102_i74
#ISCELL
  standard tap *
  page102_i75
#ISCELL
  standard tap *
  page102_i76
#ISCELL
  standard tap *
  page102_i77
#ISCELL
  standard tap *
  page102_i78
#ISCELL
  standard tap *
  page102_i79
#ISCELL
  standard offpage *
  page102_i8
#ISCELL
  standard tap *
  page102_i80
#ISCELL
  standard tap *
  page102_i81
#ISCELL
  standard tap *
  page102_i82
#ISCELL
  standard tap *
  page102_i83
#ISCELL
  standard tap *
  page102_i84
#ISCELL
  standard tap *
  page102_i85
#ISCELL
  standard tap *
  page102_i86
#ISCELL
  standard tap *
  page102_i87
#ISCELL
  standard tap *
  page102_i88
#ISCELL
  standard tap *
  page102_i89
#ISCELL
  standard offpage *
  page102_i9
#ISCELL
  standard tap *
  page102_i90
#ISCELL
  standard tap *
  page102_i91
#ISCELL
  standard tap *
  page102_i92
#ISCELL
  standard tap *
  page102_i93
#ISCELL
  standard tap *
  page102_i94
#ISCELL
  standard tap *
  page102_i95
#ISCELL
  standard tap *
  page102_i96
#ISCELL
  standard tap *
  page102_i97
#ISCELL
  standard tap *
  page102_i98
#ISCELL
  standard tap *
  page102_i99
#ISCELL
  logical_power cad_note *
  *
#ISCELL
  pure_quanta quanta_title_block_c *
  *
#ISCELL
  logical_power universal_gnd *
  page103_i1
#ISCELL
  standard offpage *
  page103_i10
#ISCELL
  standard tap *
  page103_i100
#ISCELL
  standard tap *
  page103_i101
#ISCELL
  standard tap *
  page103_i102
#ISCELL
  standard tap *
  page103_i103
#ISCELL
  standard tap *
  page103_i104
#ISCELL
  standard tap *
  page103_i105
#ISCELL
  standard tap *
  page103_i106
#ISCELL
  standard tap *
  page103_i107
#ISCELL
  standard tap *
  page103_i108
#ISCELL
  standard tap *
  page103_i109
#ISCELL
  standard offpage *
  page103_i11
#ISCELL
  standard tap *
  page103_i110
#ISCELL
  standard tap *
  page103_i111
#ISCELL
  standard tap *
  page103_i112
#ISCELL
  standard offpage *
  page103_i113
#ISCELL
  standard tap *
  page103_i114
#ISCELL
  standard tap *
  page103_i115
#ISCELL
  standard tap *
  page103_i116
#ISCELL
  standard tap *
  page103_i117
#ISCELL
  standard tap *
  page103_i118
#ISCELL
  standard tap *
  page103_i119
#ISCELL
  logical_power vcc_core *
  page103_i12
#ISCELL
  logical_power universal_gnd *
  page103_i120
#ISCELL
  logical_power universal_gnd *
  page103_i121
#CELL
  pure_quanta q_cap *
  page103_i122
#ISCELL
  logical_power vcc_core *
  page103_i123
#ISCELL
  standard offpage *
  page103_i124
#CELL
  pure_quanta q_cap *
  page103_i126
#ISCELL
  logical_power vcc_core *
  page103_i127
#CELL
  pure_quanta q_cap *
  page103_i128
#ISCELL
  logical_power universal_gnd *
  page103_i129
#ISCELL
  standard tap *
  page103_i13
#ISCELL
  standard tap *
  page103_i130
#ISCELL
  standard tap *
  page103_i131
#ISCELL
  standard tap *
  page103_i132
#ISCELL
  standard tap *
  page103_i133
#ISCELL
  standard tap *
  page103_i134
#ISCELL
  standard tap *
  page103_i135
#ISCELL
  standard tap *
  page103_i136
#ISCELL
  standard tap *
  page103_i137
#ISCELL
  standard tap *
  page103_i138
#ISCELL
  standard tap *
  page103_i139
#ISCELL
  standard offpage *
  page103_i14
#ISCELL
  standard tap *
  page103_i140
#ISCELL
  standard tap *
  page103_i141
#ISCELL
  standard tap *
  page103_i142
#ISCELL
  standard tap *
  page103_i143
#ISCELL
  standard tap *
  page103_i144
#ISCELL
  standard tap *
  page103_i145
#ISCELL
  standard tap *
  page103_i146
#ISCELL
  standard tap *
  page103_i147
#ISCELL
  standard tap *
  page103_i148
#ISCELL
  standard tap *
  page103_i149
#ISCELL
  standard offpage *
  page103_i15
#ISCELL
  standard tap *
  page103_i150
#ISCELL
  standard tap *
  page103_i151
#ISCELL
  standard tap *
  page103_i152
#ISCELL
  standard tap *
  page103_i153
#ISCELL
  standard tap *
  page103_i154
#ISCELL
  standard tap *
  page103_i155
#ISCELL
  standard tap *
  page103_i156
#ISCELL
  standard tap *
  page103_i157
#ISCELL
  standard tap *
  page103_i158
#ISCELL
  standard tap *
  page103_i159
#ISCELL
  standard offpage *
  page103_i16
#ISCELL
  standard tap *
  page103_i160
#ISCELL
  standard tap *
  page103_i161
#ISCELL
  standard tap *
  page103_i162
#ISCELL
  standard tap *
  page103_i163
#ISCELL
  standard tap *
  page103_i164
#ISCELL
  standard tap *
  page103_i165
#ISCELL
  standard tap *
  page103_i166
#ISCELL
  standard offpage *
  page103_i167
#ISCELL
  standard offpage *
  page103_i168
#ISCELL
  standard offpage *
  page103_i169
#ISCELL
  standard offpage *
  page103_i17
#ISCELL
  standard tap *
  page103_i170
#ISCELL
  standard tap *
  page103_i171
#ISCELL
  standard tap *
  page103_i172
#ISCELL
  standard offpage *
  page103_i173
#ISCELL
  standard offpage *
  page103_i174
#ISCELL
  logical_power vcc_core *
  page103_i175
#CELL
  pure_quanta sconn288_adr50017p087cc *
  page103_i176
#ISCELL
  logical_power universal_gnd *
  page103_i177
#CELL
  pure_quanta sconn288_adr50017p087cc *
  page103_i178
#ISCELL
  standard offpage *
  page103_i179
#ISCELL
  standard offpage *
  page103_i18
#CELL
  pure_quanta q_res *
  page103_i180
#ISCELL
  standard offpage *
  page103_i19
#CELL
  pure_quanta q_res *
  page103_i2
#ISCELL
  standard offpage *
  page103_i20
#ISCELL
  standard offpage *
  page103_i21
#ISCELL
  standard offpage *
  page103_i22
#ISCELL
  standard offpage *
  page103_i23
#ISCELL
  standard offpage *
  page103_i24
#ISCELL
  standard tap *
  page103_i25
#ISCELL
  standard tap *
  page103_i26
#ISCELL
  standard tap *
  page103_i27
#ISCELL
  standard tap *
  page103_i28
#ISCELL
  standard tap *
  page103_i29
#ISCELL
  standard offpage *
  page103_i3
#ISCELL
  standard tap *
  page103_i30
#ISCELL
  standard tap *
  page103_i31
#ISCELL
  standard tap *
  page103_i32
#ISCELL
  standard tap *
  page103_i33
#ISCELL
  standard tap *
  page103_i34
#ISCELL
  standard tap *
  page103_i35
#ISCELL
  standard tap *
  page103_i36
#ISCELL
  standard tap *
  page103_i37
#ISCELL
  standard tap *
  page103_i38
#ISCELL
  standard tap *
  page103_i39
#ISCELL
  standard offpage *
  page103_i4
#ISCELL
  standard tap *
  page103_i40
#ISCELL
  standard tap *
  page103_i41
#ISCELL
  standard tap *
  page103_i42
#ISCELL
  standard tap *
  page103_i43
#ISCELL
  standard tap *
  page103_i44
#ISCELL
  standard tap *
  page103_i45
#ISCELL
  standard tap *
  page103_i46
#ISCELL
  standard tap *
  page103_i47
#ISCELL
  standard tap *
  page103_i48
#ISCELL
  standard tap *
  page103_i49
#ISCELL
  standard offpage *
  page103_i5
#ISCELL
  standard tap *
  page103_i50
#CELL
  pure_quanta sconn288_adr50017p087cc *
  page103_i51
#ISCELL
  standard tap *
  page103_i52
#ISCELL
  standard tap *
  page103_i53
#ISCELL
  standard tap *
  page103_i54
#ISCELL
  standard tap *
  page103_i55
#ISCELL
  standard tap *
  page103_i56
#ISCELL
  standard tap *
  page103_i57
#ISCELL
  standard tap *
  page103_i58
#ISCELL
  standard tap *
  page103_i59
#ISCELL
  standard offpage *
  page103_i6
#ISCELL
  standard tap *
  page103_i60
#ISCELL
  standard tap *
  page103_i61
#ISCELL
  standard tap *
  page103_i62
#ISCELL
  standard tap *
  page103_i63
#ISCELL
  standard tap *
  page103_i64
#ISCELL
  standard tap *
  page103_i65
#ISCELL
  standard tap *
  page103_i66
#ISCELL
  standard tap *
  page103_i67
#ISCELL
  standard tap *
  page103_i68
#ISCELL
  standard tap *
  page103_i69
#ISCELL
  standard tap *
  page103_i70
#ISCELL
  standard tap *
  page103_i71
#ISCELL
  standard tap *
  page103_i72
#ISCELL
  standard tap *
  page103_i73
#ISCELL
  standard tap *
  page103_i74
#ISCELL
  standard tap *
  page103_i75
#ISCELL
  standard tap *
  page103_i76
#ISCELL
  standard tap *
  page103_i77
#ISCELL
  standard tap *
  page103_i78
#ISCELL
  standard tap *
  page103_i79
#ISCELL
  standard offpage *
  page103_i8
#ISCELL
  standard tap *
  page103_i80
#ISCELL
  standard tap *
  page103_i81
#ISCELL
  standard tap *
  page103_i82
#ISCELL
  standard tap *
  page103_i83
#ISCELL
  standard tap *
  page103_i84
#ISCELL
  standard tap *
  page103_i85
#ISCELL
  standard tap *
  page103_i86
#ISCELL
  standard tap *
  page103_i87
#ISCELL
  standard tap *
  page103_i88
#ISCELL
  standard tap *
  page103_i89
#ISCELL
  standard offpage *
  page103_i9
#ISCELL
  standard tap *
  page103_i90
#ISCELL
  standard tap *
  page103_i91
#ISCELL
  standard tap *
  page103_i92
#ISCELL
  standard tap *
  page103_i93
#ISCELL
  standard tap *
  page103_i94
#ISCELL
  standard tap *
  page103_i95
#ISCELL
  standard tap *
  page103_i96
#ISCELL
  standard tap *
  page103_i97
#ISCELL
  standard tap *
  page103_i98
#ISCELL
  standard tap *
  page103_i99
#ISCELL
  logical_power cad_note *
  *
#ISCELL
  pure_quanta quanta_title_block_c *
  *
#ISCELL
  logical_power universal_gnd *
  page104_i1
#ISCELL
  standard offpage *
  page104_i10
#ISCELL
  standard tap *
  page104_i100
#ISCELL
  standard tap *
  page104_i101
#ISCELL
  standard tap *
  page104_i102
#ISCELL
  standard tap *
  page104_i103
#ISCELL
  standard tap *
  page104_i104
#ISCELL
  standard tap *
  page104_i105
#ISCELL
  standard tap *
  page104_i106
#ISCELL
  standard tap *
  page104_i107
#ISCELL
  standard tap *
  page104_i108
#ISCELL
  standard tap *
  page104_i109
#ISCELL
  standard offpage *
  page104_i11
#ISCELL
  standard tap *
  page104_i110
#ISCELL
  standard tap *
  page104_i111
#ISCELL
  standard tap *
  page104_i112
#ISCELL
  standard tap *
  page104_i113
#ISCELL
  standard tap *
  page104_i114
#ISCELL
  standard tap *
  page104_i115
#ISCELL
  standard tap *
  page104_i116
#ISCELL
  standard tap *
  page104_i117
#ISCELL
  standard tap *
  page104_i118
#ISCELL
  standard tap *
  page104_i119
#ISCELL
  logical_power vcc_core *
  page104_i12
#ISCELL
  logical_power universal_gnd *
  page104_i120
#ISCELL
  logical_power universal_gnd *
  page104_i121
#CELL
  pure_quanta q_cap *
  page104_i122
#ISCELL
  logical_power vcc_core *
  page104_i123
#ISCELL
  standard offpage *
  page104_i124
#ISCELL
  standard offpage *
  page104_i125
#CELL
  pure_quanta q_cap *
  page104_i127
#ISCELL
  logical_power vcc_core *
  page104_i128
#CELL
  pure_quanta q_cap *
  page104_i129
#ISCELL
  standard offpage *
  page104_i13
#ISCELL
  standard tap *
  page104_i130
#ISCELL
  standard tap *
  page104_i131
#ISCELL
  standard tap *
  page104_i132
#ISCELL
  standard tap *
  page104_i133
#ISCELL
  standard tap *
  page104_i134
#ISCELL
  standard tap *
  page104_i135
#ISCELL
  standard tap *
  page104_i136
#ISCELL
  standard tap *
  page104_i137
#ISCELL
  standard tap *
  page104_i138
#ISCELL
  standard tap *
  page104_i139
#ISCELL
  standard offpage *
  page104_i14
#ISCELL
  standard tap *
  page104_i140
#ISCELL
  standard tap *
  page104_i141
#ISCELL
  standard tap *
  page104_i142
#ISCELL
  standard tap *
  page104_i143
#ISCELL
  standard tap *
  page104_i144
#ISCELL
  standard tap *
  page104_i145
#ISCELL
  standard tap *
  page104_i146
#ISCELL
  standard tap *
  page104_i147
#ISCELL
  standard tap *
  page104_i148
#ISCELL
  standard tap *
  page104_i149
#ISCELL
  standard offpage *
  page104_i15
#ISCELL
  standard tap *
  page104_i150
#ISCELL
  standard tap *
  page104_i151
#ISCELL
  standard tap *
  page104_i152
#ISCELL
  standard tap *
  page104_i153
#ISCELL
  standard tap *
  page104_i154
#ISCELL
  standard tap *
  page104_i155
#ISCELL
  standard tap *
  page104_i156
#ISCELL
  standard tap *
  page104_i157
#ISCELL
  standard tap *
  page104_i158
#ISCELL
  standard tap *
  page104_i159
#ISCELL
  standard offpage *
  page104_i16
#ISCELL
  standard tap *
  page104_i160
#ISCELL
  standard tap *
  page104_i161
#ISCELL
  standard tap *
  page104_i162
#ISCELL
  standard tap *
  page104_i163
#ISCELL
  standard tap *
  page104_i164
#ISCELL
  standard tap *
  page104_i165
#ISCELL
  standard tap *
  page104_i166
#ISCELL
  standard tap *
  page104_i167
#ISCELL
  standard tap *
  page104_i168
#ISCELL
  standard tap *
  page104_i169
#ISCELL
  standard offpage *
  page104_i17
#ISCELL
  standard offpage *
  page104_i170
#ISCELL
  standard offpage *
  page104_i171
#ISCELL
  standard offpage *
  page104_i172
#ISCELL
  standard offpage *
  page104_i173
#ISCELL
  logical_power universal_gnd *
  page104_i174
#CELL
  pure_quanta sconn288_adr50017p130cc *
  page104_i175
#ISCELL
  logical_power universal_gnd *
  page104_i176
#ISCELL
  logical_power vcc_core *
  page104_i177
#CELL
  pure_quanta sconn288_adr50017p130cc *
  page104_i178
#ISCELL
  standard offpage *
  page104_i179
#ISCELL
  standard offpage *
  page104_i18
#CELL
  pure_quanta q_res *
  page104_i180
#ISCELL
  standard offpage *
  page104_i19
#CELL
  pure_quanta q_res *
  page104_i2
#ISCELL
  standard offpage *
  page104_i20
#ISCELL
  standard offpage *
  page104_i21
#ISCELL
  standard offpage *
  page104_i22
#ISCELL
  standard offpage *
  page104_i23
#ISCELL
  standard offpage *
  page104_i24
#CELL
  pure_quanta sconn288_adr50017p130cc *
  page104_i25
#ISCELL
  standard tap *
  page104_i26
#ISCELL
  standard tap *
  page104_i27
#ISCELL
  standard tap *
  page104_i28
#ISCELL
  standard tap *
  page104_i29
#ISCELL
  standard offpage *
  page104_i3
#ISCELL
  standard tap *
  page104_i30
#ISCELL
  standard tap *
  page104_i31
#ISCELL
  standard tap *
  page104_i32
#ISCELL
  standard tap *
  page104_i33
#ISCELL
  standard tap *
  page104_i34
#ISCELL
  standard tap *
  page104_i35
#ISCELL
  standard tap *
  page104_i36
#ISCELL
  standard tap *
  page104_i37
#ISCELL
  standard tap *
  page104_i38
#ISCELL
  standard tap *
  page104_i39
#ISCELL
  standard offpage *
  page104_i4
#ISCELL
  standard tap *
  page104_i40
#ISCELL
  standard tap *
  page104_i41
#ISCELL
  standard tap *
  page104_i42
#ISCELL
  standard tap *
  page104_i43
#ISCELL
  standard tap *
  page104_i44
#ISCELL
  standard tap *
  page104_i45
#ISCELL
  standard tap *
  page104_i46
#ISCELL
  standard tap *
  page104_i47
#ISCELL
  standard tap *
  page104_i48
#ISCELL
  standard tap *
  page104_i49
#ISCELL
  standard offpage *
  page104_i5
#ISCELL
  standard tap *
  page104_i50
#ISCELL
  standard tap *
  page104_i51
#ISCELL
  standard tap *
  page104_i52
#ISCELL
  standard tap *
  page104_i53
#ISCELL
  standard tap *
  page104_i54
#ISCELL
  standard tap *
  page104_i55
#ISCELL
  standard tap *
  page104_i56
#ISCELL
  standard tap *
  page104_i57
#ISCELL
  standard tap *
  page104_i58
#ISCELL
  standard tap *
  page104_i59
#ISCELL
  standard offpage *
  page104_i6
#ISCELL
  standard tap *
  page104_i60
#ISCELL
  standard tap *
  page104_i61
#ISCELL
  standard tap *
  page104_i62
#ISCELL
  standard tap *
  page104_i63
#ISCELL
  standard tap *
  page104_i64
#ISCELL
  standard tap *
  page104_i65
#ISCELL
  standard tap *
  page104_i66
#ISCELL
  standard tap *
  page104_i67
#ISCELL
  standard tap *
  page104_i68
#ISCELL
  standard tap *
  page104_i69
#ISCELL
  standard offpage *
  page104_i7
#ISCELL
  standard tap *
  page104_i70
#ISCELL
  standard tap *
  page104_i71
#ISCELL
  standard tap *
  page104_i72
#ISCELL
  standard tap *
  page104_i73
#ISCELL
  standard tap *
  page104_i74
#ISCELL
  standard tap *
  page104_i75
#ISCELL
  standard tap *
  page104_i76
#ISCELL
  standard tap *
  page104_i77
#ISCELL
  standard tap *
  page104_i78
#ISCELL
  standard tap *
  page104_i79
#ISCELL
  standard tap *
  page104_i80
#ISCELL
  standard tap *
  page104_i81
#ISCELL
  standard tap *
  page104_i82
#ISCELL
  standard tap *
  page104_i83
#ISCELL
  standard tap *
  page104_i84
#ISCELL
  standard tap *
  page104_i85
#ISCELL
  standard tap *
  page104_i86
#ISCELL
  standard tap *
  page104_i87
#ISCELL
  standard tap *
  page104_i88
#ISCELL
  standard tap *
  page104_i89
#ISCELL
  standard offpage *
  page104_i9
#ISCELL
  standard tap *
  page104_i90
#ISCELL
  standard tap *
  page104_i91
#ISCELL
  standard tap *
  page104_i92
#ISCELL
  standard tap *
  page104_i93
#ISCELL
  standard tap *
  page104_i94
#ISCELL
  standard tap *
  page104_i95
#ISCELL
  standard tap *
  page104_i96
#ISCELL
  standard tap *
  page104_i97
#ISCELL
  standard tap *
  page104_i98
#ISCELL
  standard tap *
  page104_i99
#ISCELL
  logical_power cad_note *
  *
#ISCELL
  pure_quanta quanta_title_block_c *
  *
#ISCELL
  logical_power universal_gnd *
  page105_i1
#ISCELL
  standard offpage *
  page105_i10
#ISCELL
  standard tap *
  page105_i100
#ISCELL
  standard tap *
  page105_i101
#ISCELL
  standard tap *
  page105_i102
#ISCELL
  standard tap *
  page105_i103
#ISCELL
  standard tap *
  page105_i104
#ISCELL
  standard tap *
  page105_i105
#ISCELL
  standard tap *
  page105_i106
#ISCELL
  standard tap *
  page105_i107
#ISCELL
  standard tap *
  page105_i108
#ISCELL
  standard tap *
  page105_i109
#ISCELL
  standard offpage *
  page105_i11
#ISCELL
  standard tap *
  page105_i110
#ISCELL
  standard tap *
  page105_i111
#ISCELL
  standard tap *
  page105_i112
#ISCELL
  standard offpage *
  page105_i113
#ISCELL
  standard tap *
  page105_i114
#ISCELL
  standard tap *
  page105_i115
#ISCELL
  standard tap *
  page105_i116
#ISCELL
  standard tap *
  page105_i117
#ISCELL
  standard tap *
  page105_i118
#ISCELL
  standard tap *
  page105_i119
#ISCELL
  logical_power vcc_core *
  page105_i12
#ISCELL
  logical_power universal_gnd *
  page105_i120
#ISCELL
  logical_power universal_gnd *
  page105_i121
#ISCELL
  logical_power vcc_core *
  page105_i122
#CELL
  pure_quanta q_cap *
  page105_i123
#CELL
  pure_quanta q_cap *
  page105_i124
#ISCELL
  logical_power vcc_core *
  page105_i125
#ISCELL
  standard offpage *
  page105_i126
#ISCELL
  standard tap *
  page105_i128
#ISCELL
  standard tap *
  page105_i129
#ISCELL
  standard tap *
  page105_i130
#ISCELL
  standard tap *
  page105_i131
#ISCELL
  standard tap *
  page105_i132
#ISCELL
  standard tap *
  page105_i133
#ISCELL
  standard tap *
  page105_i134
#ISCELL
  standard tap *
  page105_i135
#ISCELL
  standard tap *
  page105_i136
#ISCELL
  standard tap *
  page105_i137
#ISCELL
  standard tap *
  page105_i138
#ISCELL
  standard tap *
  page105_i139
#ISCELL
  standard tap *
  page105_i14
#ISCELL
  standard tap *
  page105_i140
#ISCELL
  standard tap *
  page105_i141
#ISCELL
  standard tap *
  page105_i142
#ISCELL
  standard tap *
  page105_i143
#ISCELL
  standard tap *
  page105_i144
#ISCELL
  standard tap *
  page105_i145
#CELL
  pure_quanta q_cap *
  page105_i146
#ISCELL
  logical_power universal_gnd *
  page105_i147
#ISCELL
  standard tap *
  page105_i149
#ISCELL
  standard offpage *
  page105_i15
#ISCELL
  standard tap *
  page105_i150
#ISCELL
  standard tap *
  page105_i151
#ISCELL
  standard tap *
  page105_i152
#ISCELL
  standard tap *
  page105_i153
#ISCELL
  standard tap *
  page105_i154
#ISCELL
  standard tap *
  page105_i155
#ISCELL
  standard tap *
  page105_i156
#ISCELL
  standard tap *
  page105_i157
#ISCELL
  standard tap *
  page105_i158
#ISCELL
  standard tap *
  page105_i159
#ISCELL
  standard offpage *
  page105_i16
#ISCELL
  standard tap *
  page105_i160
#ISCELL
  standard tap *
  page105_i161
#ISCELL
  standard tap *
  page105_i162
#ISCELL
  standard tap *
  page105_i163
#ISCELL
  standard tap *
  page105_i164
#ISCELL
  standard tap *
  page105_i165
#ISCELL
  standard tap *
  page105_i166
#ISCELL
  standard tap *
  page105_i167
#ISCELL
  standard offpage *
  page105_i168
#ISCELL
  standard offpage *
  page105_i169
#ISCELL
  standard offpage *
  page105_i17
#ISCELL
  standard offpage *
  page105_i170
#ISCELL
  standard tap *
  page105_i171
#ISCELL
  standard tap *
  page105_i172
#ISCELL
  standard tap *
  page105_i173
#ISCELL
  standard offpage *
  page105_i174
#ISCELL
  standard offpage *
  page105_i175
#ISCELL
  logical_power vcc_core *
  page105_i176
#ISCELL
  logical_power universal_gnd *
  page105_i177
#CELL
  pure_quanta sconn288_adr50017p087cc *
  page105_i178
#ISCELL
  standard offpage *
  page105_i18
#CELL
  pure_quanta sconn288_adr50017p087cc *
  page105_i180
#CELL
  pure_quanta sconn288_adr50017p087cc *
  page105_i181
#ISCELL
  standard offpage *
  page105_i182
#CELL
  pure_quanta q_res *
  page105_i183
#ISCELL
  standard offpage *
  page105_i19
#CELL
  pure_quanta q_res *
  page105_i2
#ISCELL
  standard offpage *
  page105_i20
#ISCELL
  standard offpage *
  page105_i21
#ISCELL
  standard offpage *
  page105_i22
#ISCELL
  standard offpage *
  page105_i23
#ISCELL
  standard offpage *
  page105_i24
#ISCELL
  standard offpage *
  page105_i25
#ISCELL
  standard tap *
  page105_i26
#ISCELL
  standard tap *
  page105_i27
#ISCELL
  standard tap *
  page105_i28
#ISCELL
  standard tap *
  page105_i29
#ISCELL
  standard offpage *
  page105_i3
#ISCELL
  standard tap *
  page105_i30
#ISCELL
  standard tap *
  page105_i31
#ISCELL
  standard tap *
  page105_i32
#ISCELL
  standard tap *
  page105_i33
#ISCELL
  standard tap *
  page105_i34
#ISCELL
  standard tap *
  page105_i35
#ISCELL
  standard tap *
  page105_i36
#ISCELL
  standard tap *
  page105_i37
#ISCELL
  standard tap *
  page105_i38
#ISCELL
  standard tap *
  page105_i39
#ISCELL
  standard offpage *
  page105_i4
#ISCELL
  standard tap *
  page105_i40
#ISCELL
  standard tap *
  page105_i41
#ISCELL
  standard tap *
  page105_i42
#ISCELL
  standard tap *
  page105_i43
#ISCELL
  standard tap *
  page105_i44
#ISCELL
  standard tap *
  page105_i45
#ISCELL
  standard tap *
  page105_i46
#ISCELL
  standard tap *
  page105_i47
#ISCELL
  standard tap *
  page105_i48
#ISCELL
  standard tap *
  page105_i49
#ISCELL
  standard offpage *
  page105_i5
#ISCELL
  standard tap *
  page105_i50
#ISCELL
  standard tap *
  page105_i51
#ISCELL
  standard tap *
  page105_i52
#ISCELL
  standard tap *
  page105_i53
#ISCELL
  standard tap *
  page105_i54
#ISCELL
  standard tap *
  page105_i55
#ISCELL
  standard tap *
  page105_i56
#ISCELL
  standard tap *
  page105_i57
#ISCELL
  standard tap *
  page105_i58
#ISCELL
  standard tap *
  page105_i59
#ISCELL
  standard offpage *
  page105_i6
#ISCELL
  standard tap *
  page105_i60
#ISCELL
  standard tap *
  page105_i61
#ISCELL
  standard tap *
  page105_i62
#ISCELL
  standard tap *
  page105_i63
#ISCELL
  standard tap *
  page105_i64
#ISCELL
  standard tap *
  page105_i65
#ISCELL
  standard tap *
  page105_i66
#ISCELL
  standard tap *
  page105_i67
#ISCELL
  standard tap *
  page105_i68
#ISCELL
  standard tap *
  page105_i69
#ISCELL
  standard tap *
  page105_i70
#ISCELL
  standard tap *
  page105_i71
#ISCELL
  standard tap *
  page105_i72
#ISCELL
  standard tap *
  page105_i73
#ISCELL
  standard tap *
  page105_i74
#ISCELL
  standard tap *
  page105_i75
#ISCELL
  standard tap *
  page105_i76
#ISCELL
  standard tap *
  page105_i77
#ISCELL
  standard tap *
  page105_i78
#ISCELL
  standard tap *
  page105_i79
#ISCELL
  standard offpage *
  page105_i8
#ISCELL
  standard tap *
  page105_i80
#ISCELL
  standard tap *
  page105_i81
#ISCELL
  standard tap *
  page105_i82
#ISCELL
  standard tap *
  page105_i83
#ISCELL
  standard tap *
  page105_i84
#ISCELL
  standard tap *
  page105_i85
#ISCELL
  standard tap *
  page105_i86
#ISCELL
  standard tap *
  page105_i87
#ISCELL
  standard tap *
  page105_i88
#ISCELL
  standard tap *
  page105_i89
#ISCELL
  standard offpage *
  page105_i9
#ISCELL
  standard tap *
  page105_i90
#ISCELL
  standard tap *
  page105_i91
#ISCELL
  standard tap *
  page105_i92
#ISCELL
  standard tap *
  page105_i93
#ISCELL
  standard tap *
  page105_i94
#ISCELL
  standard tap *
  page105_i95
#ISCELL
  standard tap *
  page105_i96
#ISCELL
  standard tap *
  page105_i97
#ISCELL
  standard tap *
  page105_i98
#ISCELL
  standard tap *
  page105_i99
#ISCELL
  logical_power cad_note *
  *
#ISCELL
  pure_quanta quanta_title_block_c *
  *
#ISCELL
  logical_power universal_gnd *
  page106_i1
#ISCELL
  standard offpage *
  page106_i10
#ISCELL
  standard tap *
  page106_i100
#ISCELL
  standard tap *
  page106_i101
#ISCELL
  standard tap *
  page106_i102
#ISCELL
  standard tap *
  page106_i103
#ISCELL
  standard tap *
  page106_i104
#ISCELL
  standard tap *
  page106_i105
#ISCELL
  standard tap *
  page106_i106
#ISCELL
  standard tap *
  page106_i107
#ISCELL
  standard tap *
  page106_i108
#ISCELL
  standard tap *
  page106_i109
#ISCELL
  standard offpage *
  page106_i11
#ISCELL
  standard tap *
  page106_i110
#ISCELL
  standard tap *
  page106_i111
#ISCELL
  standard tap *
  page106_i112
#ISCELL
  standard tap *
  page106_i113
#ISCELL
  standard tap *
  page106_i114
#ISCELL
  standard tap *
  page106_i115
#ISCELL
  standard tap *
  page106_i116
#ISCELL
  standard tap *
  page106_i117
#ISCELL
  standard tap *
  page106_i118
#ISCELL
  standard tap *
  page106_i119
#ISCELL
  logical_power vcc_core *
  page106_i12
#ISCELL
  logical_power universal_gnd *
  page106_i120
#ISCELL
  logical_power universal_gnd *
  page106_i121
#CELL
  pure_quanta q_cap *
  page106_i122
#ISCELL
  logical_power vcc_core *
  page106_i123
#ISCELL
  standard offpage *
  page106_i124
#ISCELL
  standard offpage *
  page106_i125
#CELL
  pure_quanta q_cap *
  page106_i127
#ISCELL
  logical_power vcc_core *
  page106_i128
#ISCELL
  standard tap *
  page106_i129
#ISCELL
  standard offpage *
  page106_i13
#CELL
  pure_quanta q_cap *
  page106_i130
#ISCELL
  standard tap *
  page106_i131
#ISCELL
  standard tap *
  page106_i132
#ISCELL
  standard tap *
  page106_i133
#ISCELL
  standard tap *
  page106_i134
#ISCELL
  standard tap *
  page106_i135
#ISCELL
  standard tap *
  page106_i136
#ISCELL
  standard tap *
  page106_i137
#ISCELL
  standard tap *
  page106_i138
#ISCELL
  standard tap *
  page106_i139
#ISCELL
  standard offpage *
  page106_i14
#ISCELL
  standard tap *
  page106_i140
#ISCELL
  standard tap *
  page106_i141
#ISCELL
  standard tap *
  page106_i142
#ISCELL
  standard tap *
  page106_i143
#ISCELL
  standard tap *
  page106_i144
#ISCELL
  standard tap *
  page106_i145
#ISCELL
  standard tap *
  page106_i146
#ISCELL
  standard tap *
  page106_i147
#ISCELL
  standard tap *
  page106_i148
#ISCELL
  standard tap *
  page106_i149
#ISCELL
  standard offpage *
  page106_i15
#ISCELL
  standard tap *
  page106_i150
#ISCELL
  standard tap *
  page106_i151
#ISCELL
  standard tap *
  page106_i152
#ISCELL
  standard tap *
  page106_i153
#ISCELL
  standard tap *
  page106_i154
#ISCELL
  standard tap *
  page106_i155
#ISCELL
  standard tap *
  page106_i156
#ISCELL
  standard tap *
  page106_i157
#ISCELL
  standard tap *
  page106_i158
#ISCELL
  standard tap *
  page106_i159
#ISCELL
  standard offpage *
  page106_i16
#ISCELL
  standard tap *
  page106_i160
#ISCELL
  standard tap *
  page106_i161
#ISCELL
  standard tap *
  page106_i162
#ISCELL
  standard tap *
  page106_i163
#ISCELL
  standard tap *
  page106_i164
#ISCELL
  standard tap *
  page106_i165
#ISCELL
  standard tap *
  page106_i166
#ISCELL
  standard tap *
  page106_i167
#ISCELL
  standard tap *
  page106_i168
#ISCELL
  standard tap *
  page106_i169
#ISCELL
  standard offpage *
  page106_i17
#ISCELL
  standard offpage *
  page106_i170
#ISCELL
  standard offpage *
  page106_i171
#ISCELL
  standard offpage *
  page106_i172
#ISCELL
  standard offpage *
  page106_i173
#ISCELL
  logical_power universal_gnd *
  page106_i174
#ISCELL
  logical_power universal_gnd *
  page106_i176
#ISCELL
  logical_power vcc_core *
  page106_i177
#CELL
  pure_quanta sconn288_adr50017p130cc *
  page106_i178
#ISCELL
  standard offpage *
  page106_i18
#CELL
  pure_quanta sconn288_adr50017p130cc *
  page106_i180
#CELL
  pure_quanta sconn288_adr50017p130cc *
  page106_i181
#ISCELL
  standard offpage *
  page106_i182
#CELL
  pure_quanta q_res *
  page106_i183
#ISCELL
  standard offpage *
  page106_i19
#CELL
  pure_quanta q_res *
  page106_i2
#ISCELL
  standard offpage *
  page106_i20
#ISCELL
  standard offpage *
  page106_i21
#ISCELL
  standard offpage *
  page106_i22
#ISCELL
  standard offpage *
  page106_i23
#ISCELL
  standard offpage *
  page106_i24
#ISCELL
  standard tap *
  page106_i26
#ISCELL
  standard tap *
  page106_i27
#ISCELL
  standard tap *
  page106_i28
#ISCELL
  standard tap *
  page106_i29
#ISCELL
  standard offpage *
  page106_i3
#ISCELL
  standard tap *
  page106_i30
#ISCELL
  standard tap *
  page106_i31
#ISCELL
  standard tap *
  page106_i32
#ISCELL
  standard tap *
  page106_i33
#ISCELL
  standard tap *
  page106_i34
#ISCELL
  standard tap *
  page106_i35
#ISCELL
  standard tap *
  page106_i36
#ISCELL
  standard tap *
  page106_i37
#ISCELL
  standard tap *
  page106_i38
#ISCELL
  standard tap *
  page106_i39
#ISCELL
  standard offpage *
  page106_i4
#ISCELL
  standard tap *
  page106_i40
#ISCELL
  standard tap *
  page106_i41
#ISCELL
  standard tap *
  page106_i42
#ISCELL
  standard tap *
  page106_i43
#ISCELL
  standard tap *
  page106_i44
#ISCELL
  standard tap *
  page106_i45
#ISCELL
  standard tap *
  page106_i46
#ISCELL
  standard tap *
  page106_i47
#ISCELL
  standard tap *
  page106_i48
#ISCELL
  standard tap *
  page106_i49
#ISCELL
  standard offpage *
  page106_i5
#ISCELL
  standard tap *
  page106_i50
#ISCELL
  standard tap *
  page106_i51
#ISCELL
  standard tap *
  page106_i52
#ISCELL
  standard tap *
  page106_i53
#ISCELL
  standard tap *
  page106_i54
#ISCELL
  standard tap *
  page106_i55
#ISCELL
  standard tap *
  page106_i56
#ISCELL
  standard tap *
  page106_i57
#ISCELL
  standard tap *
  page106_i58
#ISCELL
  standard tap *
  page106_i59
#ISCELL
  standard offpage *
  page106_i6
#ISCELL
  standard tap *
  page106_i60
#ISCELL
  standard tap *
  page106_i61
#ISCELL
  standard tap *
  page106_i62
#ISCELL
  standard tap *
  page106_i63
#ISCELL
  standard tap *
  page106_i64
#ISCELL
  standard tap *
  page106_i65
#ISCELL
  standard tap *
  page106_i66
#ISCELL
  standard tap *
  page106_i67
#ISCELL
  standard tap *
  page106_i68
#ISCELL
  standard tap *
  page106_i69
#ISCELL
  standard offpage *
  page106_i7
#ISCELL
  standard tap *
  page106_i70
#ISCELL
  standard tap *
  page106_i71
#ISCELL
  standard tap *
  page106_i72
#ISCELL
  standard tap *
  page106_i73
#ISCELL
  standard tap *
  page106_i74
#ISCELL
  standard tap *
  page106_i75
#ISCELL
  standard tap *
  page106_i76
#ISCELL
  standard tap *
  page106_i77
#ISCELL
  standard tap *
  page106_i78
#ISCELL
  standard tap *
  page106_i79
#ISCELL
  standard tap *
  page106_i80
#ISCELL
  standard tap *
  page106_i81
#ISCELL
  standard tap *
  page106_i82
#ISCELL
  standard tap *
  page106_i83
#ISCELL
  standard tap *
  page106_i84
#ISCELL
  standard tap *
  page106_i85
#ISCELL
  standard tap *
  page106_i86
#ISCELL
  standard tap *
  page106_i87
#ISCELL
  standard tap *
  page106_i88
#ISCELL
  standard tap *
  page106_i89
#ISCELL
  standard offpage *
  page106_i9
#ISCELL
  standard tap *
  page106_i90
#ISCELL
  standard tap *
  page106_i91
#ISCELL
  standard tap *
  page106_i92
#ISCELL
  standard tap *
  page106_i93
#ISCELL
  standard tap *
  page106_i94
#ISCELL
  standard tap *
  page106_i95
#ISCELL
  standard tap *
  page106_i96
#ISCELL
  standard tap *
  page106_i97
#ISCELL
  standard tap *
  page106_i98
#ISCELL
  standard tap *
  page106_i99
#ISCELL
  logical_power cad_note *
  *
#ISCELL
  pure_quanta quanta_title_block_c *
  *
#ISCELL
  logical_power universal_gnd *
  page107_i1
#ISCELL
  standard offpage *
  page107_i10
#ISCELL
  standard tap *
  page107_i100
#ISCELL
  standard tap *
  page107_i101
#ISCELL
  standard tap *
  page107_i102
#ISCELL
  standard tap *
  page107_i103
#ISCELL
  standard tap *
  page107_i104
#ISCELL
  standard tap *
  page107_i105
#ISCELL
  standard tap *
  page107_i106
#ISCELL
  standard tap *
  page107_i107
#ISCELL
  standard tap *
  page107_i108
#ISCELL
  standard tap *
  page107_i109
#ISCELL
  standard offpage *
  page107_i11
#ISCELL
  standard tap *
  page107_i110
#ISCELL
  standard tap *
  page107_i111
#ISCELL
  standard tap *
  page107_i112
#ISCELL
  standard tap *
  page107_i113
#ISCELL
  standard tap *
  page107_i114
#ISCELL
  standard tap *
  page107_i115
#ISCELL
  standard tap *
  page107_i116
#ISCELL
  standard offpage *
  page107_i117
#ISCELL
  standard tap *
  page107_i118
#ISCELL
  standard tap *
  page107_i119
#ISCELL
  logical_power vcc_core *
  page107_i12
#ISCELL
  logical_power universal_gnd *
  page107_i120
#ISCELL
  logical_power universal_gnd *
  page107_i121
#CELL
  pure_quanta q_cap *
  page107_i122
#ISCELL
  logical_power vcc_core *
  page107_i123
#ISCELL
  standard offpage *
  page107_i124
#CELL
  pure_quanta q_cap *
  page107_i126
#ISCELL
  logical_power vcc_core *
  page107_i127
#CELL
  pure_quanta q_cap *
  page107_i128
#ISCELL
  standard tap *
  page107_i129
#ISCELL
  standard offpage *
  page107_i13
#ISCELL
  standard tap *
  page107_i130
#ISCELL
  standard tap *
  page107_i131
#ISCELL
  standard tap *
  page107_i132
#ISCELL
  standard tap *
  page107_i133
#ISCELL
  standard tap *
  page107_i134
#ISCELL
  standard tap *
  page107_i135
#ISCELL
  standard tap *
  page107_i136
#ISCELL
  standard tap *
  page107_i137
#ISCELL
  standard tap *
  page107_i138
#ISCELL
  standard tap *
  page107_i139
#ISCELL
  standard offpage *
  page107_i14
#ISCELL
  standard tap *
  page107_i140
#ISCELL
  standard tap *
  page107_i141
#ISCELL
  standard tap *
  page107_i142
#ISCELL
  standard tap *
  page107_i143
#ISCELL
  standard tap *
  page107_i144
#ISCELL
  standard tap *
  page107_i145
#ISCELL
  standard tap *
  page107_i146
#ISCELL
  standard tap *
  page107_i147
#ISCELL
  standard tap *
  page107_i148
#ISCELL
  standard tap *
  page107_i149
#ISCELL
  standard offpage *
  page107_i15
#ISCELL
  standard tap *
  page107_i150
#ISCELL
  standard tap *
  page107_i151
#ISCELL
  standard tap *
  page107_i152
#ISCELL
  standard tap *
  page107_i153
#ISCELL
  standard tap *
  page107_i154
#ISCELL
  standard tap *
  page107_i155
#ISCELL
  standard tap *
  page107_i156
#ISCELL
  standard tap *
  page107_i157
#ISCELL
  standard tap *
  page107_i158
#ISCELL
  standard tap *
  page107_i159
#ISCELL
  standard offpage *
  page107_i16
#ISCELL
  standard tap *
  page107_i160
#ISCELL
  standard tap *
  page107_i161
#ISCELL
  standard tap *
  page107_i162
#ISCELL
  standard tap *
  page107_i163
#ISCELL
  standard tap *
  page107_i164
#ISCELL
  standard tap *
  page107_i165
#ISCELL
  standard tap *
  page107_i166
#ISCELL
  standard tap *
  page107_i167
#ISCELL
  standard offpage *
  page107_i168
#ISCELL
  standard offpage *
  page107_i169
#ISCELL
  standard offpage *
  page107_i17
#ISCELL
  standard offpage *
  page107_i170
#ISCELL
  standard offpage *
  page107_i171
#ISCELL
  standard tap *
  page107_i172
#ISCELL
  standard offpage *
  page107_i173
#ISCELL
  logical_power universal_gnd *
  page107_i174
#ISCELL
  logical_power universal_gnd *
  page107_i176
#ISCELL
  logical_power vcc_core *
  page107_i177
#CELL
  pure_quanta sconn288_adr50017p087cc *
  page107_i179
#ISCELL
  standard offpage *
  page107_i18
#CELL
  pure_quanta sconn288_adr50017p087cc *
  page107_i180
#CELL
  pure_quanta sconn288_adr50017p087cc *
  page107_i181
#ISCELL
  standard offpage *
  page107_i182
#CELL
  pure_quanta q_res *
  page107_i183
#ISCELL
  standard offpage *
  page107_i19
#CELL
  pure_quanta q_res *
  page107_i2
#ISCELL
  standard offpage *
  page107_i20
#ISCELL
  standard offpage *
  page107_i21
#ISCELL
  standard offpage *
  page107_i22
#ISCELL
  standard offpage *
  page107_i23
#ISCELL
  standard tap *
  page107_i25
#ISCELL
  standard tap *
  page107_i26
#ISCELL
  standard tap *
  page107_i27
#ISCELL
  standard tap *
  page107_i28
#ISCELL
  standard tap *
  page107_i29
#ISCELL
  standard offpage *
  page107_i3
#ISCELL
  standard tap *
  page107_i30
#ISCELL
  standard tap *
  page107_i31
#ISCELL
  standard tap *
  page107_i32
#ISCELL
  standard tap *
  page107_i33
#ISCELL
  standard tap *
  page107_i34
#ISCELL
  standard tap *
  page107_i35
#ISCELL
  standard tap *
  page107_i36
#ISCELL
  standard tap *
  page107_i37
#ISCELL
  standard tap *
  page107_i38
#ISCELL
  standard tap *
  page107_i39
#ISCELL
  standard offpage *
  page107_i4
#ISCELL
  standard tap *
  page107_i40
#ISCELL
  standard tap *
  page107_i41
#ISCELL
  standard tap *
  page107_i42
#ISCELL
  standard tap *
  page107_i43
#ISCELL
  standard tap *
  page107_i44
#ISCELL
  standard tap *
  page107_i45
#ISCELL
  standard tap *
  page107_i46
#ISCELL
  standard tap *
  page107_i47
#ISCELL
  standard tap *
  page107_i48
#ISCELL
  standard tap *
  page107_i49
#ISCELL
  standard offpage *
  page107_i5
#ISCELL
  standard tap *
  page107_i50
#ISCELL
  standard tap *
  page107_i51
#ISCELL
  standard tap *
  page107_i52
#ISCELL
  standard tap *
  page107_i53
#ISCELL
  standard tap *
  page107_i54
#ISCELL
  standard tap *
  page107_i55
#ISCELL
  standard tap *
  page107_i56
#ISCELL
  standard tap *
  page107_i57
#ISCELL
  standard tap *
  page107_i58
#ISCELL
  standard tap *
  page107_i59
#ISCELL
  standard offpage *
  page107_i6
#ISCELL
  standard tap *
  page107_i60
#ISCELL
  standard tap *
  page107_i61
#ISCELL
  standard tap *
  page107_i62
#ISCELL
  standard tap *
  page107_i63
#ISCELL
  standard tap *
  page107_i64
#ISCELL
  standard tap *
  page107_i65
#ISCELL
  standard tap *
  page107_i66
#ISCELL
  standard tap *
  page107_i67
#ISCELL
  standard tap *
  page107_i68
#ISCELL
  standard tap *
  page107_i69
#ISCELL
  standard tap *
  page107_i70
#ISCELL
  standard tap *
  page107_i71
#ISCELL
  standard tap *
  page107_i72
#ISCELL
  standard tap *
  page107_i73
#ISCELL
  standard tap *
  page107_i74
#ISCELL
  standard tap *
  page107_i75
#ISCELL
  standard tap *
  page107_i76
#ISCELL
  standard tap *
  page107_i77
#ISCELL
  standard tap *
  page107_i78
#ISCELL
  standard tap *
  page107_i79
#ISCELL
  standard offpage *
  page107_i8
#ISCELL
  standard tap *
  page107_i80
#ISCELL
  standard tap *
  page107_i81
#ISCELL
  standard tap *
  page107_i82
#ISCELL
  standard tap *
  page107_i83
#ISCELL
  standard tap *
  page107_i84
#ISCELL
  standard tap *
  page107_i85
#ISCELL
  standard tap *
  page107_i86
#ISCELL
  standard tap *
  page107_i87
#ISCELL
  standard tap *
  page107_i88
#ISCELL
  standard tap *
  page107_i89
#ISCELL
  standard offpage *
  page107_i9
#ISCELL
  standard tap *
  page107_i90
#ISCELL
  standard tap *
  page107_i91
#ISCELL
  standard tap *
  page107_i92
#ISCELL
  standard tap *
  page107_i93
#ISCELL
  standard tap *
  page107_i94
#ISCELL
  standard tap *
  page107_i95
#ISCELL
  standard tap *
  page107_i96
#ISCELL
  standard tap *
  page107_i97
#ISCELL
  standard tap *
  page107_i98
#ISCELL
  standard tap *
  page107_i99
#ISCELL
  logical_power cad_note *
  *
#ISCELL
  pure_quanta quanta_title_block_c *
  *
#ISCELL
  standard offpage *
  page108_i1
#CELL
  pure_quanta q_res *
  page108_i10
#ISCELL
  standard tap *
  page108_i100
#ISCELL
  standard tap *
  page108_i101
#ISCELL
  standard tap *
  page108_i102
#ISCELL
  standard offpage *
  page108_i103
#ISCELL
  standard offpage *
  page108_i104
#ISCELL
  standard tap *
  page108_i105
#ISCELL
  standard tap *
  page108_i106
#ISCELL
  standard tap *
  page108_i107
#ISCELL
  standard tap *
  page108_i108
#ISCELL
  standard tap *
  page108_i109
#ISCELL
  standard offpage *
  page108_i11
#ISCELL
  standard tap *
  page108_i110
#ISCELL
  standard tap *
  page108_i111
#ISCELL
  standard tap *
  page108_i112
#ISCELL
  standard tap *
  page108_i113
#ISCELL
  standard tap *
  page108_i114
#ISCELL
  standard tap *
  page108_i115
#ISCELL
  standard tap *
  page108_i116
#ISCELL
  standard tap *
  page108_i117
#ISCELL
  standard tap *
  page108_i118
#ISCELL
  standard offpage *
  page108_i119
#ISCELL
  standard offpage *
  page108_i12
#ISCELL
  logical_power universal_gnd *
  page108_i120
#CELL
  pure_quanta q_cap *
  page108_i121
#ISCELL
  logical_power vcc_core *
  page108_i122
#CELL
  pure_quanta q_cap *
  page108_i123
#ISCELL
  logical_power vcc_core *
  page108_i124
#ISCELL
  standard tap *
  page108_i126
#ISCELL
  standard tap *
  page108_i127
#ISCELL
  standard tap *
  page108_i128
#ISCELL
  standard tap *
  page108_i129
#ISCELL
  standard offpage *
  page108_i13
#ISCELL
  standard tap *
  page108_i130
#ISCELL
  standard tap *
  page108_i131
#ISCELL
  standard tap *
  page108_i132
#ISCELL
  standard tap *
  page108_i133
#ISCELL
  standard tap *
  page108_i134
#ISCELL
  standard tap *
  page108_i135
#ISCELL
  standard tap *
  page108_i136
#ISCELL
  standard tap *
  page108_i137
#ISCELL
  standard tap *
  page108_i138
#ISCELL
  standard tap *
  page108_i139
#ISCELL
  standard offpage *
  page108_i14
#ISCELL
  standard tap *
  page108_i140
#ISCELL
  standard tap *
  page108_i141
#ISCELL
  standard tap *
  page108_i142
#ISCELL
  standard tap *
  page108_i143
#ISCELL
  standard tap *
  page108_i144
#ISCELL
  standard tap *
  page108_i145
#ISCELL
  standard tap *
  page108_i146
#ISCELL
  standard tap *
  page108_i147
#ISCELL
  standard tap *
  page108_i148
#ISCELL
  standard tap *
  page108_i149
#ISCELL
  logical_power vcc_core *
  page108_i15
#ISCELL
  standard tap *
  page108_i150
#ISCELL
  standard tap *
  page108_i151
#ISCELL
  standard tap *
  page108_i152
#ISCELL
  standard tap *
  page108_i153
#ISCELL
  standard tap *
  page108_i154
#ISCELL
  standard tap *
  page108_i155
#ISCELL
  standard tap *
  page108_i156
#ISCELL
  standard tap *
  page108_i157
#ISCELL
  standard tap *
  page108_i158
#ISCELL
  logical_power universal_gnd *
  page108_i159
#ISCELL
  standard offpage *
  page108_i16
#CELL
  pure_quanta q_cap *
  page108_i160
#ISCELL
  logical_power universal_gnd *
  page108_i161
#ISCELL
  standard offpage *
  page108_i163
#ISCELL
  standard offpage *
  page108_i164
#ISCELL
  standard tap *
  page108_i165
#ISCELL
  standard tap *
  page108_i166
#ISCELL
  standard tap *
  page108_i167
#ISCELL
  standard tap *
  page108_i168
#ISCELL
  standard tap *
  page108_i169
#ISCELL
  standard offpage *
  page108_i17
#ISCELL
  standard tap *
  page108_i170
#ISCELL
  standard tap *
  page108_i171
#ISCELL
  standard offpage *
  page108_i172
#ISCELL
  standard offpage *
  page108_i173
#ISCELL
  logical_power vcc_core *
  page108_i174
#ISCELL
  logical_power universal_gnd *
  page108_i175
#ISCELL
  standard tap *
  page108_i176
#CELL
  pure_quanta sconn288_adr50017p130cc *
  page108_i178
#CELL
  pure_quanta sconn288_adr50017p130cc *
  page108_i179
#ISCELL
  standard offpage *
  page108_i18
#CELL
  pure_quanta sconn288_adr50017p130cc *
  page108_i180
#ISCELL
  standard offpage *
  page108_i181
#CELL
  pure_quanta q_res *
  page108_i182
#ISCELL
  standard offpage *
  page108_i19
#ISCELL
  standard offpage *
  page108_i2
#ISCELL
  standard offpage *
  page108_i20
#ISCELL
  standard offpage *
  page108_i21
#ISCELL
  standard offpage *
  page108_i22
#ISCELL
  standard offpage *
  page108_i23
#ISCELL
  standard tap *
  page108_i24
#ISCELL
  standard tap *
  page108_i25
#ISCELL
  standard tap *
  page108_i26
#ISCELL
  standard tap *
  page108_i27
#ISCELL
  standard tap *
  page108_i28
#ISCELL
  standard tap *
  page108_i29
#ISCELL
  standard offpage *
  page108_i3
#ISCELL
  standard tap *
  page108_i30
#ISCELL
  standard tap *
  page108_i31
#ISCELL
  standard tap *
  page108_i32
#ISCELL
  standard tap *
  page108_i33
#ISCELL
  standard tap *
  page108_i34
#ISCELL
  standard tap *
  page108_i35
#ISCELL
  standard tap *
  page108_i36
#ISCELL
  standard tap *
  page108_i37
#ISCELL
  standard tap *
  page108_i38
#ISCELL
  standard tap *
  page108_i39
#ISCELL
  standard offpage *
  page108_i4
#ISCELL
  standard tap *
  page108_i40
#ISCELL
  standard tap *
  page108_i41
#ISCELL
  standard tap *
  page108_i42
#ISCELL
  standard tap *
  page108_i43
#ISCELL
  standard tap *
  page108_i44
#ISCELL
  standard tap *
  page108_i45
#ISCELL
  standard tap *
  page108_i46
#ISCELL
  standard tap *
  page108_i47
#ISCELL
  standard tap *
  page108_i48
#ISCELL
  standard tap *
  page108_i49
#ISCELL
  standard tap *
  page108_i50
#ISCELL
  standard tap *
  page108_i51
#ISCELL
  standard tap *
  page108_i52
#ISCELL
  standard tap *
  page108_i53
#ISCELL
  standard tap *
  page108_i54
#ISCELL
  standard tap *
  page108_i55
#ISCELL
  standard tap *
  page108_i56
#ISCELL
  standard tap *
  page108_i57
#ISCELL
  standard tap *
  page108_i58
#ISCELL
  standard tap *
  page108_i59
#ISCELL
  standard offpage *
  page108_i6
#ISCELL
  standard tap *
  page108_i60
#ISCELL
  standard tap *
  page108_i61
#ISCELL
  standard tap *
  page108_i62
#ISCELL
  standard tap *
  page108_i63
#ISCELL
  standard tap *
  page108_i64
#ISCELL
  standard tap *
  page108_i65
#ISCELL
  standard tap *
  page108_i66
#ISCELL
  standard tap *
  page108_i67
#ISCELL
  standard tap *
  page108_i68
#ISCELL
  standard tap *
  page108_i69
#ISCELL
  standard offpage *
  page108_i7
#ISCELL
  standard tap *
  page108_i70
#ISCELL
  standard tap *
  page108_i71
#ISCELL
  standard tap *
  page108_i72
#ISCELL
  standard tap *
  page108_i73
#ISCELL
  standard tap *
  page108_i74
#ISCELL
  standard tap *
  page108_i75
#ISCELL
  standard tap *
  page108_i76
#ISCELL
  standard tap *
  page108_i77
#ISCELL
  standard tap *
  page108_i78
#ISCELL
  standard tap *
  page108_i79
#ISCELL
  standard offpage *
  page108_i8
#ISCELL
  standard tap *
  page108_i80
#ISCELL
  standard tap *
  page108_i81
#ISCELL
  standard tap *
  page108_i82
#ISCELL
  standard tap *
  page108_i83
#ISCELL
  standard tap *
  page108_i84
#ISCELL
  standard tap *
  page108_i85
#ISCELL
  standard tap *
  page108_i86
#ISCELL
  standard tap *
  page108_i87
#ISCELL
  standard tap *
  page108_i88
#ISCELL
  standard tap *
  page108_i89
#ISCELL
  logical_power universal_gnd *
  page108_i9
#ISCELL
  standard tap *
  page108_i90
#ISCELL
  standard tap *
  page108_i91
#ISCELL
  standard tap *
  page108_i92
#ISCELL
  standard tap *
  page108_i93
#ISCELL
  standard tap *
  page108_i94
#ISCELL
  standard tap *
  page108_i95
#ISCELL
  standard tap *
  page108_i96
#ISCELL
  standard tap *
  page108_i97
#ISCELL
  standard tap *
  page108_i98
#ISCELL
  standard tap *
  page108_i99
#ISCELL
  logical_power cad_note *
  *
#ISCELL
  pure_quanta quanta_title_block_c *
  *
#ISCELL
  standard offpage *
  page109_i1
#ISCELL
  standard offpage *
  page109_i10
#ISCELL
  standard tap *
  page109_i100
#ISCELL
  standard tap *
  page109_i101
#ISCELL
  standard tap *
  page109_i102
#ISCELL
  standard tap *
  page109_i103
#ISCELL
  standard tap *
  page109_i104
#ISCELL
  standard offpage *
  page109_i105
#ISCELL
  standard tap *
  page109_i106
#ISCELL
  standard tap *
  page109_i107
#ISCELL
  standard tap *
  page109_i108
#ISCELL
  standard tap *
  page109_i109
#ISCELL
  standard offpage *
  page109_i11
#ISCELL
  standard tap *
  page109_i110
#ISCELL
  standard tap *
  page109_i111
#ISCELL
  standard tap *
  page109_i112
#ISCELL
  standard tap *
  page109_i113
#ISCELL
  standard tap *
  page109_i114
#ISCELL
  standard tap *
  page109_i115
#ISCELL
  standard tap *
  page109_i116
#ISCELL
  standard tap *
  page109_i117
#ISCELL
  standard tap *
  page109_i118
#ISCELL
  standard tap *
  page109_i119
#ISCELL
  standard offpage *
  page109_i12
#ISCELL
  logical_power universal_gnd *
  page109_i120
#CELL
  pure_quanta q_cap *
  page109_i121
#ISCELL
  logical_power vcc_core *
  page109_i122
#ISCELL
  standard offpage *
  page109_i123
#CELL
  pure_quanta q_cap *
  page109_i125
#ISCELL
  logical_power vcc_core *
  page109_i126
#ISCELL
  logical_power universal_gnd *
  page109_i127
#CELL
  pure_quanta q_cap *
  page109_i128
#ISCELL
  logical_power universal_gnd *
  page109_i129
#ISCELL
  standard offpage *
  page109_i13
#ISCELL
  standard tap *
  page109_i130
#ISCELL
  standard tap *
  page109_i131
#ISCELL
  standard tap *
  page109_i132
#ISCELL
  standard tap *
  page109_i133
#ISCELL
  standard tap *
  page109_i134
#ISCELL
  standard tap *
  page109_i135
#ISCELL
  standard tap *
  page109_i136
#ISCELL
  standard tap *
  page109_i137
#ISCELL
  standard tap *
  page109_i138
#ISCELL
  standard tap *
  page109_i139
#ISCELL
  standard offpage *
  page109_i14
#ISCELL
  standard tap *
  page109_i140
#ISCELL
  standard tap *
  page109_i141
#ISCELL
  standard tap *
  page109_i142
#ISCELL
  standard tap *
  page109_i143
#ISCELL
  standard tap *
  page109_i144
#ISCELL
  standard tap *
  page109_i145
#ISCELL
  standard tap *
  page109_i146
#ISCELL
  standard tap *
  page109_i147
#ISCELL
  standard tap *
  page109_i148
#ISCELL
  standard tap *
  page109_i149
#ISCELL
  standard offpage *
  page109_i15
#ISCELL
  standard tap *
  page109_i150
#ISCELL
  standard tap *
  page109_i151
#ISCELL
  standard tap *
  page109_i152
#ISCELL
  standard tap *
  page109_i153
#ISCELL
  standard tap *
  page109_i154
#ISCELL
  standard tap *
  page109_i155
#ISCELL
  standard tap *
  page109_i156
#ISCELL
  standard tap *
  page109_i157
#ISCELL
  standard tap *
  page109_i158
#ISCELL
  standard tap *
  page109_i159
#ISCELL
  standard offpage *
  page109_i16
#ISCELL
  standard tap *
  page109_i160
#ISCELL
  standard tap *
  page109_i161
#ISCELL
  standard tap *
  page109_i162
#ISCELL
  standard offpage *
  page109_i163
#ISCELL
  standard offpage *
  page109_i164
#ISCELL
  standard offpage *
  page109_i165
#ISCELL
  standard tap *
  page109_i166
#ISCELL
  standard tap *
  page109_i167
#ISCELL
  standard tap *
  page109_i168
#ISCELL
  standard tap *
  page109_i169
#ISCELL
  standard offpage *
  page109_i17
#ISCELL
  standard tap *
  page109_i170
#ISCELL
  standard tap *
  page109_i171
#ISCELL
  standard tap *
  page109_i172
#ISCELL
  standard offpage *
  page109_i173
#ISCELL
  standard offpage *
  page109_i174
#ISCELL
  logical_power vcc_core *
  page109_i175
#CELL
  pure_quanta sconn288_adr50017p087cc *
  page109_i176
#ISCELL
  logical_power universal_gnd *
  page109_i177
#CELL
  pure_quanta sconn288_adr50017p087cc *
  page109_i178
#ISCELL
  standard offpage *
  page109_i179
#ISCELL
  standard offpage *
  page109_i18
#CELL
  pure_quanta q_res *
  page109_i180
#ISCELL
  standard offpage *
  page109_i19
#ISCELL
  standard offpage *
  page109_i2
#ISCELL
  standard offpage *
  page109_i20
#ISCELL
  logical_power vcc_core *
  page109_i21
#ISCELL
  standard tap *
  page109_i22
#ISCELL
  standard tap *
  page109_i23
#ISCELL
  standard tap *
  page109_i24
#ISCELL
  standard tap *
  page109_i25
#ISCELL
  standard tap *
  page109_i26
#ISCELL
  standard tap *
  page109_i27
#ISCELL
  standard tap *
  page109_i28
#ISCELL
  standard tap *
  page109_i29
#ISCELL
  standard offpage *
  page109_i3
#ISCELL
  standard tap *
  page109_i30
#ISCELL
  standard tap *
  page109_i31
#ISCELL
  standard tap *
  page109_i32
#ISCELL
  standard tap *
  page109_i33
#ISCELL
  standard tap *
  page109_i34
#ISCELL
  standard tap *
  page109_i35
#ISCELL
  standard tap *
  page109_i36
#ISCELL
  standard tap *
  page109_i37
#ISCELL
  standard tap *
  page109_i38
#ISCELL
  standard tap *
  page109_i39
#ISCELL
  standard offpage *
  page109_i4
#ISCELL
  standard tap *
  page109_i40
#ISCELL
  standard tap *
  page109_i41
#ISCELL
  standard tap *
  page109_i42
#ISCELL
  standard tap *
  page109_i43
#ISCELL
  standard tap *
  page109_i44
#ISCELL
  logical_power universal_gnd *
  page109_i45
#CELL
  pure_quanta q_res *
  page109_i46
#CELL
  pure_quanta sconn288_adr50017p087cc *
  page109_i47
#ISCELL
  standard tap *
  page109_i48
#ISCELL
  standard tap *
  page109_i49
#ISCELL
  standard tap *
  page109_i50
#ISCELL
  standard tap *
  page109_i51
#ISCELL
  standard tap *
  page109_i52
#ISCELL
  standard tap *
  page109_i53
#ISCELL
  standard tap *
  page109_i54
#ISCELL
  standard tap *
  page109_i55
#ISCELL
  standard tap *
  page109_i56
#ISCELL
  standard tap *
  page109_i57
#ISCELL
  standard tap *
  page109_i58
#ISCELL
  standard tap *
  page109_i59
#ISCELL
  standard offpage *
  page109_i6
#ISCELL
  standard tap *
  page109_i60
#ISCELL
  standard tap *
  page109_i61
#ISCELL
  standard tap *
  page109_i62
#ISCELL
  standard tap *
  page109_i63
#ISCELL
  standard tap *
  page109_i64
#ISCELL
  standard tap *
  page109_i65
#ISCELL
  standard tap *
  page109_i66
#ISCELL
  standard tap *
  page109_i67
#ISCELL
  standard tap *
  page109_i68
#ISCELL
  standard tap *
  page109_i69
#ISCELL
  standard offpage *
  page109_i7
#ISCELL
  standard tap *
  page109_i70
#ISCELL
  standard tap *
  page109_i71
#ISCELL
  standard tap *
  page109_i72
#ISCELL
  standard tap *
  page109_i73
#ISCELL
  standard tap *
  page109_i74
#ISCELL
  standard tap *
  page109_i75
#ISCELL
  standard tap *
  page109_i76
#ISCELL
  standard tap *
  page109_i77
#ISCELL
  standard tap *
  page109_i78
#ISCELL
  standard tap *
  page109_i79
#ISCELL
  standard offpage *
  page109_i8
#ISCELL
  standard tap *
  page109_i80
#ISCELL
  standard tap *
  page109_i81
#ISCELL
  standard tap *
  page109_i82
#ISCELL
  standard tap *
  page109_i83
#ISCELL
  standard tap *
  page109_i84
#ISCELL
  standard tap *
  page109_i85
#ISCELL
  standard tap *
  page109_i86
#ISCELL
  standard tap *
  page109_i87
#ISCELL
  standard tap *
  page109_i88
#ISCELL
  standard tap *
  page109_i89
#ISCELL
  standard offpage *
  page109_i9
#ISCELL
  standard tap *
  page109_i90
#ISCELL
  standard tap *
  page109_i91
#ISCELL
  standard tap *
  page109_i92
#ISCELL
  standard tap *
  page109_i93
#ISCELL
  standard tap *
  page109_i94
#ISCELL
  standard tap *
  page109_i95
#ISCELL
  standard tap *
  page109_i96
#ISCELL
  standard tap *
  page109_i97
#ISCELL
  standard tap *
  page109_i98
#ISCELL
  standard tap *
  page109_i99
#ISCELL
  logical_power cad_note *
  *
#ISCELL
  pure_quanta quanta_title_block_c *
  *
#ISCELL
  logical_power universal_gnd *
  page110_i1
#ISCELL
  standard offpage *
  page110_i10
#ISCELL
  standard tap *
  page110_i100
#ISCELL
  standard tap *
  page110_i101
#ISCELL
  standard tap *
  page110_i102
#ISCELL
  standard tap *
  page110_i103
#ISCELL
  standard tap *
  page110_i104
#ISCELL
  standard tap *
  page110_i105
#ISCELL
  standard offpage *
  page110_i106
#ISCELL
  standard tap *
  page110_i107
#ISCELL
  standard tap *
  page110_i108
#ISCELL
  standard tap *
  page110_i109
#ISCELL
  standard offpage *
  page110_i11
#ISCELL
  standard tap *
  page110_i110
#ISCELL
  standard tap *
  page110_i111
#ISCELL
  standard tap *
  page110_i112
#ISCELL
  standard tap *
  page110_i113
#ISCELL
  standard tap *
  page110_i114
#ISCELL
  standard tap *
  page110_i115
#ISCELL
  standard tap *
  page110_i116
#ISCELL
  standard tap *
  page110_i117
#ISCELL
  standard tap *
  page110_i118
#ISCELL
  logical_power universal_gnd *
  page110_i119
#ISCELL
  standard offpage *
  page110_i12
#CELL
  pure_quanta q_cap *
  page110_i120
#ISCELL
  logical_power vcc_core *
  page110_i121
#ISCELL
  standard offpage *
  page110_i122
#CELL
  pure_quanta q_cap *
  page110_i124
#ISCELL
  logical_power vcc_core *
  page110_i125
#CELL
  pure_quanta q_cap *
  page110_i126
#ISCELL
  logical_power universal_gnd *
  page110_i127
#ISCELL
  logical_power universal_gnd *
  page110_i128
#ISCELL
  standard tap *
  page110_i129
#ISCELL
  standard offpage *
  page110_i13
#ISCELL
  standard tap *
  page110_i130
#ISCELL
  standard tap *
  page110_i131
#ISCELL
  standard tap *
  page110_i132
#ISCELL
  standard tap *
  page110_i133
#ISCELL
  standard tap *
  page110_i134
#ISCELL
  standard tap *
  page110_i135
#ISCELL
  standard tap *
  page110_i136
#ISCELL
  standard tap *
  page110_i137
#ISCELL
  standard tap *
  page110_i138
#ISCELL
  standard tap *
  page110_i139
#ISCELL
  standard offpage *
  page110_i14
#ISCELL
  standard tap *
  page110_i140
#ISCELL
  standard tap *
  page110_i141
#ISCELL
  standard tap *
  page110_i142
#ISCELL
  standard tap *
  page110_i143
#ISCELL
  standard tap *
  page110_i144
#ISCELL
  standard tap *
  page110_i145
#ISCELL
  standard tap *
  page110_i146
#ISCELL
  standard tap *
  page110_i147
#ISCELL
  standard tap *
  page110_i148
#ISCELL
  standard tap *
  page110_i149
#ISCELL
  standard offpage *
  page110_i15
#ISCELL
  standard tap *
  page110_i150
#ISCELL
  standard tap *
  page110_i151
#ISCELL
  standard tap *
  page110_i152
#ISCELL
  standard tap *
  page110_i153
#ISCELL
  standard tap *
  page110_i154
#ISCELL
  standard tap *
  page110_i155
#ISCELL
  standard tap *
  page110_i156
#ISCELL
  standard tap *
  page110_i157
#ISCELL
  standard tap *
  page110_i158
#ISCELL
  standard tap *
  page110_i159
#ISCELL
  standard offpage *
  page110_i16
#ISCELL
  standard tap *
  page110_i160
#ISCELL
  standard tap *
  page110_i161
#ISCELL
  standard tap *
  page110_i162
#ISCELL
  standard offpage *
  page110_i163
#ISCELL
  standard offpage *
  page110_i164
#ISCELL
  standard offpage *
  page110_i165
#ISCELL
  standard tap *
  page110_i166
#ISCELL
  standard tap *
  page110_i167
#ISCELL
  standard tap *
  page110_i168
#ISCELL
  standard tap *
  page110_i169
#ISCELL
  standard offpage *
  page110_i17
#ISCELL
  standard tap *
  page110_i170
#ISCELL
  standard tap *
  page110_i171
#ISCELL
  standard offpage *
  page110_i172
#ISCELL
  standard offpage *
  page110_i173
#ISCELL
  logical_power vcc_core *
  page110_i174
#ISCELL
  logical_power universal_gnd *
  page110_i176
#CELL
  pure_quanta sconn288_adr50017p130cc *
  page110_i178
#CELL
  pure_quanta sconn288_adr50017p130cc *
  page110_i179
#ISCELL
  standard offpage *
  page110_i18
#CELL
  pure_quanta sconn288_adr50017p130cc *
  page110_i180
#ISCELL
  standard offpage *
  page110_i181
#CELL
  pure_quanta q_res *
  page110_i182
#ISCELL
  standard offpage *
  page110_i19
#ISCELL
  standard offpage *
  page110_i2
#ISCELL
  standard offpage *
  page110_i20
#ISCELL
  standard offpage *
  page110_i21
#ISCELL
  logical_power vcc_core *
  page110_i22
#ISCELL
  standard tap *
  page110_i23
#ISCELL
  standard tap *
  page110_i24
#ISCELL
  standard tap *
  page110_i25
#ISCELL
  standard tap *
  page110_i26
#ISCELL
  standard tap *
  page110_i27
#ISCELL
  standard tap *
  page110_i28
#ISCELL
  standard tap *
  page110_i29
#ISCELL
  standard offpage *
  page110_i3
#ISCELL
  standard tap *
  page110_i30
#ISCELL
  standard tap *
  page110_i31
#ISCELL
  standard tap *
  page110_i32
#ISCELL
  standard tap *
  page110_i33
#ISCELL
  standard tap *
  page110_i34
#ISCELL
  standard tap *
  page110_i35
#ISCELL
  standard tap *
  page110_i36
#ISCELL
  standard tap *
  page110_i37
#ISCELL
  standard tap *
  page110_i38
#ISCELL
  standard tap *
  page110_i39
#ISCELL
  standard offpage *
  page110_i4
#ISCELL
  standard tap *
  page110_i40
#ISCELL
  standard tap *
  page110_i41
#ISCELL
  standard tap *
  page110_i42
#ISCELL
  standard tap *
  page110_i43
#ISCELL
  standard tap *
  page110_i44
#ISCELL
  standard tap *
  page110_i45
#ISCELL
  standard tap *
  page110_i46
#CELL
  pure_quanta q_res *
  page110_i47
#ISCELL
  standard tap *
  page110_i48
#ISCELL
  standard tap *
  page110_i49
#ISCELL
  standard offpage *
  page110_i5
#ISCELL
  standard tap *
  page110_i50
#ISCELL
  standard tap *
  page110_i51
#ISCELL
  standard tap *
  page110_i52
#ISCELL
  standard tap *
  page110_i53
#ISCELL
  standard tap *
  page110_i54
#ISCELL
  standard tap *
  page110_i55
#ISCELL
  standard tap *
  page110_i56
#ISCELL
  standard tap *
  page110_i57
#ISCELL
  standard tap *
  page110_i58
#ISCELL
  standard tap *
  page110_i59
#ISCELL
  standard tap *
  page110_i60
#ISCELL
  standard tap *
  page110_i61
#ISCELL
  standard tap *
  page110_i62
#ISCELL
  standard tap *
  page110_i63
#ISCELL
  standard tap *
  page110_i64
#ISCELL
  standard tap *
  page110_i65
#ISCELL
  standard tap *
  page110_i66
#ISCELL
  standard tap *
  page110_i67
#ISCELL
  standard tap *
  page110_i68
#ISCELL
  standard tap *
  page110_i69
#ISCELL
  standard offpage *
  page110_i7
#ISCELL
  standard tap *
  page110_i70
#ISCELL
  standard tap *
  page110_i71
#ISCELL
  standard tap *
  page110_i72
#ISCELL
  standard tap *
  page110_i73
#ISCELL
  standard tap *
  page110_i74
#ISCELL
  standard tap *
  page110_i75
#ISCELL
  standard tap *
  page110_i76
#ISCELL
  standard tap *
  page110_i77
#ISCELL
  standard tap *
  page110_i78
#ISCELL
  standard tap *
  page110_i79
#ISCELL
  standard offpage *
  page110_i8
#ISCELL
  standard tap *
  page110_i80
#ISCELL
  standard tap *
  page110_i81
#ISCELL
  standard tap *
  page110_i82
#ISCELL
  standard tap *
  page110_i83
#ISCELL
  standard tap *
  page110_i84
#ISCELL
  standard tap *
  page110_i85
#ISCELL
  standard tap *
  page110_i86
#ISCELL
  standard tap *
  page110_i87
#ISCELL
  standard tap *
  page110_i88
#ISCELL
  standard tap *
  page110_i89
#ISCELL
  standard offpage *
  page110_i9
#ISCELL
  standard tap *
  page110_i90
#ISCELL
  standard tap *
  page110_i91
#ISCELL
  standard tap *
  page110_i92
#ISCELL
  standard tap *
  page110_i93
#ISCELL
  standard tap *
  page110_i94
#ISCELL
  standard tap *
  page110_i95
#ISCELL
  standard tap *
  page110_i96
#ISCELL
  standard tap *
  page110_i97
#ISCELL
  standard tap *
  page110_i98
#ISCELL
  standard tap *
  page110_i99
#ISCELL
  logical_power cad_note *
  *
#ISCELL
  pure_quanta quanta_title_block_c *
  *
#ISCELL
  standard offpage *
  page111_i1
#ISCELL
  standard offpage *
  page111_i10
#ISCELL
  standard tap *
  page111_i100
#ISCELL
  standard offpage *
  page111_i101
#ISCELL
  standard tap *
  page111_i102
#ISCELL
  standard tap *
  page111_i103
#ISCELL
  standard tap *
  page111_i104
#ISCELL
  standard tap *
  page111_i105
#ISCELL
  standard tap *
  page111_i106
#ISCELL
  standard tap *
  page111_i107
#ISCELL
  standard tap *
  page111_i108
#ISCELL
  standard tap *
  page111_i109
#ISCELL
  standard offpage *
  page111_i11
#ISCELL
  standard tap *
  page111_i110
#ISCELL
  standard tap *
  page111_i111
#ISCELL
  standard tap *
  page111_i112
#ISCELL
  standard tap *
  page111_i113
#ISCELL
  standard tap *
  page111_i114
#ISCELL
  standard tap *
  page111_i115
#ISCELL
  standard tap *
  page111_i116
#ISCELL
  standard tap *
  page111_i117
#ISCELL
  standard tap *
  page111_i118
#ISCELL
  standard tap *
  page111_i119
#ISCELL
  standard offpage *
  page111_i12
#ISCELL
  standard tap *
  page111_i120
#ISCELL
  standard tap *
  page111_i121
#ISCELL
  standard tap *
  page111_i122
#ISCELL
  standard tap *
  page111_i123
#ISCELL
  standard tap *
  page111_i124
#ISCELL
  standard tap *
  page111_i125
#ISCELL
  standard tap *
  page111_i126
#ISCELL
  standard tap *
  page111_i127
#ISCELL
  standard offpage *
  page111_i128
#ISCELL
  standard offpage *
  page111_i13
#ISCELL
  standard tap *
  page111_i130
#ISCELL
  standard tap *
  page111_i131
#ISCELL
  standard tap *
  page111_i132
#ISCELL
  standard tap *
  page111_i133
#ISCELL
  standard tap *
  page111_i134
#ISCELL
  standard tap *
  page111_i135
#ISCELL
  standard tap *
  page111_i136
#ISCELL
  standard tap *
  page111_i137
#ISCELL
  standard tap *
  page111_i138
#ISCELL
  standard tap *
  page111_i139
#ISCELL
  standard offpage *
  page111_i14
#ISCELL
  standard tap *
  page111_i140
#ISCELL
  standard tap *
  page111_i141
#ISCELL
  standard tap *
  page111_i142
#ISCELL
  standard tap *
  page111_i143
#ISCELL
  standard tap *
  page111_i144
#ISCELL
  standard tap *
  page111_i145
#ISCELL
  standard tap *
  page111_i146
#ISCELL
  standard tap *
  page111_i147
#ISCELL
  standard tap *
  page111_i148
#ISCELL
  standard tap *
  page111_i149
#ISCELL
  standard offpage *
  page111_i15
#ISCELL
  standard tap *
  page111_i150
#ISCELL
  standard tap *
  page111_i151
#ISCELL
  standard tap *
  page111_i152
#ISCELL
  standard tap *
  page111_i153
#ISCELL
  standard tap *
  page111_i154
#ISCELL
  standard tap *
  page111_i155
#ISCELL
  standard tap *
  page111_i156
#ISCELL
  standard tap *
  page111_i157
#ISCELL
  standard tap *
  page111_i158
#ISCELL
  standard tap *
  page111_i159
#ISCELL
  standard offpage *
  page111_i16
#ISCELL
  standard tap *
  page111_i160
#ISCELL
  standard tap *
  page111_i161
#ISCELL
  standard tap *
  page111_i162
#ISCELL
  standard tap *
  page111_i163
#ISCELL
  standard tap *
  page111_i164
#ISCELL
  standard tap *
  page111_i165
#ISCELL
  standard tap *
  page111_i166
#ISCELL
  standard tap *
  page111_i167
#ISCELL
  standard tap *
  page111_i168
#ISCELL
  standard tap *
  page111_i169
#ISCELL
  standard offpage *
  page111_i17
#ISCELL
  standard offpage *
  page111_i170
#ISCELL
  standard offpage *
  page111_i171
#ISCELL
  standard offpage *
  page111_i172
#ISCELL
  standard offpage *
  page111_i173
#ISCELL
  logical_power vcc_core *
  page111_i174
#ISCELL
  standard offpage *
  page111_i175
#ISCELL
  standard offpage *
  page111_i176
#CELL
  pure_quanta sconn288_adr50017p087cc *
  page111_i178
#CELL
  pure_quanta sconn288_adr50017p087cc *
  page111_i179
#ISCELL
  standard offpage *
  page111_i18
#CELL
  pure_quanta sconn288_adr50017p087cc *
  page111_i180
#ISCELL
  standard offpage *
  page111_i181
#CELL
  pure_quanta q_res *
  page111_i182
#ISCELL
  standard offpage *
  page111_i19
#ISCELL
  standard offpage *
  page111_i2
#ISCELL
  standard offpage *
  page111_i20
#ISCELL
  standard offpage *
  page111_i21
#ISCELL
  logical_power vcc_core *
  page111_i22
#ISCELL
  standard tap *
  page111_i23
#ISCELL
  standard tap *
  page111_i24
#ISCELL
  standard tap *
  page111_i25
#ISCELL
  standard tap *
  page111_i26
#ISCELL
  standard tap *
  page111_i27
#ISCELL
  standard tap *
  page111_i28
#ISCELL
  standard tap *
  page111_i29
#ISCELL
  standard offpage *
  page111_i3
#ISCELL
  standard tap *
  page111_i30
#ISCELL
  standard tap *
  page111_i31
#ISCELL
  standard tap *
  page111_i32
#ISCELL
  standard tap *
  page111_i33
#ISCELL
  standard tap *
  page111_i34
#ISCELL
  standard tap *
  page111_i35
#ISCELL
  standard tap *
  page111_i36
#ISCELL
  standard tap *
  page111_i37
#ISCELL
  standard tap *
  page111_i38
#ISCELL
  standard tap *
  page111_i39
#ISCELL
  logical_power universal_gnd *
  page111_i4
#ISCELL
  standard tap *
  page111_i40
#ISCELL
  standard tap *
  page111_i41
#ISCELL
  standard tap *
  page111_i42
#ISCELL
  standard tap *
  page111_i43
#ISCELL
  standard tap *
  page111_i44
#ISCELL
  standard tap *
  page111_i45
#ISCELL
  standard tap *
  page111_i46
#ISCELL
  standard tap *
  page111_i47
#ISCELL
  standard tap *
  page111_i48
#ISCELL
  standard tap *
  page111_i49
#CELL
  pure_quanta q_res *
  page111_i5
#ISCELL
  standard tap *
  page111_i50
#ISCELL
  standard tap *
  page111_i51
#ISCELL
  standard tap *
  page111_i52
#ISCELL
  logical_power universal_gnd *
  page111_i53
#CELL
  pure_quanta q_cap *
  page111_i54
#ISCELL
  logical_power vcc_core *
  page111_i55
#CELL
  pure_quanta q_cap *
  page111_i56
#ISCELL
  logical_power vcc_core *
  page111_i57
#ISCELL
  logical_power universal_gnd *
  page111_i58
#CELL
  pure_quanta q_cap *
  page111_i59
#ISCELL
  standard offpage *
  page111_i6
#ISCELL
  logical_power universal_gnd *
  page111_i60
#ISCELL
  logical_power universal_gnd *
  page111_i62
#ISCELL
  standard tap *
  page111_i63
#ISCELL
  standard tap *
  page111_i64
#ISCELL
  standard tap *
  page111_i65
#ISCELL
  standard tap *
  page111_i66
#ISCELL
  standard tap *
  page111_i67
#ISCELL
  standard tap *
  page111_i68
#ISCELL
  standard tap *
  page111_i69
#ISCELL
  standard tap *
  page111_i70
#ISCELL
  standard tap *
  page111_i71
#ISCELL
  standard tap *
  page111_i72
#ISCELL
  standard tap *
  page111_i73
#ISCELL
  standard tap *
  page111_i74
#ISCELL
  standard tap *
  page111_i75
#ISCELL
  standard tap *
  page111_i76
#ISCELL
  standard tap *
  page111_i77
#ISCELL
  standard tap *
  page111_i78
#ISCELL
  standard tap *
  page111_i79
#ISCELL
  standard offpage *
  page111_i8
#ISCELL
  standard tap *
  page111_i80
#ISCELL
  standard tap *
  page111_i81
#ISCELL
  standard tap *
  page111_i82
#ISCELL
  standard tap *
  page111_i83
#ISCELL
  standard tap *
  page111_i84
#ISCELL
  standard tap *
  page111_i85
#ISCELL
  standard tap *
  page111_i86
#ISCELL
  standard tap *
  page111_i87
#ISCELL
  standard tap *
  page111_i88
#ISCELL
  standard tap *
  page111_i89
#ISCELL
  standard offpage *
  page111_i9
#ISCELL
  standard tap *
  page111_i90
#ISCELL
  standard tap *
  page111_i91
#ISCELL
  standard tap *
  page111_i92
#ISCELL
  standard tap *
  page111_i93
#ISCELL
  standard tap *
  page111_i94
#ISCELL
  standard tap *
  page111_i95
#ISCELL
  standard tap *
  page111_i96
#ISCELL
  standard tap *
  page111_i97
#ISCELL
  standard tap *
  page111_i98
#ISCELL
  standard tap *
  page111_i99
#ISCELL
  logical_power cad_note *
  *
#ISCELL
  pure_quanta quanta_title_block_c *
  *
#ISCELL
  standard offpage *
  page112_i1
#ISCELL
  standard offpage *
  page112_i10
#ISCELL
  standard tap *
  page112_i100
#ISCELL
  standard offpage *
  page112_i101
#ISCELL
  standard tap *
  page112_i102
#ISCELL
  standard tap *
  page112_i103
#ISCELL
  standard tap *
  page112_i104
#ISCELL
  standard tap *
  page112_i105
#ISCELL
  standard tap *
  page112_i106
#ISCELL
  standard tap *
  page112_i107
#ISCELL
  standard tap *
  page112_i108
#ISCELL
  standard tap *
  page112_i109
#ISCELL
  standard offpage *
  page112_i11
#ISCELL
  standard tap *
  page112_i110
#ISCELL
  standard tap *
  page112_i111
#ISCELL
  standard tap *
  page112_i112
#ISCELL
  standard tap *
  page112_i113
#ISCELL
  standard tap *
  page112_i114
#ISCELL
  standard tap *
  page112_i115
#ISCELL
  standard tap *
  page112_i116
#ISCELL
  standard tap *
  page112_i117
#ISCELL
  standard tap *
  page112_i118
#ISCELL
  standard tap *
  page112_i119
#ISCELL
  logical_power vcc_core *
  page112_i12
#ISCELL
  standard tap *
  page112_i120
#ISCELL
  standard offpage *
  page112_i121
#ISCELL
  logical_power universal_gnd *
  page112_i122
#ISCELL
  logical_power universal_gnd *
  page112_i123
#CELL
  pure_quanta q_cap *
  page112_i124
#CELL
  pure_quanta q_cap *
  page112_i125
#CELL
  pure_quanta q_cap *
  page112_i126
#ISCELL
  logical_power vcc_core *
  page112_i127
#ISCELL
  logical_power vcc_core *
  page112_i129
#ISCELL
  standard tap *
  page112_i130
#ISCELL
  standard tap *
  page112_i131
#ISCELL
  standard tap *
  page112_i132
#ISCELL
  standard tap *
  page112_i133
#ISCELL
  standard tap *
  page112_i134
#ISCELL
  standard tap *
  page112_i135
#ISCELL
  standard tap *
  page112_i136
#ISCELL
  standard tap *
  page112_i137
#ISCELL
  standard tap *
  page112_i138
#ISCELL
  standard tap *
  page112_i139
#ISCELL
  standard tap *
  page112_i14
#ISCELL
  standard tap *
  page112_i140
#ISCELL
  standard tap *
  page112_i141
#ISCELL
  standard tap *
  page112_i142
#ISCELL
  standard tap *
  page112_i143
#ISCELL
  standard tap *
  page112_i144
#ISCELL
  standard tap *
  page112_i145
#ISCELL
  standard tap *
  page112_i146
#ISCELL
  standard tap *
  page112_i147
#ISCELL
  standard tap *
  page112_i148
#ISCELL
  standard tap *
  page112_i149
#ISCELL
  standard tap *
  page112_i15
#ISCELL
  standard tap *
  page112_i150
#ISCELL
  standard tap *
  page112_i151
#ISCELL
  standard tap *
  page112_i152
#ISCELL
  standard tap *
  page112_i153
#ISCELL
  standard tap *
  page112_i154
#ISCELL
  standard tap *
  page112_i155
#ISCELL
  standard tap *
  page112_i156
#ISCELL
  standard tap *
  page112_i157
#ISCELL
  standard tap *
  page112_i158
#ISCELL
  standard tap *
  page112_i159
#ISCELL
  standard tap *
  page112_i16
#ISCELL
  standard tap *
  page112_i160
#ISCELL
  standard tap *
  page112_i161
#ISCELL
  standard tap *
  page112_i162
#ISCELL
  standard tap *
  page112_i163
#ISCELL
  standard tap *
  page112_i164
#ISCELL
  standard tap *
  page112_i165
#ISCELL
  standard tap *
  page112_i166
#ISCELL
  standard tap *
  page112_i167
#ISCELL
  standard tap *
  page112_i168
#ISCELL
  standard tap *
  page112_i169
#ISCELL
  standard tap *
  page112_i17
#ISCELL
  logical_power universal_gnd *
  page112_i170
#ISCELL
  standard offpage *
  page112_i172
#ISCELL
  standard offpage *
  page112_i173
#ISCELL
  standard offpage *
  page112_i174
#ISCELL
  standard offpage *
  page112_i175
#ISCELL
  logical_power vcc_core *
  page112_i176
#ISCELL
  logical_power universal_gnd *
  page112_i177
#CELL
  pure_quanta sconn288_adr50017p130cc *
  page112_i178
#ISCELL
  standard tap *
  page112_i18
#CELL
  pure_quanta sconn288_adr50017p130cc *
  page112_i180
#CELL
  pure_quanta sconn288_adr50017p130cc *
  page112_i181
#ISCELL
  standard offpage *
  page112_i182
#CELL
  pure_quanta q_res *
  page112_i183
#ISCELL
  standard tap *
  page112_i19
#ISCELL
  logical_power universal_gnd *
  page112_i2
#ISCELL
  standard offpage *
  page112_i20
#ISCELL
  standard offpage *
  page112_i21
#ISCELL
  standard offpage *
  page112_i22
#ISCELL
  standard offpage *
  page112_i23
#ISCELL
  standard offpage *
  page112_i24
#ISCELL
  standard offpage *
  page112_i25
#ISCELL
  standard offpage *
  page112_i26
#ISCELL
  standard offpage *
  page112_i27
#ISCELL
  standard offpage *
  page112_i28
#ISCELL
  standard offpage *
  page112_i29
#CELL
  pure_quanta q_res *
  page112_i3
#ISCELL
  standard offpage *
  page112_i30
#ISCELL
  standard offpage *
  page112_i31
#ISCELL
  standard tap *
  page112_i32
#ISCELL
  standard tap *
  page112_i33
#ISCELL
  standard tap *
  page112_i34
#ISCELL
  standard tap *
  page112_i35
#ISCELL
  standard tap *
  page112_i36
#ISCELL
  standard tap *
  page112_i37
#ISCELL
  standard tap *
  page112_i38
#ISCELL
  standard tap *
  page112_i39
#ISCELL
  standard offpage *
  page112_i4
#ISCELL
  standard tap *
  page112_i40
#ISCELL
  standard tap *
  page112_i41
#ISCELL
  standard tap *
  page112_i42
#ISCELL
  standard tap *
  page112_i43
#ISCELL
  standard tap *
  page112_i44
#ISCELL
  standard tap *
  page112_i45
#ISCELL
  standard tap *
  page112_i46
#ISCELL
  standard tap *
  page112_i47
#ISCELL
  standard tap *
  page112_i48
#ISCELL
  standard tap *
  page112_i49
#ISCELL
  standard offpage *
  page112_i5
#ISCELL
  standard tap *
  page112_i50
#ISCELL
  standard tap *
  page112_i51
#ISCELL
  standard tap *
  page112_i52
#ISCELL
  standard tap *
  page112_i53
#ISCELL
  standard tap *
  page112_i54
#ISCELL
  standard tap *
  page112_i55
#ISCELL
  standard tap *
  page112_i56
#ISCELL
  standard tap *
  page112_i57
#ISCELL
  standard tap *
  page112_i58
#ISCELL
  standard tap *
  page112_i59
#ISCELL
  standard offpage *
  page112_i6
#ISCELL
  standard tap *
  page112_i60
#ISCELL
  standard tap *
  page112_i61
#ISCELL
  standard tap *
  page112_i62
#ISCELL
  standard tap *
  page112_i63
#ISCELL
  standard tap *
  page112_i64
#ISCELL
  standard tap *
  page112_i65
#ISCELL
  standard tap *
  page112_i66
#ISCELL
  standard tap *
  page112_i67
#ISCELL
  standard tap *
  page112_i68
#ISCELL
  standard tap *
  page112_i69
#ISCELL
  standard tap *
  page112_i70
#ISCELL
  standard tap *
  page112_i71
#ISCELL
  standard tap *
  page112_i72
#ISCELL
  standard tap *
  page112_i73
#ISCELL
  standard tap *
  page112_i74
#ISCELL
  standard tap *
  page112_i75
#ISCELL
  standard tap *
  page112_i76
#ISCELL
  standard tap *
  page112_i77
#ISCELL
  standard tap *
  page112_i78
#ISCELL
  standard tap *
  page112_i79
#ISCELL
  standard offpage *
  page112_i8
#ISCELL
  standard tap *
  page112_i80
#ISCELL
  standard tap *
  page112_i81
#ISCELL
  standard tap *
  page112_i82
#ISCELL
  standard tap *
  page112_i83
#ISCELL
  standard tap *
  page112_i84
#ISCELL
  standard tap *
  page112_i85
#ISCELL
  standard tap *
  page112_i86
#ISCELL
  standard tap *
  page112_i87
#ISCELL
  standard tap *
  page112_i88
#ISCELL
  standard tap *
  page112_i89
#ISCELL
  standard offpage *
  page112_i9
#ISCELL
  standard tap *
  page112_i90
#ISCELL
  standard tap *
  page112_i91
#ISCELL
  standard tap *
  page112_i92
#ISCELL
  standard tap *
  page112_i93
#ISCELL
  standard tap *
  page112_i94
#ISCELL
  standard tap *
  page112_i95
#ISCELL
  standard tap *
  page112_i96
#ISCELL
  standard tap *
  page112_i97
#ISCELL
  standard tap *
  page112_i98
#ISCELL
  standard tap *
  page112_i99
#ISCELL
  logical_power cad_note *
  *
#ISCELL
  pure_quanta quanta_title_block_c *
  *
#ISCELL
  logical_power universal_gnd *
  page113_i1
#ISCELL
  standard offpage *
  page113_i10
#ISCELL
  standard tap *
  page113_i100
#ISCELL
  standard tap *
  page113_i101
#ISCELL
  standard tap *
  page113_i102
#ISCELL
  standard tap *
  page113_i103
#ISCELL
  standard tap *
  page113_i104
#ISCELL
  standard tap *
  page113_i105
#ISCELL
  standard tap *
  page113_i106
#ISCELL
  standard tap *
  page113_i107
#ISCELL
  standard tap *
  page113_i108
#ISCELL
  standard offpage *
  page113_i109
#ISCELL
  standard offpage *
  page113_i11
#ISCELL
  standard tap *
  page113_i110
#ISCELL
  standard tap *
  page113_i111
#ISCELL
  standard tap *
  page113_i112
#ISCELL
  standard tap *
  page113_i113
#ISCELL
  logical_power universal_gnd *
  page113_i114
#ISCELL
  logical_power universal_gnd *
  page113_i115
#CELL
  pure_quanta q_cap *
  page113_i116
#ISCELL
  logical_power vcc_core *
  page113_i117
#ISCELL
  standard offpage *
  page113_i119
#ISCELL
  logical_power vcc_core *
  page113_i12
#CELL
  pure_quanta q_cap *
  page113_i120
#ISCELL
  logical_power vcc_core *
  page113_i121
#CELL
  pure_quanta q_cap *
  page113_i122
#ISCELL
  logical_power universal_gnd *
  page113_i123
#ISCELL
  standard tap *
  page113_i124
#ISCELL
  standard tap *
  page113_i125
#ISCELL
  standard tap *
  page113_i126
#ISCELL
  standard tap *
  page113_i127
#ISCELL
  standard tap *
  page113_i128
#ISCELL
  standard tap *
  page113_i129
#ISCELL
  standard tap *
  page113_i13
#ISCELL
  standard tap *
  page113_i130
#ISCELL
  standard tap *
  page113_i131
#ISCELL
  standard tap *
  page113_i132
#ISCELL
  standard tap *
  page113_i133
#ISCELL
  standard tap *
  page113_i134
#ISCELL
  standard tap *
  page113_i135
#ISCELL
  standard tap *
  page113_i136
#ISCELL
  standard tap *
  page113_i137
#ISCELL
  standard tap *
  page113_i138
#ISCELL
  standard tap *
  page113_i139
#ISCELL
  standard offpage *
  page113_i14
#ISCELL
  standard tap *
  page113_i140
#ISCELL
  standard tap *
  page113_i141
#ISCELL
  standard tap *
  page113_i142
#ISCELL
  standard tap *
  page113_i143
#ISCELL
  standard tap *
  page113_i144
#ISCELL
  standard tap *
  page113_i145
#ISCELL
  standard tap *
  page113_i146
#ISCELL
  standard tap *
  page113_i147
#ISCELL
  standard tap *
  page113_i148
#ISCELL
  standard tap *
  page113_i149
#ISCELL
  standard offpage *
  page113_i15
#ISCELL
  standard tap *
  page113_i150
#ISCELL
  standard tap *
  page113_i151
#ISCELL
  standard tap *
  page113_i152
#ISCELL
  standard tap *
  page113_i153
#ISCELL
  standard tap *
  page113_i154
#ISCELL
  standard tap *
  page113_i155
#ISCELL
  standard tap *
  page113_i156
#ISCELL
  standard tap *
  page113_i157
#ISCELL
  standard tap *
  page113_i158
#ISCELL
  standard tap *
  page113_i159
#ISCELL
  standard offpage *
  page113_i16
#ISCELL
  standard tap *
  page113_i160
#ISCELL
  standard tap *
  page113_i161
#ISCELL
  standard offpage *
  page113_i162
#ISCELL
  standard offpage *
  page113_i163
#ISCELL
  standard offpage *
  page113_i164
#ISCELL
  standard tap *
  page113_i165
#ISCELL
  standard tap *
  page113_i166
#ISCELL
  standard offpage *
  page113_i167
#ISCELL
  standard offpage *
  page113_i168
#ISCELL
  logical_power vcc_core *
  page113_i169
#ISCELL
  standard offpage *
  page113_i17
#ISCELL
  logical_power universal_gnd *
  page113_i171
#ISCELL
  standard offpage *
  page113_i172
#ISCELL
  standard offpage *
  page113_i173
#ISCELL
  standard offpage *
  page113_i174
#ISCELL
  standard tap *
  page113_i175
#ISCELL
  standard tap *
  page113_i176
#CELL
  pure_quanta sconn288_adr50017p087cc *
  page113_i177
#CELL
  pure_quanta sconn288_adr50017p087cc *
  page113_i179
#ISCELL
  standard offpage *
  page113_i18
#CELL
  pure_quanta sconn288_adr50017p087cc *
  page113_i180
#ISCELL
  standard offpage *
  page113_i181
#CELL
  pure_quanta q_res *
  page113_i182
#ISCELL
  standard offpage *
  page113_i19
#CELL
  pure_quanta q_res *
  page113_i2
#ISCELL
  standard offpage *
  page113_i20
#ISCELL
  standard offpage *
  page113_i21
#ISCELL
  standard tap *
  page113_i22
#ISCELL
  standard tap *
  page113_i23
#ISCELL
  standard tap *
  page113_i24
#ISCELL
  standard tap *
  page113_i25
#ISCELL
  standard tap *
  page113_i26
#ISCELL
  standard tap *
  page113_i27
#ISCELL
  standard tap *
  page113_i28
#ISCELL
  standard tap *
  page113_i29
#ISCELL
  standard offpage *
  page113_i3
#ISCELL
  standard tap *
  page113_i30
#ISCELL
  standard tap *
  page113_i31
#ISCELL
  standard tap *
  page113_i32
#ISCELL
  standard tap *
  page113_i33
#ISCELL
  standard tap *
  page113_i34
#ISCELL
  standard tap *
  page113_i35
#ISCELL
  standard tap *
  page113_i36
#ISCELL
  standard tap *
  page113_i37
#ISCELL
  standard tap *
  page113_i38
#ISCELL
  standard tap *
  page113_i39
#ISCELL
  standard tap *
  page113_i40
#ISCELL
  standard tap *
  page113_i41
#ISCELL
  standard tap *
  page113_i42
#ISCELL
  standard tap *
  page113_i43
#ISCELL
  standard tap *
  page113_i44
#ISCELL
  standard tap *
  page113_i45
#ISCELL
  standard tap *
  page113_i46
#ISCELL
  standard tap *
  page113_i47
#ISCELL
  standard tap *
  page113_i48
#ISCELL
  standard tap *
  page113_i49
#ISCELL
  standard offpage *
  page113_i5
#ISCELL
  standard tap *
  page113_i50
#ISCELL
  standard tap *
  page113_i51
#ISCELL
  standard tap *
  page113_i52
#ISCELL
  standard tap *
  page113_i53
#ISCELL
  standard tap *
  page113_i54
#ISCELL
  standard tap *
  page113_i55
#ISCELL
  standard tap *
  page113_i56
#ISCELL
  standard tap *
  page113_i57
#ISCELL
  standard tap *
  page113_i58
#ISCELL
  standard tap *
  page113_i59
#ISCELL
  standard offpage *
  page113_i6
#ISCELL
  standard tap *
  page113_i60
#ISCELL
  standard tap *
  page113_i61
#ISCELL
  standard tap *
  page113_i62
#ISCELL
  standard tap *
  page113_i63
#ISCELL
  standard tap *
  page113_i64
#ISCELL
  standard tap *
  page113_i65
#ISCELL
  standard tap *
  page113_i66
#ISCELL
  standard tap *
  page113_i67
#ISCELL
  standard tap *
  page113_i68
#ISCELL
  standard tap *
  page113_i69
#ISCELL
  standard offpage *
  page113_i7
#ISCELL
  standard tap *
  page113_i70
#ISCELL
  standard tap *
  page113_i71
#ISCELL
  standard tap *
  page113_i72
#ISCELL
  standard tap *
  page113_i73
#ISCELL
  standard tap *
  page113_i74
#ISCELL
  standard tap *
  page113_i75
#ISCELL
  standard tap *
  page113_i76
#ISCELL
  standard tap *
  page113_i77
#ISCELL
  standard tap *
  page113_i78
#ISCELL
  standard tap *
  page113_i79
#ISCELL
  standard offpage *
  page113_i8
#ISCELL
  standard tap *
  page113_i80
#ISCELL
  standard tap *
  page113_i81
#ISCELL
  standard tap *
  page113_i82
#ISCELL
  standard tap *
  page113_i83
#ISCELL
  standard tap *
  page113_i84
#ISCELL
  standard tap *
  page113_i85
#ISCELL
  standard tap *
  page113_i86
#ISCELL
  standard tap *
  page113_i87
#ISCELL
  standard tap *
  page113_i88
#ISCELL
  standard tap *
  page113_i89
#ISCELL
  standard offpage *
  page113_i9
#ISCELL
  standard tap *
  page113_i90
#ISCELL
  standard tap *
  page113_i91
#ISCELL
  standard tap *
  page113_i92
#ISCELL
  standard tap *
  page113_i93
#ISCELL
  standard tap *
  page113_i94
#ISCELL
  standard tap *
  page113_i95
#ISCELL
  standard tap *
  page113_i96
#ISCELL
  standard tap *
  page113_i97
#ISCELL
  standard tap *
  page113_i98
#ISCELL
  standard tap *
  page113_i99
#ISCELL
  pure_quanta quanta_title_block_c *
  *
#ISCELL
  standard offpage *
  page114_i1
#ISCELL
  standard offpage *
  page114_i10
#ISCELL
  standard offpage *
  page114_i11
#ISCELL
  standard offpage *
  page114_i12
#ISCELL
  standard offpage *
  page114_i13
#ISCELL
  standard offpage *
  page114_i14
#ISCELL
  standard offpage *
  page114_i15
#ISCELL
  standard offpage *
  page114_i16
#CELL
  pure_quanta q_res *
  page114_i17
#CELL
  pure_quanta q_res *
  page114_i18
#CELL
  pure_quanta q_res *
  page114_i19
#ISCELL
  standard offpage *
  page114_i2
#CELL
  pure_quanta q_res *
  page114_i20
#CELL
  pure_quanta q_res *
  page114_i21
#CELL
  pure_quanta q_res *
  page114_i22
#CELL
  pure_quanta q_res *
  page114_i23
#CELL
  pure_quanta q_res *
  page114_i24
#CELL
  pure_quanta q_res *
  page114_i25
#CELL
  pure_quanta q_res *
  page114_i26
#CELL
  pure_quanta q_res *
  page114_i27
#CELL
  pure_quanta q_res *
  page114_i28
#CELL
  pure_quanta q_res *
  page114_i29
#ISCELL
  standard offpage *
  page114_i3
#CELL
  pure_quanta q_res *
  page114_i30
#CELL
  pure_quanta q_res *
  page114_i31
#CELL
  pure_quanta q_res *
  page114_i32
#ISCELL
  standard offpage *
  page114_i34
#ISCELL
  standard offpage *
  page114_i36
#ISCELL
  standard offpage *
  page114_i38
#ISCELL
  standard offpage *
  page114_i39
#ISCELL
  standard offpage *
  page114_i4
#ISCELL
  standard offpage *
  page114_i40
#ISCELL
  standard offpage *
  page114_i41
#ISCELL
  standard offpage *
  page114_i42
#ISCELL
  standard offpage *
  page114_i43
#ISCELL
  standard offpage *
  page114_i44
#ISCELL
  standard offpage *
  page114_i45
#ISCELL
  standard offpage *
  page114_i46
#ISCELL
  standard offpage *
  page114_i47
#ISCELL
  standard offpage *
  page114_i48
#ISCELL
  standard offpage *
  page114_i49
#ISCELL
  standard offpage *
  page114_i5
#ISCELL
  standard offpage *
  page114_i50
#ISCELL
  standard offpage *
  page114_i51
#ISCELL
  standard offpage *
  page114_i53
#ISCELL
  standard offpage *
  page114_i54
#ISCELL
  standard offpage *
  page114_i55
#ISCELL
  standard offpage *
  page114_i56
#CELL
  pure_quanta q_res *
  page114_i57
#CELL
  pure_quanta q_res *
  page114_i58
#CELL
  pure_quanta q_res *
  page114_i59
#ISCELL
  standard offpage *
  page114_i6
#CELL
  pure_quanta q_res *
  page114_i60
#CELL
  pure_quanta q_res *
  page114_i61
#CELL
  pure_quanta q_res *
  page114_i62
#CELL
  pure_quanta q_res *
  page114_i63
#CELL
  pure_quanta q_res *
  page114_i64
#CELL
  pure_quanta q_res *
  page114_i65
#CELL
  pure_quanta q_res *
  page114_i66
#CELL
  pure_quanta q_res *
  page114_i67
#CELL
  pure_quanta q_res *
  page114_i68
#CELL
  pure_quanta q_res *
  page114_i69
#ISCELL
  standard offpage *
  page114_i7
#ISCELL
  standard offpage *
  page114_i71
#ISCELL
  standard offpage *
  page114_i74
#ISCELL
  standard offpage *
  page114_i75
#CELL
  pure_quanta q_res *
  page114_i77
#CELL
  pure_quanta q_res *
  page114_i78
#CELL
  pure_quanta q_res *
  page114_i79
#ISCELL
  standard offpage *
  page114_i8
#ISCELL
  standard offpage *
  page114_i80
#ISCELL
  standard offpage *
  page114_i9
#ISCELL
  pure_quanta quanta_title_block_c *
  *
#ISCELL
  standard offpage *
  page115_i1
#ISCELL
  logical_power universal_power *
  page115_i10
#CELL
  pure_quanta q_res *
  page115_i11
#CELL
  pure_quanta q_res *
  page115_i12
#ISCELL
  logical_power universal_power *
  page115_i13
#CELL
  pure_quanta q_res *
  page115_i14
#ISCELL
  logical_power universal_power *
  page115_i15
#CELL
  pure_quanta q_res *
  page115_i16
#CELL
  pure_quanta q_res *
  page115_i17
#CELL
  pure_quanta q_res *
  page115_i18
#CELL
  pure_quanta q_res *
  page115_i19
#ISCELL
  standard offpage *
  page115_i2
#ISCELL
  logical_power universal_power *
  page115_i20
#CELL
  pure_quanta schottky_12 *
  page115_i22
#ISCELL
  logical_power universal_power *
  page115_i24
#CELL
  pure_quanta schottky_12 *
  page115_i25
#CELL
  pure_quanta schottky_12 *
  page115_i27
#CELL
  pure_quanta schottky_12 *
  page115_i29
#ISCELL
  standard offpage *
  page115_i3
#ISCELL
  logical_power universal_power *
  page115_i30
#ISCELL
  logical_power universal_power *
  page115_i31
#ISCELL
  logical_power universal_power *
  page115_i32
#ISCELL
  standard offpage *
  page115_i33
#ISCELL
  standard offpage *
  page115_i34
#ISCELL
  standard offpage *
  page115_i35
#ISCELL
  standard offpage *
  page115_i36
#CELL
  pure_quanta q_res *
  page115_i37
#CELL
  pure_quanta q_res *
  page115_i38
#ISCELL
  logical_power universal_power *
  page115_i39
#ISCELL
  standard offpage *
  page115_i4
#CELL
  pure_quanta q_res *
  page115_i40
#CELL
  pure_quanta q_res *
  page115_i41
#CELL
  pure_quanta q_res *
  page115_i42
#ISCELL
  logical_power universal_power *
  page115_i43
#ISCELL
  logical_power universal_power *
  page115_i44
#CELL
  pure_quanta q_res *
  page115_i45
#CELL
  pure_quanta q_res *
  page115_i46
#ISCELL
  logical_power universal_power *
  page115_i47
#CELL
  pure_quanta q_res *
  page115_i48
#ISCELL
  standard offpage *
  page115_i5
#CELL
  pure_quanta schottky_12 *
  page115_i50
#CELL
  pure_quanta schottky_12 *
  page115_i52
#CELL
  pure_quanta schottky_12 *
  page115_i54
#ISCELL
  logical_power universal_power *
  page115_i56
#ISCELL
  logical_power universal_power *
  page115_i57
#ISCELL
  logical_power universal_power *
  page115_i58
#CELL
  pure_quanta schottky_12 *
  page115_i59
#ISCELL
  standard offpage *
  page115_i6
#ISCELL
  logical_power universal_power *
  page115_i60
#ISCELL
  standard offpage *
  page115_i61
#ISCELL
  standard offpage *
  page115_i62
#ISCELL
  standard offpage *
  page115_i63
#ISCELL
  standard offpage *
  page115_i64
#CELL
  pure_quanta q_res *
  page115_i65
#CELL
  pure_quanta q_res *
  page115_i66
#CELL
  pure_quanta q_res *
  page115_i67
#CELL
  pure_quanta q_res *
  page115_i68
#CELL
  pure_quanta q_res *
  page115_i69
#ISCELL
  standard offpage *
  page115_i7
#CELL
  pure_quanta q_res *
  page115_i70
#CELL
  pure_quanta q_res *
  page115_i71
#CELL
  pure_quanta q_res *
  page115_i72
#ISCELL
  standard offpage *
  page115_i8
#CELL
  pure_quanta q_res *
  page115_i9
#ISCELL
  pure_quanta quanta_title_block_c *
  *
#ISCELL
  pure_quanta quanta_title_block_c *
  *
#CELL
  pure_quanta q_res *
  page117_i10
#ISCELL
  standard offpage *
  page117_i11
#ISCELL
  standard offpage *
  page117_i12
#CELL
  pure_quanta q_res *
  page117_i13
#ISCELL
  logical_power universal_power *
  page117_i14
#ISCELL
  logical_power universal_power *
  page117_i15
#CELL
  pure_quanta q_res *
  page117_i16
#CELL
  pure_quanta q_res *
  page117_i17
#ISCELL
  logical_power universal_gnd *
  page117_i18
#CELL
  pure_quanta q_res *
  page117_i19
#ISCELL
  logical_power universal_gnd *
  page117_i20
#ISCELL
  standard offpage *
  page117_i6
#ISCELL
  standard offpage *
  page117_i7
#CELL
  pure_quanta q_res *
  page117_i9
#ISCELL
  pure_quanta quanta_title_block_c *
  *
#ISCELL
  standard offpage *
  page118_i100
#CELL
  pure_quanta q_res *
  page118_i101
#CELL
  pure_quanta q_res *
  page118_i102
#ISCELL
  standard offpage *
  page118_i12
#CELL
  pure_quanta q_res *
  page118_i23
#ISCELL
  standard offpage *
  page118_i55
#CELL
  pure_quanta q_res *
  page118_i63
#ISCELL
  standard offpage *
  page118_i64
#CELL
  pure_quanta q_res *
  page118_i65
#ISCELL
  logical_power universal_power *
  page118_i66
#CELL
  pure_quanta q_res *
  page118_i67
#ISCELL
  logical_power universal_power *
  page118_i68
#CELL
  pure_quanta q_res *
  page118_i73
#ISCELL
  logical_power universal_power *
  page118_i74
#CELL
  pure_quanta q_res *
  page118_i76
#ISCELL
  logical_power universal_power *
  page118_i78
#ISCELL
  standard offpage *
  page118_i79
#ISCELL
  standard offpage *
  page118_i80
#ISCELL
  standard offpage *
  page118_i84
#CELL
  pure_quanta q_res *
  page118_i92
#ISCELL
  standard offpage *
  page118_i98
#ISCELL
  logical_power design_note *
  *
#ISCELL
  mstr_misc dns *
  *
#ISCELL
  pure_quanta quanta_title_block_c *
  *
#CELL
  pure_quanta q_res *
  page119_i100
#CELL
  pure_quanta q_res *
  page119_i101
#ISCELL
  logical_power universal_power *
  page119_i102
#ISCELL
  standard offpage *
  page119_i103
#ISCELL
  standard offpage *
  page119_i104
#ISCELL
  standard offpage *
  page119_i105
#ISCELL
  standard offpage *
  page119_i106
#ISCELL
  standard offpage *
  page119_i107
#ISCELL
  standard offpage *
  page119_i108
#ISCELL
  standard offpage *
  page119_i109
#ISCELL
  standard offpage *
  page119_i110
#ISCELL
  standard offpage *
  page119_i111
#ISCELL
  standard offpage *
  page119_i112
#ISCELL
  standard offpage *
  page119_i113
#ISCELL
  standard offpage *
  page119_i114
#CELL
  pure_quanta q_res *
  page119_i116
#ISCELL
  standard offpage *
  page119_i120
#ISCELL
  standard offpage *
  page119_i121
#ISCELL
  standard offpage *
  page119_i124
#CELL
  pure_quanta q_res *
  page119_i125
#CELL
  pure_quanta q_res *
  page119_i135
#CELL
  pure_quanta q_res *
  page119_i136
#ISCELL
  standard offpage *
  page119_i137
#ISCELL
  logical_power universal_power *
  page119_i138
#CELL
  pure_quanta q_res *
  page119_i139
#ISCELL
  logical_power universal_power *
  page119_i141
#ISCELL
  standard offpage *
  page119_i142
#ISCELL
  standard offpage *
  page119_i143
#ISCELL
  standard offpage *
  page119_i144
#ISCELL
  standard offpage *
  page119_i145
#ISCELL
  standard offpage *
  page119_i146
#CELL
  pure_quanta q_res *
  page119_i147
#CELL
  pure_quanta q_res *
  page119_i148
#ISCELL
  logical_power universal_power *
  page119_i149
#CELL
  pure_quanta q_res *
  page119_i150
#CELL
  pure_quanta q_res *
  page119_i151
#CELL
  pure_quanta q_res *
  page119_i152
#ISCELL
  standard offpage *
  page119_i155
#CELL
  pure_quanta q_res *
  page119_i156
#ISCELL
  standard offpage *
  page119_i157
#CELL
  pure_quanta q_res *
  page119_i158
#ISCELL
  standard offpage *
  page119_i159
#CELL
  pure_quanta q_res *
  page119_i160
#CELL
  pure_quanta q_res *
  page119_i161
#ISCELL
  standard offpage *
  page119_i162
#CELL
  pure_quanta q_res *
  page119_i163
#ISCELL
  standard offpage *
  page119_i164
#ISCELL
  standard offpage *
  page119_i167
#ISCELL
  standard offpage *
  page119_i168
#CELL
  pure_quanta q_res *
  page119_i169
#CELL
  pure_quanta q_res *
  page119_i170
#ISCELL
  logical_power universal_gnd *
  page119_i171
#CELL
  pure_quanta q_res *
  page119_i172
#ISCELL
  standard offpage *
  page119_i173
#ISCELL
  standard offpage *
  page119_i174
#ISCELL
  standard offpage *
  page119_i175
#CELL
  pure_quanta q_res *
  page119_i176
#CELL
  pure_quanta q_res *
  page119_i177
#ISCELL
  standard offpage *
  page119_i178
#ISCELL
  logical_power universal_power *
  page119_i18
#CELL
  pure_quanta q_res *
  page119_i196
#ISCELL
  logical_power universal_gnd *
  page119_i197
#ISCELL
  standard offpage *
  page119_i199
#ISCELL
  logical_power universal_power *
  page119_i210
#CELL
  pure_quanta q_res *
  page119_i211
#ISCELL
  standard offpage *
  page119_i212
#ISCELL
  logical_power universal_gnd *
  page119_i213
#ISCELL
  logical_power universal_power *
  page119_i214
#CELL
  pure_quanta q_res *
  page119_i215
#CELL
  pure_quanta q_res *
  page119_i216
#ISCELL
  standard offpage *
  page119_i217
#ISCELL
  logical_power universal_power *
  page119_i218
#CELL
  pure_quanta q_res *
  page119_i219
#CELL
  pure_quanta q_res *
  page119_i220
#ISCELL
  logical_power universal_gnd *
  page119_i221
#ISCELL
  standard offpage *
  page119_i222
#ISCELL
  logical_power universal_power *
  page119_i223
#CELL
  pure_quanta q_res *
  page119_i224
#CELL
  pure_quanta q_res *
  page119_i225
#ISCELL
  logical_power universal_gnd *
  page119_i226
#ISCELL
  standard offpage *
  page119_i29
#ISCELL
  standard offpage *
  page119_i40
#ISCELL
  logical_power universal_gnd *
  page119_i44
#ISCELL
  standard offpage *
  page119_i49
#ISCELL
  standard offpage *
  page119_i50
#CELL
  pure_quanta q_res *
  page119_i53
#CELL
  pure_quanta q_res *
  page119_i54
#ISCELL
  standard offpage *
  page119_i56
#CELL
  pure_quanta q_res *
  page119_i57
#CELL
  pure_quanta q_res *
  page119_i58
#ISCELL
  standard offpage *
  page119_i59
#ISCELL
  standard offpage *
  page119_i60
#CELL
  pure_quanta q_res *
  page119_i61
#CELL
  pure_quanta q_res *
  page119_i62
#ISCELL
  standard offpage *
  page119_i63
#ISCELL
  standard offpage *
  page119_i65
#CELL
  pure_quanta q_res *
  page119_i66
#ISCELL
  standard offpage *
  page119_i67
#CELL
  pure_quanta q_res *
  page119_i68
#CELL
  pure_quanta q_res *
  page119_i71
#CELL
  pure_quanta q_res *
  page119_i72
#CELL
  pure_quanta q_res *
  page119_i88
#CELL
  pure_quanta q_res *
  page119_i89
#CELL
  pure_quanta q_res *
  page119_i90
#ISCELL
  logical_power universal_power *
  page119_i91
#CELL
  pure_quanta q_res *
  page119_i92
#CELL
  pure_quanta q_res *
  page119_i93
#CELL
  pure_quanta q_res *
  page119_i94
#CELL
  pure_quanta q_res *
  page119_i95
#CELL
  pure_quanta q_res *
  page119_i96
#CELL
  pure_quanta q_res *
  page119_i97
#CELL
  pure_quanta q_res *
  page119_i98
#ISCELL
  mstr_misc dns *
  *
#ISCELL
  pure_quanta quanta_title_block_c *
  *
#ISCELL
  standard offpage *
  page120_i11
#ISCELL
  standard offpage *
  page120_i12
#ISCELL
  standard offpage *
  page120_i14
#ISCELL
  standard offpage *
  page120_i15
#ISCELL
  standard offpage *
  page120_i16
#ISCELL
  standard offpage *
  page120_i17
#CELL
  pure_quanta q_res *
  page120_i27
#CELL
  pure_quanta q_res *
  page120_i28
#CELL
  pure_quanta q_res *
  page120_i29
#CELL
  pure_quanta q_res *
  page120_i30
#CELL
  pure_quanta q_res *
  page120_i31
#CELL
  pure_quanta q_res *
  page120_i32
#ISCELL
  standard offpage *
  page120_i35
#ISCELL
  standard offpage *
  page120_i36
#ISCELL
  standard offpage *
  page120_i37
#ISCELL
  standard offpage *
  page120_i38
#ISCELL
  standard offpage *
  page120_i39
#ISCELL
  standard offpage *
  page120_i40
#ISCELL
  logical_power universal_power *
  page120_i41
#CELL
  pure_quanta q_res *
  page120_i42
#CELL
  pure_quanta q_res *
  page120_i43
#CELL
  pure_quanta q_res *
  page120_i44
#CELL
  pure_quanta q_res *
  page120_i45
#CELL
  pure_quanta q_res *
  page120_i46
#CELL
  pure_quanta q_res *
  page120_i48
#ISCELL
  logical_power universal_gnd *
  page120_i55
#ISCELL
  standard offpage *
  page120_i57
#ISCELL
  standard offpage *
  page120_i58
#CELL
  pure_quanta q_res *
  page120_i61
#CELL
  pure_quanta q_res *
  page120_i62
#ISCELL
  logical_power universal_gnd *
  page120_i63
#ISCELL
  standard offpage *
  page120_i64
#ISCELL
  standard offpage *
  page120_i65
#CELL
  pure_quanta q_res *
  page120_i66
#CELL
  pure_quanta q_res *
  page120_i67
#ISCELL
  logical_power universal_power *
  page120_i8
#ISCELL
  pure_quanta quanta_title_block_c *
  *
#ISCELL
  standard offpage *
  page121_i1
#CELL
  pure_quanta q_res *
  page121_i10
#ISCELL
  standard offpage *
  page121_i11
#ISCELL
  logical_power universal_power *
  page121_i12
#CELL
  pure_quanta q_res *
  page121_i13
#ISCELL
  logical_power universal_power *
  page121_i14
#CELL
  pure_quanta q_res *
  page121_i15
#CELL
  pure_quanta q_res *
  page121_i16
#CELL
  pure_quanta bc847bpn *
  page121_i17
#ISCELL
  logical_power universal_power *
  page121_i18
#CELL
  pure_quanta q_res *
  page121_i19
#ISCELL
  standard offpage *
  page121_i2
#ISCELL
  logical_power universal_power *
  page121_i20
#CELL
  pure_quanta bc847bpn *
  page121_i21
#ISCELL
  logical_power universal_gnd *
  page121_i22
#CELL
  pure_quanta q_res *
  page121_i23
#ISCELL
  logical_power universal_power *
  page121_i24
#ISCELL
  logical_power universal_power *
  page121_i25
#CELL
  pure_quanta q_res *
  page121_i26
#ISCELL
  standard offpage *
  page121_i27
#ISCELL
  standard offpage *
  page121_i28
#CELL
  pure_quanta q_res *
  page121_i29
#ISCELL
  standard offpage *
  page121_i3
#ISCELL
  standard offpage *
  page121_i30
#CELL
  pure_quanta bc847bpn *
  page121_i31
#ISCELL
  logical_power universal_gnd *
  page121_i32
#CELL
  pure_quanta q_res *
  page121_i33
#ISCELL
  logical_power universal_power *
  page121_i34
#CELL
  pure_quanta q_res *
  page121_i35
#ISCELL
  standard offpage *
  page121_i36
#CELL
  pure_quanta q_res *
  page121_i4
#CELL
  pure_quanta q_res *
  page121_i5
#CELL
  pure_quanta q_res *
  page121_i6
#CELL
  pure_quanta q_res *
  page121_i7
#CELL
  pure_quanta bc847bpn *
  page121_i8
#ISCELL
  logical_power universal_power *
  page121_i9
#ISCELL
  pure_quanta quanta_title_block_c *
  *
#ISCELL
  standard offpage *
  page122_i1
#CELL
  pure_quanta bc847bpn *
  page122_i10
#ISCELL
  logical_power universal_power *
  page122_i11
#CELL
  pure_quanta bc847bpn *
  page122_i12
#ISCELL
  logical_power universal_power *
  page122_i13
#ISCELL
  logical_power universal_power *
  page122_i14
#CELL
  pure_quanta q_res *
  page122_i15
#CELL
  pure_quanta q_res *
  page122_i16
#CELL
  pure_quanta bc847bpn *
  page122_i17
#CELL
  pure_quanta q_res *
  page122_i18
#ISCELL
  standard offpage *
  page122_i19
#ISCELL
  standard offpage *
  page122_i2
#CELL
  pure_quanta q_res *
  page122_i20
#CELL
  pure_quanta q_res *
  page122_i21
#CELL
  pure_quanta bc847bpn *
  page122_i22
#ISCELL
  logical_power universal_gnd *
  page122_i23
#CELL
  pure_quanta q_res *
  page122_i24
#ISCELL
  logical_power universal_power *
  page122_i25
#ISCELL
  logical_power universal_gnd *
  page122_i26
#CELL
  pure_quanta q_res *
  page122_i27
#ISCELL
  logical_power universal_power *
  page122_i28
#CELL
  pure_quanta q_res *
  page122_i29
#ISCELL
  standard offpage *
  page122_i3
#ISCELL
  logical_power universal_power *
  page122_i30
#CELL
  pure_quanta q_res *
  page122_i31
#ISCELL
  standard offpage *
  page122_i32
#CELL
  pure_quanta q_res *
  page122_i33
#CELL
  pure_quanta q_res *
  page122_i34
#ISCELL
  standard offpage *
  page122_i35
#ISCELL
  standard offpage *
  page122_i36
#CELL
  pure_quanta q_res *
  page122_i37
#ISCELL
  logical_power universal_power *
  page122_i38
#ISCELL
  standard offpage *
  page122_i4
#CELL
  pure_quanta q_res *
  page122_i5
#CELL
  pure_quanta q_res *
  page122_i6
#ISCELL
  logical_power universal_power *
  page122_i7
#CELL
  pure_quanta q_res *
  page122_i8
#CELL
  pure_quanta q_res *
  page122_i9
#ISCELL
  pure_quanta quanta_title_block_c *
  *
#ISCELL
  standard offpage *
  page123_i1
#CELL
  pure_quanta q_res *
  page123_i10
#CELL
  pure_quanta bc847bpn *
  page123_i11
#CELL
  pure_quanta bc847bpn *
  page123_i12
#ISCELL
  logical_power universal_power *
  page123_i13
#CELL
  pure_quanta q_res *
  page123_i14
#CELL
  pure_quanta q_res *
  page123_i15
#CELL
  pure_quanta bc847bpn *
  page123_i16
#ISCELL
  logical_power universal_gnd *
  page123_i17
#CELL
  pure_quanta bc847bpn *
  page123_i18
#CELL
  pure_quanta q_res *
  page123_i19
#ISCELL
  standard offpage *
  page123_i2
#ISCELL
  logical_power universal_power *
  page123_i20
#ISCELL
  logical_power universal_power *
  page123_i21
#ISCELL
  logical_power universal_gnd *
  page123_i22
#CELL
  pure_quanta q_res *
  page123_i23
#ISCELL
  logical_power universal_power *
  page123_i24
#ISCELL
  standard offpage *
  page123_i25
#ISCELL
  standard offpage *
  page123_i26
#CELL
  pure_quanta q_res *
  page123_i27
#ISCELL
  logical_power universal_power *
  page123_i28
#CELL
  pure_quanta q_res *
  page123_i29
#ISCELL
  standard offpage *
  page123_i3
#ISCELL
  logical_power universal_power *
  page123_i30
#CELL
  pure_quanta q_res *
  page123_i31
#CELL
  pure_quanta q_res *
  page123_i32
#CELL
  pure_quanta q_res *
  page123_i33
#ISCELL
  standard offpage *
  page123_i34
#ISCELL
  standard offpage *
  page123_i35
#ISCELL
  logical_power universal_power *
  page123_i36
#CELL
  pure_quanta q_res *
  page123_i4
#CELL
  pure_quanta q_res *
  page123_i5
#CELL
  pure_quanta q_res *
  page123_i6
#CELL
  pure_quanta q_res *
  page123_i7
#CELL
  pure_quanta q_res *
  page123_i8
#ISCELL
  logical_power universal_power *
  page123_i9
#ISCELL
  pure_quanta quanta_title_block_c *
  *
#ISCELL
  standard offpage *
  page124_i11
#CELL
  pure_quanta q_res *
  page124_i17
#CELL
  pure_quanta q_res *
  page124_i19
#ISCELL
  standard offpage *
  page124_i20
#CELL
  pure_quanta q_res *
  page124_i26
#ISCELL
  standard offpage *
  page124_i27
#CELL
  pure_quanta q_res *
  page124_i33
#ISCELL
  standard offpage *
  page124_i34
#ISCELL
  standard offpage *
  page124_i40
#CELL
  pure_quanta q_res *
  page124_i43
#ISCELL
  logical_power universal_power *
  page124_i51
#CELL
  pure_quanta q_res *
  page124_i52
#ISCELL
  standard offpage *
  page124_i54
#ISCELL
  standard offpage *
  page124_i57
#ISCELL
  standard offpage *
  page124_i58
#ISCELL
  logical_power universal_power *
  page124_i59
#CELL
  pure_quanta q_res *
  page124_i60
#CELL
  pure_quanta q_res *
  page124_i62
#CELL
  pure_quanta q_res *
  page124_i68
#ISCELL
  logical_power universal_power *
  page124_i69
#CELL
  pure_quanta q_res *
  page124_i70
#ISCELL
  logical_power universal_power *
  page124_i71
#CELL
  pure_quanta q_res *
  page124_i72
#ISCELL
  logical_power universal_power *
  page124_i73
#ISCELL
  logical_power universal_power *
  page124_i75
#CELL
  pure_quanta q_res *
  page124_i76
#CELL
  pure_quanta q_res *
  page124_i77
#CELL
  pure_quanta q_res *
  page124_i78
#CELL
  pure_quanta q_res *
  page124_i79
#ISCELL
  standard offpage *
  page124_i80
#CELL
  pure_quanta q_res *
  page124_i82
#ISCELL
  standard offpage *
  page124_i83
#CELL
  pure_quanta q_res *
  page124_i85
#ISCELL
  standard offpage *
  page124_i86
#CELL
  pure_quanta q_res *
  page124_i87
#ISCELL
  standard offpage *
  page124_i88
#ISCELL
  pure_quanta quanta_title_block_c *
  *
#ISCELL
  standard offpage *
  page125_i1
#ISCELL
  standard offpage *
  page125_i10
#ISCELL
  standard offpage *
  page125_i11
#CELL
  pure_quanta q_res *
  page125_i13
#CELL
  pure_quanta q_res *
  page125_i15
#CELL
  pure_quanta q_res *
  page125_i17
#ISCELL
  standard offpage *
  page125_i2
#CELL
  pure_quanta q_res *
  page125_i24
#CELL
  pure_quanta q_res *
  page125_i26
#ISCELL
  logical_power universal_power *
  page125_i27
#ISCELL
  standard offpage *
  page125_i28
#ISCELL
  logical_power universal_power *
  page125_i29
#CELL
  pure_quanta q_res *
  page125_i3
#ISCELL
  standard offpage *
  page125_i30
#CELL
  pure_quanta q_res *
  page125_i5
#CELL
  pure_quanta q_res *
  page125_i56
#ISCELL
  logical_power universal_power *
  page125_i57
#CELL
  pure_quanta q_res *
  page125_i58
#ISCELL
  logical_power universal_power *
  page125_i59
#CELL
  pure_quanta q_res *
  page125_i60
#ISCELL
  logical_power universal_power *
  page125_i61
#CELL
  pure_quanta q_res *
  page125_i62
#ISCELL
  logical_power universal_power *
  page125_i63
#CELL
  pure_quanta q_res *
  page125_i64
#CELL
  pure_quanta q_res *
  page125_i65
#CELL
  pure_quanta q_res *
  page125_i66
#ISCELL
  standard offpage *
  page125_i67
#CELL
  pure_quanta q_res *
  page125_i68
#ISCELL
  standard offpage *
  page125_i69
#CELL
  pure_quanta q_res *
  page125_i7
#CELL
  pure_quanta q_res *
  page125_i70
#ISCELL
  standard offpage *
  page125_i71
#CELL
  pure_quanta q_res *
  page125_i72
#ISCELL
  standard offpage *
  page125_i73
#ISCELL
  standard offpage *
  page125_i8
#ISCELL
  standard offpage *
  page125_i9
#ISCELL
  mstr_misc dns *
  *
#ISCELL
  pure_quanta quanta_title_block_c *
  *
#CELL
  pure_quanta q_res *
  page126_i114
#ISCELL
  standard offpage *
  page126_i133
#ISCELL
  standard offpage *
  page126_i134
#CELL
  pure_quanta q_res *
  page126_i135
#CELL
  pure_quanta q_res *
  page126_i136
#ISCELL
  logical_power universal_power *
  page126_i137
#ISCELL
  standard offpage *
  page126_i138
#ISCELL
  standard offpage *
  page126_i139
#CELL
  pure_quanta q_res *
  page126_i140
#CELL
  pure_quanta q_res *
  page126_i141
#CELL
  pure_quanta q_res *
  page126_i22
#CELL
  pure_quanta q_res *
  page126_i23
#ISCELL
  logical_power universal_power *
  page126_i24
#CELL
  pure_quanta q_res *
  page126_i25
#ISCELL
  standard offpage *
  page126_i42
#ISCELL
  standard offpage *
  page126_i43
#ISCELL
  standard offpage *
  page126_i44
#ISCELL
  standard offpage *
  page126_i45
#ISCELL
  mstr_misc dns *
  *
#ISCELL
  pure_quanta quanta_title_block_c *
  *
#CELL
  pure_quanta q_res *
  page127_i1
#ISCELL
  standard offpage *
  page127_i10
#ISCELL
  standard offpage *
  page127_i11
#ISCELL
  standard offpage *
  page127_i12
#CELL
  pure_quanta q_res *
  page127_i13
#CELL
  pure_quanta q_res *
  page127_i14
#CELL
  pure_quanta q_res *
  page127_i15
#ISCELL
  logical_power universal_gnd *
  page127_i16
#CELL
  pure_quanta q_res *
  page127_i17
#ISCELL
  logical_power universal_gnd *
  page127_i18
#ISCELL
  logical_power universal_power *
  page127_i19
#ISCELL
  standard offpage *
  page127_i2
#CELL
  pure_quanta q_res *
  page127_i20
#CELL
  pure_quanta q_res *
  page127_i21
#ISCELL
  logical_power universal_gnd *
  page127_i22
#ISCELL
  logical_power universal_power *
  page127_i23
#CELL
  pure_quanta q_res *
  page127_i24
#ISCELL
  logical_power universal_gnd *
  page127_i25
#CELL
  pure_quanta q_res *
  page127_i26
#ISCELL
  standard offpage *
  page127_i27
#ISCELL
  logical_power universal_power *
  page127_i28
#ISCELL
  standard offpage *
  page127_i3
#ISCELL
  logical_power universal_gnd *
  page127_i30
#CELL
  pure_quanta q_res *
  page127_i31
#CELL
  pure_quanta q_res *
  page127_i32
#ISCELL
  standard offpage *
  page127_i33
#ISCELL
  logical_power universal_power *
  page127_i34
#CELL
  pure_quanta q_res *
  page127_i35
#CELL
  pure_quanta q_res *
  page127_i36
#ISCELL
  logical_power universal_gnd *
  page127_i37
#ISCELL
  standard offpage *
  page127_i4
#CELL
  pure_quanta q_res *
  page127_i5
#CELL
  pure_quanta q_res *
  page127_i6
#CELL
  pure_quanta q_res *
  page127_i7
#ISCELL
  logical_power universal_gnd *
  page127_i8
#ISCELL
  logical_power universal_gnd *
  page127_i9
#ISCELL
  pure_quanta quanta_title_block_c *
  *
#ISCELL
  standard offpage *
  page128_i1
#CELL
  pure_quanta q_res *
  page128_i10
#CELL
  pure_quanta q_res *
  page128_i11
#CELL
  pure_quanta q_res *
  page128_i12
#ISCELL
  standard offpage *
  page128_i2
#ISCELL
  standard offpage *
  page128_i3
#ISCELL
  standard offpage *
  page128_i30
#ISCELL
  standard offpage *
  page128_i31
#ISCELL
  standard offpage *
  page128_i32
#ISCELL
  standard offpage *
  page128_i33
#ISCELL
  standard offpage *
  page128_i4
#ISCELL
  standard offpage *
  page128_i44
#ISCELL
  standard offpage *
  page128_i45
#ISCELL
  standard offpage *
  page128_i46
#ISCELL
  standard offpage *
  page128_i47
#CELL
  pure_quanta q_res *
  page128_i48
#CELL
  pure_quanta q_res *
  page128_i49
#CELL
  pure_quanta q_res *
  page128_i50
#CELL
  pure_quanta q_res *
  page128_i51
#ISCELL
  standard offpage *
  page128_i68
#ISCELL
  standard offpage *
  page128_i69
#ISCELL
  standard offpage *
  page128_i70
#ISCELL
  standard offpage *
  page128_i71
#CELL
  pure_quanta q_res *
  page128_i77
#CELL
  pure_quanta q_res *
  page128_i78
#CELL
  pure_quanta q_res *
  page128_i79
#CELL
  pure_quanta q_res *
  page128_i80
#ISCELL
  logical_power universal_gnd *
  page128_i81
#CELL
  pure_quanta q_res *
  page128_i82
#CELL
  pure_quanta q_res *
  page128_i83
#ISCELL
  logical_power universal_gnd *
  page128_i84
#CELL
  pure_quanta q_res *
  page128_i85
#CELL
  pure_quanta q_res *
  page128_i86
#CELL
  pure_quanta q_res *
  page128_i9
#ISCELL
  mstr_misc dns *
  *
#ISCELL
  pure_quanta quanta_title_block_c *
  *
#ISCELL
  logical_power universal_gnd *
  page129_i100
#CELL
  pure_quanta q_cap *
  page129_i102
#CELL
  pure_quanta q_res *
  page129_i103
#CELL
  pure_quanta q_res *
  page129_i106
#CELL
  pure_quanta q_res *
  page129_i109
#CELL
  pure_quanta q_res *
  page129_i112
#CELL
  pure_quanta q_res *
  page129_i119
#ISCELL
  logical_power universal_power *
  page129_i120
#CELL
  pure_quanta q_res *
  page129_i121
#ISCELL
  logical_power universal_power *
  page129_i122
#CELL
  pure_quanta q_res *
  page129_i123
#ISCELL
  logical_power universal_power *
  page129_i124
#CELL
  pure_quanta q_res *
  page129_i125
#ISCELL
  logical_power universal_power *
  page129_i126
#ISCELL
  standard offpage *
  page129_i22
#CELL
  pure_quanta q_res *
  page129_i26
#ISCELL
  standard offpage *
  page129_i51
#ISCELL
  standard offpage *
  page129_i52
#CELL
  pure_quanta q_res *
  page129_i59
#ISCELL
  standard offpage *
  page129_i64
#ISCELL
  standard offpage *
  page129_i65
#ISCELL
  standard offpage *
  page129_i66
#CELL
  pure_quanta q_res *
  page129_i76
#ISCELL
  standard offpage *
  page129_i83
#CELL
  pure_quanta q_res *
  page129_i86
#ISCELL
  standard offpage *
  page129_i90
#CELL
  pure_quanta q_cap *
  page129_i91
#ISCELL
  logical_power universal_gnd *
  page129_i93
#CELL
  pure_quanta q_cap *
  page129_i94
#ISCELL
  logical_power universal_gnd *
  page129_i96
#ISCELL
  logical_power universal_gnd *
  page129_i97
#CELL
  pure_quanta q_cap *
  page129_i99
#ISCELL
  mstr_misc dns *
  *
#ISCELL
  pure_quanta quanta_title_block_c *
  *
#CELL
  pure_quanta q_res *
  page130_i11
#CELL
  pure_quanta q_res *
  page130_i22
#CELL
  pure_quanta q_res *
  page130_i26
#CELL
  pure_quanta q_res *
  page130_i37
#ISCELL
  standard offpage *
  page130_i53
#ISCELL
  standard offpage *
  page130_i54
#ISCELL
  standard offpage *
  page130_i55
#ISCELL
  standard offpage *
  page130_i56
#ISCELL
  logical_power universal_gnd *
  page130_i57
#ISCELL
  logical_power universal_gnd *
  page130_i58
#CELL
  pure_quanta q_cap *
  page130_i59
#ISCELL
  logical_power universal_gnd *
  page130_i61
#CELL
  pure_quanta q_cap *
  page130_i62
#CELL
  pure_quanta q_res *
  page130_i63
#ISCELL
  logical_power universal_gnd *
  page130_i64
#CELL
  pure_quanta q_cap *
  page130_i65
#CELL
  pure_quanta q_cap *
  page130_i68
#CELL
  pure_quanta q_res *
  page130_i75
#CELL
  pure_quanta q_res *
  page130_i76
#CELL
  pure_quanta q_res *
  page130_i79
#ISCELL
  standard offpage *
  page130_i80
#ISCELL
  logical_power universal_power *
  page130_i81
#CELL
  pure_quanta q_res *
  page130_i82
#ISCELL
  logical_power universal_power *
  page130_i83
#CELL
  pure_quanta q_res *
  page130_i84
#ISCELL
  standard offpage *
  page130_i85
#ISCELL
  standard offpage *
  page130_i86
#ISCELL
  logical_power universal_power *
  page130_i87
#CELL
  pure_quanta q_res *
  page130_i88
#ISCELL
  logical_power universal_power *
  page130_i89
#CELL
  pure_quanta q_res *
  page130_i90
#ISCELL
  standard offpage *
  page130_i91
#ISCELL
  mstr_misc dns *
  *
#ISCELL
  pure_quanta quanta_title_block_c *
  *
#CELL
  pure_quanta q_res *
  page133_i10
#CELL
  pure_quanta q_cap *
  page133_i100
#ISCELL
  logical_power universal_gnd *
  page133_i101
#CELL
  pure_quanta q_res *
  page133_i102
#ISCELL
  logical_power universal_gnd *
  page133_i103
#ISCELL
  logical_power universal_gnd *
  page133_i104
#CELL
  pure_quanta q_cap *
  page133_i105
#ISCELL
  standard offpage *
  page133_i106
#ISCELL
  logical_power universal_power *
  page133_i109
#ISCELL
  logical_power universal_power *
  page133_i11
#CELL
  pure_quanta q_res *
  page133_i111
#CELL
  pure_quanta q_res *
  page133_i112
#CELL
  pure_quanta q_res *
  page133_i113
#ISCELL
  standard offpage *
  page133_i115
#ISCELL
  standard offpage *
  page133_i116
#CELL
  pure_quanta q_res *
  page133_i118
#ISCELL
  logical_power universal_gnd *
  page133_i12
#CELL
  pure_quanta q_res *
  page133_i120
#ISCELL
  standard offpage *
  page133_i121
#ISCELL
  standard offpage *
  page133_i122
#ISCELL
  standard offpage *
  page133_i123
#CELL
  pure_quanta q_res *
  page133_i124
#ISCELL
  logical_power universal_gnd *
  page133_i126
#ISCELL
  logical_power universal_gnd *
  page133_i128
#CELL
  pure_quanta q_cap *
  page133_i129
#ISCELL
  standard offpage *
  page133_i13
#CELL
  pure_quanta q_cap *
  page133_i130
#ISCELL
  standard offpage *
  page133_i131
#CELL
  pure_quanta q_res *
  page133_i132
#ISCELL
  logical_power universal_gnd *
  page133_i133
#ISCELL
  standard offpage *
  page133_i134
#ISCELL
  standard offpage *
  page133_i137
#ISCELL
  standard offpage *
  page133_i138
#ISCELL
  standard offpage *
  page133_i139
#ISCELL
  logical_power universal_power *
  page133_i14
#CELL
  pure_quanta q_res *
  page133_i144
#ISCELL
  standard offpage *
  page133_i145
#ISCELL
  standard offpage *
  page133_i147
#CELL
  pure_quanta q_res *
  page133_i148
#CELL
  pure_quanta q_res *
  page133_i15
#ISCELL
  standard offpage *
  page133_i150
#ISCELL
  standard offpage *
  page133_i151
#ISCELL
  standard offpage *
  page133_i152
#CELL
  pure_quanta q_res *
  page133_i153
#ISCELL
  standard offpage *
  page133_i16
#ISCELL
  logical_power universal_power *
  page133_i20
#ISCELL
  standard offpage *
  page133_i4
#CELL
  pure_quanta sconn60_asp21410801 *
  page133_i44
#ISCELL
  standard offpage *
  page133_i45
#ISCELL
  standard offpage *
  page133_i47
#ISCELL
  standard offpage *
  page133_i49
#CELL
  pure_quanta q_res *
  page133_i5
#ISCELL
  standard offpage *
  page133_i50
#ISCELL
  standard offpage *
  page133_i51
#ISCELL
  standard offpage *
  page133_i52
#ISCELL
  standard offpage *
  page133_i53
#ISCELL
  standard offpage *
  page133_i54
#ISCELL
  standard offpage *
  page133_i55
#ISCELL
  standard offpage *
  page133_i56
#ISCELL
  standard offpage *
  page133_i57
#ISCELL
  standard offpage *
  page133_i58
#ISCELL
  standard offpage *
  page133_i59
#ISCELL
  standard offpage *
  page133_i60
#ISCELL
  logical_power universal_gnd *
  page133_i61
#ISCELL
  standard offpage *
  page133_i62
#ISCELL
  standard offpage *
  page133_i63
#ISCELL
  standard offpage *
  page133_i64
#ISCELL
  standard offpage *
  page133_i65
#ISCELL
  standard offpage *
  page133_i66
#ISCELL
  standard offpage *
  page133_i67
#ISCELL
  standard offpage *
  page133_i68
#ISCELL
  logical_power universal_power *
  page133_i69
#CELL
  pure_quanta q_res *
  page133_i7
#CELL
  pure_quanta q_res *
  page133_i70
#CELL
  pure_quanta q_res *
  page133_i71
#CELL
  pure_quanta q_res *
  page133_i74
#ISCELL
  standard offpage *
  page133_i76
#ISCELL
  standard offpage *
  page133_i78
#ISCELL
  standard offpage *
  page133_i79
#ISCELL
  standard offpage *
  page133_i8
#ISCELL
  standard offpage *
  page133_i80
#ISCELL
  standard offpage *
  page133_i81
#CELL
  pure_quanta q_res *
  page133_i83
#ISCELL
  standard offpage *
  page133_i85
#ISCELL
  standard offpage *
  page133_i86
#ISCELL
  standard offpage *
  page133_i87
#ISCELL
  standard offpage *
  page133_i88
#ISCELL
  standard offpage *
  page133_i89
#ISCELL
  standard offpage *
  page133_i9
#ISCELL
  standard offpage *
  page133_i91
#CELL
  pure_quanta q_res *
  page133_i92
#ISCELL
  logical_power universal_power *
  page133_i94
#CELL
  pure_quanta q_res *
  page133_i95
#CELL
  pure_quanta q_cap *
  page133_i96
#ISCELL
  logical_power universal_gnd *
  page133_i97
#ISCELL
  logical_power universal_gnd *
  page133_i98
#CELL
  pure_quanta q_cap *
  page133_i99
#ISCELL
  pure_quanta quanta_title_block_c *
  *
#ISCELL
  standard offpage *
  page134_i116
#ISCELL
  standard offpage *
  page134_i117
#ISCELL
  standard offpage *
  page134_i124
#ISCELL
  standard offpage *
  page134_i125
#CELL
  pure_quanta q_res *
  page134_i126
#CELL
  pure_quanta q_res *
  page134_i127
#CELL
  pure_quanta q_res *
  page134_i128
#CELL
  pure_quanta 74cbtlv3126pw *
  page134_i129
#ISCELL
  logical_power universal_power *
  page134_i134
#CELL
  pure_quanta q_cap *
  page134_i135
#ISCELL
  logical_power universal_gnd *
  page134_i136
#ISCELL
  standard offpage *
  page134_i140
#ISCELL
  standard offpage *
  page134_i141
#ISCELL
  standard offpage *
  page134_i142
#ISCELL
  standard offpage *
  page134_i143
#ISCELL
  standard offpage *
  page134_i145
#CELL
  pure_quanta q_res *
  page134_i147
#CELL
  pure_quanta q_res *
  page134_i148
#ISCELL
  standard offpage *
  page134_i153
#ISCELL
  standard offpage *
  page134_i154
#ISCELL
  standard offpage *
  page134_i156
#ISCELL
  standard offpage *
  page134_i157
#ISCELL
  standard offpage *
  page134_i158
#ISCELL
  standard offpage *
  page134_i159
#ISCELL
  standard offpage *
  page134_i160
#ISCELL
  standard offpage *
  page134_i161
#ISCELL
  standard offpage *
  page134_i162
#ISCELL
  standard offpage *
  page134_i163
#ISCELL
  logical_power universal_gnd *
  page134_i164
#ISCELL
  logical_power universal_gnd *
  page134_i165
#CELL
  pure_quanta q_res *
  page134_i166
#ISCELL
  logical_power universal_power *
  page134_i167
#CELL
  pure_quanta q_res *
  page134_i168
#CELL
  pure_quanta q_res *
  page134_i169
#ISCELL
  logical_power universal_power *
  page134_i172
#CELL
  pure_quanta q_res *
  page134_i174
#CELL
  pure_quanta q_res *
  page134_i175
#CELL
  pure_quanta q_res *
  page134_i176
#CELL
  pure_quanta q_res *
  page134_i177
#CELL
  pure_quanta q_res *
  page134_i178
#CELL
  pure_quanta q_res *
  page134_i179
#CELL
  pure_quanta q_res *
  page134_i180
#ISCELL
  logical_power universal_power *
  page134_i181
#CELL
  pure_quanta 74cbtlv3126pw *
  page134_i80
#ISCELL
  logical_power universal_power *
  page134_i81
#ISCELL
  standard offpage *
  page134_i82
#ISCELL
  standard offpage *
  page134_i86
#ISCELL
  standard offpage *
  page134_i87
#ISCELL
  standard offpage *
  page134_i88
#ISCELL
  standard offpage *
  page134_i89
#CELL
  pure_quanta q_res *
  page134_i90
#ISCELL
  logical_power universal_gnd *
  page134_i91
#ISCELL
  logical_power universal_gnd *
  page134_i92
#CELL
  pure_quanta q_cap *
  page134_i93
#ISCELL
  standard offpage *
  page134_i95
#ISCELL
  standard offpage *
  page134_i97
#ISCELL
  pure_quanta quanta_title_block_c *
  *
#CELL
  pure_quanta q_cap *
  page135_i100
#ISCELL
  logical_power universal_gnd *
  page135_i103
#CELL
  pure_quanta q_res *
  page135_i106
#CELL
  pure_quanta q_res *
  page135_i107
#ISCELL
  logical_power universal_power *
  page135_i108
#CELL
  pure_quanta q_res *
  page135_i109
#CELL
  pure_quanta q_res *
  page135_i110
#ISCELL
  standard offpage *
  page135_i111
#ISCELL
  standard offpage *
  page135_i112
#ISCELL
  standard offpage *
  page135_i113
#ISCELL
  standard offpage *
  page135_i114
#CELL
  pure_quanta 74lvc1g66gv *
  page135_i115
#ISCELL
  standard offpage *
  page135_i23
#ISCELL
  logical_power universal_gnd *
  page135_i27
#CELL
  pure_quanta nc7sb3157 *
  page135_i58
#ISCELL
  standard offpage *
  page135_i59
#ISCELL
  logical_power universal_power *
  page135_i60
#CELL
  pure_quanta q_cap *
  page135_i61
#ISCELL
  standard offpage *
  page135_i63
#ISCELL
  standard offpage *
  page135_i64
#CELL
  pure_quanta q_res *
  page135_i65
#CELL
  pure_quanta q_res *
  page135_i66
#ISCELL
  logical_power universal_power *
  page135_i67
#ISCELL
  logical_power universal_power *
  page135_i68
#ISCELL
  logical_power universal_gnd *
  page135_i69
#CELL
  pure_quanta q_cap *
  page135_i70
#CELL
  pure_quanta nc7sb3157 *
  page135_i71
#ISCELL
  logical_power universal_power *
  page135_i72
#ISCELL
  logical_power universal_power *
  page135_i73
#ISCELL
  logical_power universal_power *
  page135_i74
#CELL
  pure_quanta q_res *
  page135_i77
#CELL
  pure_quanta q_res *
  page135_i78
#ISCELL
  logical_power universal_gnd *
  page135_i79
#CELL
  pure_quanta q_cap *
  page135_i80
#CELL
  pure_quanta q_cap *
  page135_i81
#ISCELL
  logical_power universal_gnd *
  page135_i82
#ISCELL
  standard offpage *
  page135_i84
#ISCELL
  standard offpage *
  page135_i85
#ISCELL
  standard offpage *
  page135_i86
#ISCELL
  standard offpage *
  page135_i87
#ISCELL
  standard offpage *
  page135_i90
#ISCELL
  standard offpage *
  page135_i91
#ISCELL
  logical_power universal_gnd *
  page135_i92
#ISCELL
  logical_power universal_power *
  page135_i93
#CELL
  pure_quanta q_cap *
  page135_i94
#ISCELL
  logical_power universal_gnd *
  page135_i95
#CELL
  pure_quanta 74lvc1g02gw *
  page135_i96
#CELL
  pure_quanta q_res *
  page135_i97
#ISCELL
  logical_power universal_power *
  page135_i98
#ISCELL
  logical_power universal_gnd *
  page135_i99
#ISCELL
  logical_power design_note *
  *
#ISCELL
  mstr_misc dns *
  *
#ISCELL
  pure_quanta quanta_title_block_c *
  *
#ISCELL
  logical_power universal_gnd *
  page137_i101
#CELL
  pure_quanta q_res *
  page137_i102
#CELL
  pure_quanta q_res *
  page137_i103
#ISCELL
  logical_power universal_gnd *
  page137_i104
#CELL
  pure_quanta q_res *
  page137_i105
#CELL
  pure_quanta q_res *
  page137_i106
#ISCELL
  logical_power universal_gnd *
  page137_i107
#CELL
  pure_quanta nc7sb3157 *
  page137_i109
#CELL
  pure_quanta q_cap *
  page137_i110
#ISCELL
  logical_power universal_power *
  page137_i111
#CELL
  pure_quanta q_cap *
  page137_i112
#ISCELL
  logical_power universal_gnd *
  page137_i113
#ISCELL
  standard offpage *
  page137_i114
#ISCELL
  standard offpage *
  page137_i115
#CELL
  pure_quanta q_res *
  page137_i116
#ISCELL
  logical_power universal_gnd *
  page137_i117
#ISCELL
  logical_power universal_power *
  page137_i118
#ISCELL
  standard offpage *
  page137_i119
#CELL
  pure_quanta 74cbtlv3126pw *
  page137_i84
#ISCELL
  standard offpage *
  page137_i85
#ISCELL
  standard offpage *
  page137_i86
#CELL
  pure_quanta q_res *
  page137_i87
#CELL
  pure_quanta q_res *
  page137_i88
#ISCELL
  logical_power universal_power *
  page137_i89
#CELL
  pure_quanta q_cap *
  page137_i90
#ISCELL
  logical_power universal_gnd *
  page137_i91
#ISCELL
  logical_power universal_gnd *
  page137_i92
#ISCELL
  logical_power universal_power *
  page137_i93
#ISCELL
  logical_power universal_gnd *
  page137_i94
#CELL
  pure_quanta q_cap *
  page137_i95
#CELL
  pure_quanta mosfet_n *
  page137_i96
#CELL
  pure_quanta q_res *
  page137_i97
#CELL
  pure_quanta q_res *
  page137_i98
#ISCELL
  pure_quanta quanta_title_block_c *
  *
#ISCELL
  pure_quanta quanta_title_block_c *
  *
#ISCELL
  logical_power universal_gnd *
  page142_i1
#ISCELL
  standard offpage *
  page142_i10
#ISCELL
  standard offpage *
  page142_i11
#ISCELL
  standard offpage *
  page142_i12
#ISCELL
  standard offpage *
  page142_i13
#ISCELL
  standard offpage *
  page142_i14
#ISCELL
  standard offpage *
  page142_i15
#ISCELL
  standard offpage *
  page142_i16
#ISCELL
  standard offpage *
  page142_i17
#ISCELL
  standard offpage *
  page142_i18
#ISCELL
  standard offpage *
  page142_i19
#ISCELL
  standard offpage *
  page142_i2
#ISCELL
  standard offpage *
  page142_i20
#ISCELL
  standard offpage *
  page142_i21
#ISCELL
  standard offpage *
  page142_i22
#ISCELL
  standard offpage *
  page142_i23
#ISCELL
  standard offpage *
  page142_i24
#ISCELL
  standard offpage *
  page142_i25
#ISCELL
  standard offpage *
  page142_i26
#ISCELL
  standard offpage *
  page142_i27
#ISCELL
  standard offpage *
  page142_i28
#ISCELL
  standard offpage *
  page142_i29
#ISCELL
  standard offpage *
  page142_i3
#ISCELL
  standard offpage *
  page142_i30
#ISCELL
  standard offpage *
  page142_i31
#ISCELL
  standard offpage *
  page142_i32
#ISCELL
  standard offpage *
  page142_i33
#ISCELL
  logical_power universal_gnd *
  page142_i34
#ISCELL
  standard offpage *
  page142_i35
#ISCELL
  standard offpage *
  page142_i36
#ISCELL
  standard offpage *
  page142_i37
#ISCELL
  standard offpage *
  page142_i38
#ISCELL
  standard offpage *
  page142_i39
#ISCELL
  standard offpage *
  page142_i4
#ISCELL
  standard offpage *
  page142_i40
#ISCELL
  standard offpage *
  page142_i41
#ISCELL
  standard offpage *
  page142_i42
#ISCELL
  standard offpage *
  page142_i43
#ISCELL
  standard offpage *
  page142_i44
#ISCELL
  standard offpage *
  page142_i45
#ISCELL
  standard offpage *
  page142_i46
#ISCELL
  standard offpage *
  page142_i47
#ISCELL
  standard offpage *
  page142_i48
#ISCELL
  standard offpage *
  page142_i49
#ISCELL
  standard offpage *
  page142_i5
#ISCELL
  standard offpage *
  page142_i50
#ISCELL
  standard offpage *
  page142_i51
#ISCELL
  standard offpage *
  page142_i52
#ISCELL
  standard offpage *
  page142_i53
#ISCELL
  standard offpage *
  page142_i54
#ISCELL
  standard offpage *
  page142_i55
#ISCELL
  standard offpage *
  page142_i56
#ISCELL
  standard offpage *
  page142_i57
#ISCELL
  standard offpage *
  page142_i58
#ISCELL
  standard offpage *
  page142_i59
#ISCELL
  standard offpage *
  page142_i6
#ISCELL
  standard offpage *
  page142_i60
#ISCELL
  standard offpage *
  page142_i61
#ISCELL
  standard offpage *
  page142_i62
#ISCELL
  standard offpage *
  page142_i63
#ISCELL
  standard offpage *
  page142_i64
#CELL
  pure_quanta conn112_10137002101lf *
  page142_i65
#ISCELL
  standard offpage *
  page142_i66
#ISCELL
  standard offpage *
  page142_i67
#CELL
  pure_quanta conn112_10137002101lf *
  page142_i68
#ISCELL
  standard offpage *
  page142_i7
#ISCELL
  standard offpage *
  page142_i8
#ISCELL
  standard offpage *
  page142_i80
#ISCELL
  standard offpage *
  page142_i83
#ISCELL
  standard offpage *
  page142_i84
#ISCELL
  standard offpage *
  page142_i85
#ISCELL
  standard offpage *
  page142_i86
#ISCELL
  standard offpage *
  page142_i87
#ISCELL
  standard offpage *
  page142_i88
#ISCELL
  standard offpage *
  page142_i89
#ISCELL
  standard offpage *
  page142_i9
#ISCELL
  pure_quanta quanta_title_block_c *
  *
#ISCELL
  standard offpage *
  page144_i1
#ISCELL
  standard offpage *
  page144_i10
#ISCELL
  standard offpage *
  page144_i11
#ISCELL
  standard offpage *
  page144_i12
#ISCELL
  standard offpage *
  page144_i13
#ISCELL
  standard offpage *
  page144_i14
#ISCELL
  standard offpage *
  page144_i15
#ISCELL
  standard offpage *
  page144_i16
#ISCELL
  logical_power universal_gnd *
  page144_i17
#ISCELL
  standard offpage *
  page144_i18
#ISCELL
  standard offpage *
  page144_i19
#ISCELL
  standard offpage *
  page144_i2
#ISCELL
  standard offpage *
  page144_i20
#ISCELL
  standard offpage *
  page144_i21
#ISCELL
  standard offpage *
  page144_i22
#ISCELL
  standard offpage *
  page144_i23
#ISCELL
  standard offpage *
  page144_i24
#ISCELL
  standard offpage *
  page144_i25
#ISCELL
  standard offpage *
  page144_i26
#ISCELL
  standard offpage *
  page144_i27
#ISCELL
  standard offpage *
  page144_i28
#ISCELL
  standard offpage *
  page144_i29
#ISCELL
  standard offpage *
  page144_i3
#ISCELL
  standard offpage *
  page144_i30
#ISCELL
  standard offpage *
  page144_i31
#ISCELL
  standard offpage *
  page144_i32
#ISCELL
  standard offpage *
  page144_i33
#ISCELL
  standard offpage *
  page144_i34
#ISCELL
  standard offpage *
  page144_i35
#ISCELL
  standard offpage *
  page144_i36
#ISCELL
  standard offpage *
  page144_i37
#ISCELL
  standard offpage *
  page144_i38
#ISCELL
  standard offpage *
  page144_i39
#ISCELL
  standard offpage *
  page144_i4
#ISCELL
  standard offpage *
  page144_i40
#ISCELL
  standard offpage *
  page144_i41
#ISCELL
  standard offpage *
  page144_i42
#ISCELL
  standard offpage *
  page144_i43
#ISCELL
  standard offpage *
  page144_i44
#ISCELL
  standard offpage *
  page144_i45
#ISCELL
  standard offpage *
  page144_i46
#ISCELL
  standard offpage *
  page144_i47
#ISCELL
  logical_power universal_gnd *
  page144_i48
#ISCELL
  standard offpage *
  page144_i49
#ISCELL
  standard offpage *
  page144_i5
#ISCELL
  standard offpage *
  page144_i50
#ISCELL
  standard offpage *
  page144_i51
#ISCELL
  standard offpage *
  page144_i52
#ISCELL
  standard offpage *
  page144_i53
#ISCELL
  standard offpage *
  page144_i54
#ISCELL
  standard offpage *
  page144_i55
#ISCELL
  standard offpage *
  page144_i56
#ISCELL
  standard offpage *
  page144_i57
#ISCELL
  standard offpage *
  page144_i58
#ISCELL
  standard offpage *
  page144_i59
#ISCELL
  standard offpage *
  page144_i6
#ISCELL
  standard offpage *
  page144_i60
#ISCELL
  standard offpage *
  page144_i61
#ISCELL
  standard offpage *
  page144_i62
#ISCELL
  standard offpage *
  page144_i63
#ISCELL
  standard offpage *
  page144_i64
#CELL
  pure_quanta conn112_10137002101lf *
  page144_i65
#ISCELL
  standard offpage *
  page144_i66
#ISCELL
  standard offpage *
  page144_i67
#CELL
  pure_quanta conn112_10137002101lf *
  page144_i68
#ISCELL
  standard offpage *
  page144_i7
#ISCELL
  standard offpage *
  page144_i8
#ISCELL
  standard offpage *
  page144_i82
#ISCELL
  standard offpage *
  page144_i85
#ISCELL
  standard offpage *
  page144_i86
#ISCELL
  standard offpage *
  page144_i88
#ISCELL
  standard offpage *
  page144_i89
#ISCELL
  standard offpage *
  page144_i9
#ISCELL
  standard offpage *
  page144_i90
#ISCELL
  standard offpage *
  page144_i91
#ISCELL
  pure_quanta quanta_title_block_c *
  *
#ISCELL
  standard offpage *
  page317_i1
#ISCELL
  standard offpage *
  page317_i10
#ISCELL
  standard offpage *
  page317_i12
#ISCELL
  standard offpage *
  page317_i13
#ISCELL
  standard offpage *
  page317_i14
#ISCELL
  standard offpage *
  page317_i15
#ISCELL
  standard offpage *
  page317_i16
#ISCELL
  standard offpage *
  page317_i17
#ISCELL
  standard offpage *
  page317_i18
#ISCELL
  logical_power universal_gnd *
  page317_i19
#ISCELL
  standard offpage *
  page317_i2
#ISCELL
  standard offpage *
  page317_i20
#ISCELL
  standard offpage *
  page317_i21
#ISCELL
  standard offpage *
  page317_i22
#ISCELL
  standard offpage *
  page317_i23
#ISCELL
  standard offpage *
  page317_i24
#ISCELL
  standard offpage *
  page317_i27
#ISCELL
  standard offpage *
  page317_i28
#ISCELL
  standard offpage *
  page317_i29
#ISCELL
  standard offpage *
  page317_i3
#ISCELL
  standard offpage *
  page317_i30
#ISCELL
  standard offpage *
  page317_i31
#ISCELL
  standard offpage *
  page317_i32
#ISCELL
  standard offpage *
  page317_i33
#ISCELL
  standard offpage *
  page317_i34
#ISCELL
  standard offpage *
  page317_i35
#ISCELL
  standard offpage *
  page317_i36
#ISCELL
  standard offpage *
  page317_i37
#CELL
  pure_quanta conn112_10137002101lf *
  page317_i38
#ISCELL
  standard offpage *
  page317_i39
#ISCELL
  standard offpage *
  page317_i4
#ISCELL
  standard offpage *
  page317_i40
#ISCELL
  standard offpage *
  page317_i41
#ISCELL
  standard offpage *
  page317_i42
#ISCELL
  standard offpage *
  page317_i43
#ISCELL
  standard offpage *
  page317_i44
#ISCELL
  standard offpage *
  page317_i45
#ISCELL
  standard offpage *
  page317_i46
#ISCELL
  standard offpage *
  page317_i49
#ISCELL
  standard offpage *
  page317_i5
#ISCELL
  standard offpage *
  page317_i50
#ISCELL
  standard offpage *
  page317_i51
#ISCELL
  standard offpage *
  page317_i52
#ISCELL
  standard offpage *
  page317_i53
#ISCELL
  standard offpage *
  page317_i54
#ISCELL
  standard offpage *
  page317_i55
#ISCELL
  standard offpage *
  page317_i56
#ISCELL
  logical_power universal_gnd *
  page317_i57
#CELL
  pure_quanta conn112_10137002101lf *
  page317_i58
#ISCELL
  standard offpage *
  page317_i59
#ISCELL
  standard offpage *
  page317_i6
#ISCELL
  standard offpage *
  page317_i60
#ISCELL
  standard offpage *
  page317_i61
#ISCELL
  standard offpage *
  page317_i62
#ISCELL
  standard offpage *
  page317_i63
#ISCELL
  standard offpage *
  page317_i64
#ISCELL
  standard offpage *
  page317_i65
#ISCELL
  standard offpage *
  page317_i66
#ISCELL
  standard offpage *
  page317_i69
#ISCELL
  standard offpage *
  page317_i70
#ISCELL
  standard offpage *
  page317_i71
#ISCELL
  standard offpage *
  page317_i72
#ISCELL
  standard offpage *
  page317_i73
#ISCELL
  standard offpage *
  page317_i74
#ISCELL
  standard offpage *
  page317_i75
#ISCELL
  standard offpage *
  page317_i76
#ISCELL
  standard offpage *
  page317_i77
#ISCELL
  standard offpage *
  page317_i78
#ISCELL
  standard offpage *
  page317_i79
#ISCELL
  standard offpage *
  page317_i8
#ISCELL
  standard offpage *
  page317_i9
#ISCELL
  pure_quanta quanta_title_block_c *
  *
#ISCELL
  standard offpage *
  page320_i1
#ISCELL
  standard offpage *
  page320_i10
#ISCELL
  standard offpage *
  page320_i11
#ISCELL
  standard offpage *
  page320_i13
#ISCELL
  standard offpage *
  page320_i14
#ISCELL
  standard offpage *
  page320_i15
#ISCELL
  standard offpage *
  page320_i16
#ISCELL
  standard offpage *
  page320_i17
#ISCELL
  standard offpage *
  page320_i18
#ISCELL
  logical_power universal_gnd *
  page320_i19
#ISCELL
  standard offpage *
  page320_i2
#ISCELL
  standard offpage *
  page320_i20
#ISCELL
  standard offpage *
  page320_i21
#ISCELL
  standard offpage *
  page320_i22
#ISCELL
  standard offpage *
  page320_i23
#ISCELL
  standard offpage *
  page320_i24
#ISCELL
  standard offpage *
  page320_i25
#ISCELL
  standard offpage *
  page320_i26
#ISCELL
  standard offpage *
  page320_i27
#ISCELL
  standard offpage *
  page320_i3
#ISCELL
  standard offpage *
  page320_i30
#ISCELL
  standard offpage *
  page320_i31
#ISCELL
  standard offpage *
  page320_i32
#ISCELL
  standard offpage *
  page320_i33
#ISCELL
  standard offpage *
  page320_i34
#ISCELL
  standard offpage *
  page320_i35
#ISCELL
  standard offpage *
  page320_i36
#ISCELL
  standard offpage *
  page320_i37
#ISCELL
  standard offpage *
  page320_i38
#ISCELL
  standard offpage *
  page320_i39
#ISCELL
  standard offpage *
  page320_i4
#ISCELL
  standard offpage *
  page320_i40
#ISCELL
  standard offpage *
  page320_i41
#ISCELL
  standard offpage *
  page320_i42
#ISCELL
  standard offpage *
  page320_i43
#ISCELL
  standard offpage *
  page320_i44
#ISCELL
  standard offpage *
  page320_i45
#ISCELL
  standard offpage *
  page320_i47
#ISCELL
  standard offpage *
  page320_i48
#ISCELL
  standard offpage *
  page320_i5
#ISCELL
  standard offpage *
  page320_i50
#ISCELL
  standard offpage *
  page320_i51
#ISCELL
  standard offpage *
  page320_i52
#ISCELL
  standard offpage *
  page320_i53
#ISCELL
  standard offpage *
  page320_i54
#ISCELL
  standard offpage *
  page320_i55
#ISCELL
  logical_power universal_gnd *
  page320_i56
#CELL
  pure_quanta conn112_10137002101lf *
  page320_i57
#ISCELL
  standard offpage *
  page320_i58
#ISCELL
  standard offpage *
  page320_i59
#ISCELL
  standard offpage *
  page320_i6
#ISCELL
  standard offpage *
  page320_i60
#ISCELL
  standard offpage *
  page320_i61
#ISCELL
  standard offpage *
  page320_i62
#ISCELL
  standard offpage *
  page320_i63
#ISCELL
  standard offpage *
  page320_i65
#ISCELL
  standard offpage *
  page320_i67
#ISCELL
  standard offpage *
  page320_i68
#ISCELL
  standard offpage *
  page320_i69
#ISCELL
  standard offpage *
  page320_i7
#ISCELL
  standard offpage *
  page320_i70
#ISCELL
  standard offpage *
  page320_i71
#ISCELL
  standard offpage *
  page320_i72
#ISCELL
  standard offpage *
  page320_i73
#ISCELL
  standard offpage *
  page320_i74
#ISCELL
  standard offpage *
  page320_i75
#CELL
  pure_quanta conn112_10137002101lf *
  page320_i76
#ISCELL
  standard offpage *
  page320_i77
#ISCELL
  standard offpage *
  page320_i78
#ISCELL
  standard offpage *
  page320_i79
#ISCELL
  standard offpage *
  page320_i8
#ISCELL
  standard offpage *
  page320_i80
#ISCELL
  standard offpage *
  page320_i81
#ISCELL
  pure_quanta quanta_title_block_c *
  *
#ISCELL
  standard offpage *
  page319_i1
#ISCELL
  standard offpage *
  page319_i11
#ISCELL
  standard offpage *
  page319_i12
#ISCELL
  standard offpage *
  page319_i13
#ISCELL
  standard offpage *
  page319_i14
#ISCELL
  logical_power universal_gnd *
  page319_i15
#ISCELL
  standard offpage *
  page319_i16
#ISCELL
  standard offpage *
  page319_i17
#ISCELL
  standard offpage *
  page319_i18
#ISCELL
  standard offpage *
  page319_i19
#ISCELL
  standard offpage *
  page319_i2
#ISCELL
  standard offpage *
  page319_i20
#ISCELL
  standard offpage *
  page319_i21
#ISCELL
  standard offpage *
  page319_i22
#ISCELL
  standard offpage *
  page319_i23
#ISCELL
  standard offpage *
  page319_i24
#ISCELL
  standard offpage *
  page319_i25
#ISCELL
  standard offpage *
  page319_i26
#ISCELL
  standard offpage *
  page319_i27
#ISCELL
  standard offpage *
  page319_i3
#ISCELL
  standard offpage *
  page319_i30
#ISCELL
  standard offpage *
  page319_i31
#ISCELL
  standard offpage *
  page319_i32
#ISCELL
  standard offpage *
  page319_i33
#ISCELL
  standard offpage *
  page319_i34
#ISCELL
  standard offpage *
  page319_i35
#ISCELL
  standard offpage *
  page319_i36
#ISCELL
  standard offpage *
  page319_i37
#ISCELL
  standard offpage *
  page319_i38
#ISCELL
  standard offpage *
  page319_i39
#ISCELL
  standard offpage *
  page319_i4
#ISCELL
  standard offpage *
  page319_i40
#ISCELL
  standard offpage *
  page319_i41
#ISCELL
  standard offpage *
  page319_i42
#ISCELL
  standard offpage *
  page319_i43
#ISCELL
  standard offpage *
  page319_i44
#ISCELL
  standard offpage *
  page319_i45
#ISCELL
  standard offpage *
  page319_i47
#ISCELL
  standard offpage *
  page319_i49
#ISCELL
  standard offpage *
  page319_i5
#ISCELL
  standard offpage *
  page319_i50
#ISCELL
  standard offpage *
  page319_i51
#ISCELL
  logical_power universal_gnd *
  page319_i52
#CELL
  pure_quanta conn112_10137002101lf *
  page319_i53
#ISCELL
  standard offpage *
  page319_i54
#ISCELL
  standard offpage *
  page319_i55
#ISCELL
  standard offpage *
  page319_i56
#ISCELL
  standard offpage *
  page319_i57
#ISCELL
  standard offpage *
  page319_i58
#ISCELL
  standard offpage *
  page319_i59
#ISCELL
  standard offpage *
  page319_i6
#ISCELL
  standard offpage *
  page319_i60
#ISCELL
  standard offpage *
  page319_i61
#ISCELL
  standard offpage *
  page319_i62
#ISCELL
  standard offpage *
  page319_i63
#ISCELL
  standard offpage *
  page319_i64
#ISCELL
  standard offpage *
  page319_i65
#ISCELL
  standard offpage *
  page319_i68
#ISCELL
  standard offpage *
  page319_i69
#ISCELL
  standard offpage *
  page319_i7
#ISCELL
  standard offpage *
  page319_i70
#ISCELL
  standard offpage *
  page319_i71
#ISCELL
  standard offpage *
  page319_i72
#ISCELL
  standard offpage *
  page319_i73
#ISCELL
  standard offpage *
  page319_i74
#ISCELL
  standard offpage *
  page319_i75
#CELL
  pure_quanta conn112_10137002101lf *
  page319_i76
#ISCELL
  standard offpage *
  page319_i8
#ISCELL
  standard offpage *
  page319_i83
#ISCELL
  standard offpage *
  page319_i84
#ISCELL
  standard offpage *
  page319_i85
#ISCELL
  standard offpage *
  page319_i86
#ISCELL
  standard offpage *
  page319_i87
#ISCELL
  standard offpage *
  page319_i88
#ISCELL
  standard offpage *
  page319_i89
#ISCELL
  standard offpage *
  page319_i90
#ISCELL
  pure_quanta quanta_title_block_c *
  *
#ISCELL
  standard offpage *
  page318_i1
#ISCELL
  standard offpage *
  page318_i11
#ISCELL
  standard offpage *
  page318_i12
#ISCELL
  standard offpage *
  page318_i13
#ISCELL
  standard offpage *
  page318_i14
#ISCELL
  logical_power universal_gnd *
  page318_i15
#CELL
  pure_quanta conn112_10137002101lf *
  page318_i16
#ISCELL
  standard offpage *
  page318_i17
#ISCELL
  standard offpage *
  page318_i18
#ISCELL
  standard offpage *
  page318_i19
#ISCELL
  standard offpage *
  page318_i2
#ISCELL
  standard offpage *
  page318_i20
#ISCELL
  standard offpage *
  page318_i21
#ISCELL
  standard offpage *
  page318_i22
#ISCELL
  standard offpage *
  page318_i23
#ISCELL
  standard offpage *
  page318_i24
#ISCELL
  standard offpage *
  page318_i25
#ISCELL
  standard offpage *
  page318_i26
#ISCELL
  standard offpage *
  page318_i27
#ISCELL
  standard offpage *
  page318_i28
#ISCELL
  standard offpage *
  page318_i3
#ISCELL
  standard offpage *
  page318_i31
#ISCELL
  standard offpage *
  page318_i32
#ISCELL
  standard offpage *
  page318_i33
#ISCELL
  standard offpage *
  page318_i34
#ISCELL
  standard offpage *
  page318_i35
#ISCELL
  standard offpage *
  page318_i36
#ISCELL
  standard offpage *
  page318_i37
#ISCELL
  standard offpage *
  page318_i38
#ISCELL
  standard offpage *
  page318_i39
#ISCELL
  standard offpage *
  page318_i4
#ISCELL
  standard offpage *
  page318_i40
#ISCELL
  standard offpage *
  page318_i41
#ISCELL
  standard offpage *
  page318_i42
#ISCELL
  standard offpage *
  page318_i43
#ISCELL
  standard offpage *
  page318_i44
#ISCELL
  standard offpage *
  page318_i45
#ISCELL
  standard offpage *
  page318_i46
#ISCELL
  standard offpage *
  page318_i49
#ISCELL
  standard offpage *
  page318_i5
#ISCELL
  standard offpage *
  page318_i50
#ISCELL
  standard offpage *
  page318_i51
#ISCELL
  standard offpage *
  page318_i52
#ISCELL
  logical_power universal_gnd *
  page318_i53
#CELL
  pure_quanta conn112_10137002101lf *
  page318_i54
#ISCELL
  standard offpage *
  page318_i55
#ISCELL
  standard offpage *
  page318_i56
#ISCELL
  standard offpage *
  page318_i57
#ISCELL
  standard offpage *
  page318_i58
#ISCELL
  standard offpage *
  page318_i59
#ISCELL
  standard offpage *
  page318_i6
#ISCELL
  standard offpage *
  page318_i60
#ISCELL
  standard offpage *
  page318_i61
#ISCELL
  standard offpage *
  page318_i62
#ISCELL
  standard offpage *
  page318_i63
#ISCELL
  standard offpage *
  page318_i64
#ISCELL
  standard offpage *
  page318_i65
#ISCELL
  standard offpage *
  page318_i66
#ISCELL
  standard offpage *
  page318_i69
#ISCELL
  standard offpage *
  page318_i7
#ISCELL
  standard offpage *
  page318_i70
#ISCELL
  standard offpage *
  page318_i71
#ISCELL
  standard offpage *
  page318_i72
#ISCELL
  standard offpage *
  page318_i73
#ISCELL
  standard offpage *
  page318_i74
#ISCELL
  standard offpage *
  page318_i75
#ISCELL
  standard offpage *
  page318_i76
#ISCELL
  standard offpage *
  page318_i78
#ISCELL
  standard offpage *
  page318_i79
#ISCELL
  standard offpage *
  page318_i8
#ISCELL
  standard offpage *
  page318_i80
#ISCELL
  standard offpage *
  page318_i81
#ISCELL
  standard offpage *
  page318_i84
#ISCELL
  standard offpage *
  page318_i85
#ISCELL
  standard offpage *
  page318_i86
#ISCELL
  standard offpage *
  page318_i87
#ISCELL
  pure_quanta quanta_title_block_c *
  *
#ISCELL
  standard offpage *
  page148_i1
#ISCELL
  standard offpage *
  page148_i10
#ISCELL
  standard offpage *
  page148_i106
#ISCELL
  standard offpage *
  page148_i107
#ISCELL
  standard offpage *
  page148_i108
#ISCELL
  standard offpage *
  page148_i109
#ISCELL
  standard offpage *
  page148_i11
#ISCELL
  standard offpage *
  page148_i114
#ISCELL
  standard offpage *
  page148_i118
#ISCELL
  standard offpage *
  page148_i12
#ISCELL
  standard offpage *
  page148_i120
#ISCELL
  standard offpage *
  page148_i121
#ISCELL
  standard offpage *
  page148_i13
#ISCELL
  standard offpage *
  page148_i14
#ISCELL
  standard offpage *
  page148_i15
#ISCELL
  standard offpage *
  page148_i16
#ISCELL
  standard offpage *
  page148_i2
#ISCELL
  standard offpage *
  page148_i3
#ISCELL
  standard offpage *
  page148_i34
#ISCELL
  standard offpage *
  page148_i35
#ISCELL
  standard offpage *
  page148_i36
#ISCELL
  standard offpage *
  page148_i37
#ISCELL
  standard offpage *
  page148_i38
#ISCELL
  standard offpage *
  page148_i39
#ISCELL
  standard offpage *
  page148_i4
#ISCELL
  standard offpage *
  page148_i40
#ISCELL
  standard offpage *
  page148_i42
#ISCELL
  standard offpage *
  page148_i43
#ISCELL
  standard offpage *
  page148_i44
#ISCELL
  standard offpage *
  page148_i45
#ISCELL
  standard offpage *
  page148_i46
#ISCELL
  standard offpage *
  page148_i47
#ISCELL
  standard offpage *
  page148_i48
#ISCELL
  standard offpage *
  page148_i49
#ISCELL
  standard offpage *
  page148_i5
#ISCELL
  standard offpage *
  page148_i50
#ISCELL
  standard offpage *
  page148_i51
#ISCELL
  standard offpage *
  page148_i52
#ISCELL
  standard offpage *
  page148_i53
#ISCELL
  standard offpage *
  page148_i54
#ISCELL
  standard offpage *
  page148_i55
#ISCELL
  standard offpage *
  page148_i56
#ISCELL
  standard offpage *
  page148_i57
#ISCELL
  standard offpage *
  page148_i59
#ISCELL
  standard offpage *
  page148_i6
#ISCELL
  standard offpage *
  page148_i60
#ISCELL
  standard offpage *
  page148_i61
#ISCELL
  standard offpage *
  page148_i62
#ISCELL
  standard offpage *
  page148_i63
#ISCELL
  standard offpage *
  page148_i64
#ISCELL
  standard offpage *
  page148_i65
#ISCELL
  standard offpage *
  page148_i66
#ISCELL
  standard offpage *
  page148_i7
#ISCELL
  standard offpage *
  page148_i72
#CELL
  pure_quanta conn112_10137002101lf *
  page148_i74
#CELL
  pure_quanta conn112_10137002101lf *
  page148_i75
#ISCELL
  standard offpage *
  page148_i76
#ISCELL
  standard offpage *
  page148_i77
#ISCELL
  standard offpage *
  page148_i78
#ISCELL
  standard offpage *
  page148_i79
#ISCELL
  standard offpage *
  page148_i8
#ISCELL
  standard offpage *
  page148_i80
#ISCELL
  standard offpage *
  page148_i81
#ISCELL
  standard offpage *
  page148_i82
#ISCELL
  standard offpage *
  page148_i83
#ISCELL
  standard offpage *
  page148_i84
#ISCELL
  standard offpage *
  page148_i85
#ISCELL
  standard offpage *
  page148_i86
#ISCELL
  standard offpage *
  page148_i87
#ISCELL
  standard offpage *
  page148_i88
#ISCELL
  standard offpage *
  page148_i89
#ISCELL
  standard offpage *
  page148_i9
#ISCELL
  standard offpage *
  page148_i90
#ISCELL
  standard offpage *
  page148_i91
#ISCELL
  logical_power universal_gnd *
  page148_i92
#ISCELL
  logical_power universal_gnd *
  page148_i93
#ISCELL
  pure_quanta quanta_title_block_c *
  *
#ISCELL
  standard offpage *
  page149_i216
#ISCELL
  standard offpage *
  page149_i217
#ISCELL
  standard offpage *
  page149_i218
#ISCELL
  standard offpage *
  page149_i219
#ISCELL
  standard offpage *
  page149_i220
#ISCELL
  standard offpage *
  page149_i221
#ISCELL
  standard offpage *
  page149_i222
#ISCELL
  standard offpage *
  page149_i223
#ISCELL
  standard offpage *
  page149_i224
#ISCELL
  standard offpage *
  page149_i225
#ISCELL
  standard offpage *
  page149_i226
#ISCELL
  standard offpage *
  page149_i227
#ISCELL
  standard offpage *
  page149_i228
#ISCELL
  standard offpage *
  page149_i229
#ISCELL
  standard offpage *
  page149_i230
#ISCELL
  standard offpage *
  page149_i231
#ISCELL
  standard offpage *
  page149_i232
#ISCELL
  standard offpage *
  page149_i233
#ISCELL
  standard offpage *
  page149_i234
#ISCELL
  standard offpage *
  page149_i235
#ISCELL
  standard offpage *
  page149_i236
#ISCELL
  standard offpage *
  page149_i237
#ISCELL
  standard offpage *
  page149_i238
#ISCELL
  standard offpage *
  page149_i239
#ISCELL
  standard offpage *
  page149_i240
#ISCELL
  standard offpage *
  page149_i241
#ISCELL
  standard offpage *
  page149_i242
#ISCELL
  standard offpage *
  page149_i243
#ISCELL
  standard offpage *
  page149_i244
#ISCELL
  standard offpage *
  page149_i245
#ISCELL
  standard offpage *
  page149_i246
#ISCELL
  standard offpage *
  page149_i247
#ISCELL
  standard offpage *
  page149_i248
#ISCELL
  standard offpage *
  page149_i249
#ISCELL
  standard offpage *
  page149_i250
#ISCELL
  standard offpage *
  page149_i251
#ISCELL
  standard offpage *
  page149_i252
#ISCELL
  standard offpage *
  page149_i253
#ISCELL
  standard offpage *
  page149_i254
#ISCELL
  standard offpage *
  page149_i255
#ISCELL
  standard offpage *
  page149_i256
#ISCELL
  standard offpage *
  page149_i257
#ISCELL
  standard offpage *
  page149_i258
#ISCELL
  standard offpage *
  page149_i259
#ISCELL
  standard offpage *
  page149_i260
#ISCELL
  standard offpage *
  page149_i261
#ISCELL
  standard offpage *
  page149_i262
#ISCELL
  standard offpage *
  page149_i263
#ISCELL
  standard offpage *
  page149_i264
#ISCELL
  standard offpage *
  page149_i265
#ISCELL
  standard offpage *
  page149_i266
#ISCELL
  standard offpage *
  page149_i267
#ISCELL
  standard offpage *
  page149_i268
#ISCELL
  standard offpage *
  page149_i269
#ISCELL
  standard offpage *
  page149_i270
#ISCELL
  standard offpage *
  page149_i271
#ISCELL
  standard offpage *
  page149_i272
#ISCELL
  standard offpage *
  page149_i273
#ISCELL
  standard offpage *
  page149_i274
#ISCELL
  standard offpage *
  page149_i275
#ISCELL
  standard offpage *
  page149_i276
#ISCELL
  standard offpage *
  page149_i277
#ISCELL
  standard offpage *
  page149_i278
#ISCELL
  standard offpage *
  page149_i279
#ISCELL
  standard offpage *
  page149_i280
#ISCELL
  standard offpage *
  page149_i292
#ISCELL
  standard offpage *
  page149_i293
#ISCELL
  standard offpage *
  page149_i294
#ISCELL
  standard offpage *
  page149_i295
#ISCELL
  standard offpage *
  page149_i298
#ISCELL
  standard offpage *
  page149_i299
#ISCELL
  standard offpage *
  page149_i302
#ISCELL
  standard offpage *
  page149_i304
#ISCELL
  standard offpage *
  page149_i305
#ISCELL
  standard offpage *
  page149_i310
#ISCELL
  standard offpage *
  page149_i311
#ISCELL
  standard offpage *
  page149_i312
#ISCELL
  standard offpage *
  page149_i313
#ISCELL
  standard offpage *
  page149_i318
#ISCELL
  standard offpage *
  page149_i319
#ISCELL
  standard offpage *
  page149_i336
#ISCELL
  standard offpage *
  page149_i337
#ISCELL
  standard offpage *
  page149_i338
#ISCELL
  standard offpage *
  page149_i339
#ISCELL
  standard offpage *
  page149_i340
#ISCELL
  standard offpage *
  page149_i341
#ISCELL
  standard offpage *
  page149_i342
#ISCELL
  standard offpage *
  page149_i343
#ISCELL
  standard offpage *
  page149_i344
#ISCELL
  standard offpage *
  page149_i345
#ISCELL
  standard offpage *
  page149_i346
#ISCELL
  standard offpage *
  page149_i347
#ISCELL
  standard offpage *
  page149_i348
#ISCELL
  standard offpage *
  page149_i349
#ISCELL
  standard offpage *
  page149_i350
#ISCELL
  standard offpage *
  page149_i351
#ISCELL
  standard offpage *
  page149_i352
#ISCELL
  standard offpage *
  page149_i353
#CELL
  pure_quanta conn160_10131762101lf *
  page149_i75
#CELL
  pure_quanta conn160_10131762101lf *
  page149_i76
#ISCELL
  logical_power universal_gnd *
  page149_i77
#ISCELL
  logical_power universal_gnd *
  page149_i78
#ISCELL
  mstr_misc dns *
  *
#ISCELL
  pure_quanta quanta_title_block_c *
  *
#ISCELL
  standard offpage *
  page147_i1
#CELL
  pure_quanta q_res *
  page147_i11
#ISCELL
  logical_power universal_gnd *
  page147_i13
#ISCELL
  standard offpage *
  page147_i14
#CELL
  pure_quanta q_cap *
  page147_i15
#ISCELL
  logical_power universal_gnd *
  page147_i16
#ISCELL
  logical_power universal_power *
  page147_i17
#CELL
  pure_quanta q_res *
  page147_i18
#ISCELL
  logical_power universal_gnd *
  page147_i19
#ISCELL
  standard offpage *
  page147_i2
#CELL
  pure_quanta mosfet_nch_dual *
  page147_i20
#ISCELL
  standard offpage *
  page147_i21
#CELL
  pure_quanta q_cap *
  page147_i22
#ISCELL
  logical_power universal_gnd *
  page147_i23
#ISCELL
  logical_power universal_power *
  page147_i24
#CELL
  pure_quanta q_res *
  page147_i25
#CELL
  pure_quanta mosfet_nch_dual *
  page147_i26
#ISCELL
  logical_power universal_gnd *
  page147_i27
#CELL
  pure_quanta q_res *
  page147_i28
#ISCELL
  logical_power universal_power *
  page147_i29
#ISCELL
  standard offpage *
  page147_i3
#ISCELL
  logical_power universal_gnd *
  page147_i30
#CELL
  pure_quanta mosfet_nch_dual *
  page147_i31
#ISCELL
  logical_power universal_power *
  page147_i32
#CELL
  pure_quanta q_res *
  page147_i33
#CELL
  pure_quanta q_res *
  page147_i34
#ISCELL
  logical_power universal_power *
  page147_i35
#CELL
  pure_quanta q_res *
  page147_i36
#ISCELL
  logical_power universal_gnd *
  page147_i37
#CELL
  pure_quanta mosfet_nch_dual *
  page147_i38
#ISCELL
  logical_power universal_gnd *
  page147_i39
#ISCELL
  standard offpage *
  page147_i4
#ISCELL
  logical_power universal_power *
  page147_i40
#CELL
  pure_quanta q_res *
  page147_i41
#CELL
  pure_quanta q_res *
  page147_i42
#ISCELL
  logical_power universal_gnd *
  page147_i43
#ISCELL
  standard offpage *
  page147_i44
#ISCELL
  standard offpage *
  page147_i45
#ISCELL
  standard offpage *
  page147_i46
#CELL
  pure_quanta q_cap *
  page147_i47
#ISCELL
  logical_power universal_gnd *
  page147_i48
#ISCELL
  logical_power universal_power *
  page147_i49
#CELL
  pure_quanta q_res *
  page147_i5
#CELL
  pure_quanta q_res *
  page147_i50
#CELL
  pure_quanta mosfet_nch_dual *
  page147_i51
#ISCELL
  logical_power universal_gnd *
  page147_i52
#ISCELL
  logical_power universal_power *
  page147_i53
#CELL
  pure_quanta q_res *
  page147_i54
#CELL
  pure_quanta mosfet_nch_dual *
  page147_i55
#ISCELL
  logical_power universal_gnd *
  page147_i56
#ISCELL
  logical_power universal_power *
  page147_i57
#CELL
  pure_quanta q_res *
  page147_i58
#ISCELL
  standard offpage *
  page147_i59
#CELL
  pure_quanta q_res *
  page147_i6
#CELL
  pure_quanta q_res *
  page147_i60
#ISCELL
  logical_power universal_gnd *
  page147_i61
#CELL
  pure_quanta mosfet_nch_dual *
  page147_i62
#ISCELL
  standard offpage *
  page147_i63
#ISCELL
  logical_power universal_power *
  page147_i64
#CELL
  pure_quanta q_res *
  page147_i65
#CELL
  pure_quanta q_cap *
  page147_i66
#ISCELL
  logical_power universal_gnd *
  page147_i67
#ISCELL
  logical_power universal_gnd *
  page147_i68
#ISCELL
  logical_power universal_power *
  page147_i69
#CELL
  pure_quanta q_res *
  page147_i7
#CELL
  pure_quanta q_res *
  page147_i70
#CELL
  pure_quanta mosfet_nch_dual *
  page147_i71
#ISCELL
  logical_power universal_gnd *
  page147_i72
#ISCELL
  logical_power universal_power *
  page147_i74
#CELL
  pure_quanta q_res *
  page147_i75
#CELL
  pure_quanta q_res *
  page147_i76
#ISCELL
  logical_power universal_gnd *
  page147_i77
#ISCELL
  standard offpage *
  page147_i78
#CELL
  pure_quanta q_res *
  page147_i8
#ISCELL
  standard offpage *
  page147_i9
#ISCELL
  mstr_misc dns *
  *
#ISCELL
  pure_quanta quanta_title_block_c *
  *
#ISCELL
  standard offpage *
  page139_i1
#ISCELL
  logical_power universal_power *
  page139_i10
#ISCELL
  logical_power universal_gnd *
  page139_i100
#ISCELL
  logical_power universal_gnd *
  page139_i101
#ISCELL
  logical_power universal_gnd *
  page139_i102
#CELL
  pure_quanta q_res *
  page139_i107
#CELL
  pure_quanta q_res *
  page139_i108
#CELL
  pure_quanta q_res *
  page139_i109
#ISCELL
  logical_power universal_gnd *
  page139_i11
#CELL
  pure_quanta q_res *
  page139_i110
#ISCELL
  standard offpage *
  page139_i12
#CELL
  pure_quanta q_res *
  page139_i13
#CELL
  pure_quanta q_res *
  page139_i14
#ISCELL
  logical_power universal_power *
  page139_i15
#ISCELL
  logical_power universal_gnd *
  page139_i16
#CELL
  pure_quanta mosfet_nch_dual *
  page139_i17
#CELL
  pure_quanta q_res *
  page139_i18
#ISCELL
  logical_power universal_power *
  page139_i19
#CELL
  pure_quanta q_res *
  page139_i2
#ISCELL
  logical_power universal_gnd *
  page139_i20
#CELL
  pure_quanta mosfet_nch_dual *
  page139_i21
#CELL
  pure_quanta mosfet_nch_dual *
  page139_i22
#CELL
  pure_quanta q_res *
  page139_i23
#ISCELL
  logical_power universal_power *
  page139_i24
#CELL
  pure_quanta mosfet_nch_dual *
  page139_i25
#ISCELL
  logical_power universal_gnd *
  page139_i26
#CELL
  pure_quanta q_res *
  page139_i27
#CELL
  pure_quanta mosfet_nch_dual *
  page139_i28
#CELL
  pure_quanta mosfet_nch_dual *
  page139_i29
#ISCELL
  logical_power universal_gnd *
  page139_i3
#ISCELL
  logical_power universal_power *
  page139_i30
#ISCELL
  logical_power universal_gnd *
  page139_i31
#ISCELL
  logical_power universal_gnd *
  page139_i32
#CELL
  pure_quanta q_cap *
  page139_i33
#ISCELL
  logical_power universal_gnd *
  page139_i34
#CELL
  pure_quanta q_res *
  page139_i35
#ISCELL
  logical_power universal_power *
  page139_i36
#ISCELL
  logical_power universal_gnd *
  page139_i37
#ISCELL
  standard offpage *
  page139_i38
#CELL
  pure_quanta q_res *
  page139_i39
#CELL
  pure_quanta q_res *
  page139_i4
#ISCELL
  logical_power universal_power *
  page139_i40
#ISCELL
  logical_power universal_gnd *
  page139_i41
#CELL
  pure_quanta q_cap *
  page139_i42
#ISCELL
  logical_power universal_gnd *
  page139_i43
#CELL
  pure_quanta q_cap *
  page139_i44
#ISCELL
  standard offpage *
  page139_i45
#ISCELL
  standard offpage *
  page139_i46
#CELL
  pure_quanta q_res *
  page139_i47
#ISCELL
  logical_power universal_power *
  page139_i48
#ISCELL
  logical_power universal_power *
  page139_i49
#ISCELL
  standard offpage *
  page139_i5
#CELL
  pure_quanta q_res *
  page139_i50
#ISCELL
  standard offpage *
  page139_i51
#CELL
  pure_quanta q_cap *
  page139_i52
#ISCELL
  logical_power universal_gnd *
  page139_i53
#ISCELL
  logical_power universal_gnd *
  page139_i54
#CELL
  pure_quanta mosfet_nch_dual *
  page139_i55
#ISCELL
  logical_power universal_power *
  page139_i56
#CELL
  pure_quanta q_res *
  page139_i57
#ISCELL
  logical_power universal_power *
  page139_i58
#ISCELL
  logical_power universal_power *
  page139_i6
#ISCELL
  logical_power universal_gnd *
  page139_i60
#CELL
  pure_quanta mosfet_nch_dual *
  page139_i61
#CELL
  pure_quanta q_res *
  page139_i62
#ISCELL
  logical_power universal_gnd *
  page139_i63
#ISCELL
  standard offpage *
  page139_i64
#ISCELL
  logical_power universal_gnd *
  page139_i7
#CELL
  pure_quanta q_res *
  page139_i8
#CELL
  pure_quanta q_res *
  page139_i85
#CELL
  pure_quanta 74lvc2g17gw *
  page139_i86
#CELL
  pure_quanta q_res *
  page139_i87
#ISCELL
  logical_power universal_power *
  page139_i88
#CELL
  pure_quanta q_res *
  page139_i89
#CELL
  pure_quanta q_res *
  page139_i9
#ISCELL
  logical_power universal_gnd *
  page139_i90
#ISCELL
  standard offpage *
  page139_i91
#ISCELL
  logical_power universal_gnd *
  page139_i92
#CELL
  pure_quanta q_cap *
  page139_i93
#ISCELL
  logical_power universal_power *
  page139_i94
#ISCELL
  standard offpage *
  page139_i95
#ISCELL
  logical_power universal_power *
  page139_i96
#CELL
  pure_quanta q_res *
  page139_i98
#CELL
  pure_quanta q_res *
  page139_i99
#ISCELL
  mstr_misc dns *
  *
#ISCELL
  pure_quanta quanta_title_block_c *
  *
#ISCELL
  standard offpage *
  page143_i1
#ISCELL
  logical_power universal_gnd *
  page143_i10
#CELL
  pure_quanta q_res *
  page143_i100
#CELL
  pure_quanta q_res *
  page143_i101
#ISCELL
  standard offpage *
  page143_i102
#ISCELL
  logical_power universal_power *
  page143_i103
#ISCELL
  logical_power universal_gnd *
  page143_i104
#CELL
  pure_quanta q_cap *
  page143_i105
#ISCELL
  logical_power universal_gnd *
  page143_i106
#CELL
  pure_quanta mosfet_nch_dual *
  page143_i107
#ISCELL
  logical_power universal_power *
  page143_i108
#ISCELL
  logical_power universal_gnd *
  page143_i109
#CELL
  pure_quanta mosfet_nch_dual *
  page143_i11
#ISCELL
  logical_power universal_power *
  page143_i110
#ISCELL
  standard offpage *
  page143_i112
#CELL
  pure_quanta q_res *
  page143_i113
#ISCELL
  logical_power universal_gnd *
  page143_i114
#CELL
  pure_quanta q_res *
  page143_i116
#ISCELL
  standard offpage *
  page143_i117
#CELL
  pure_quanta q_cap *
  page143_i118
#ISCELL
  logical_power universal_gnd *
  page143_i119
#ISCELL
  logical_power universal_power *
  page143_i12
#ISCELL
  logical_power universal_power *
  page143_i120
#CELL
  pure_quanta mosfet_nch_dual *
  page143_i121
#ISCELL
  logical_power universal_gnd *
  page143_i122
#ISCELL
  logical_power universal_power *
  page143_i123
#CELL
  pure_quanta q_res *
  page143_i124
#ISCELL
  logical_power universal_gnd *
  page143_i125
#CELL
  pure_quanta mosfet_nch_dual *
  page143_i126
#ISCELL
  logical_power universal_power *
  page143_i127
#CELL
  pure_quanta q_res *
  page143_i129
#CELL
  pure_quanta q_res *
  page143_i13
#ISCELL
  logical_power universal_gnd *
  page143_i130
#ISCELL
  standard offpage *
  page143_i131
#CELL
  pure_quanta q_res *
  page143_i132
#CELL
  pure_quanta q_res *
  page143_i136
#CELL
  pure_quanta q_res *
  page143_i137
#CELL
  pure_quanta q_res *
  page143_i138
#CELL
  pure_quanta q_res *
  page143_i139
#CELL
  pure_quanta q_res *
  page143_i14
#CELL
  pure_quanta q_res *
  page143_i140
#CELL
  pure_quanta q_res *
  page143_i141
#CELL
  pure_quanta q_res *
  page143_i142
#CELL
  pure_quanta q_res *
  page143_i143
#CELL
  pure_quanta q_res *
  page143_i144
#CELL
  pure_quanta q_res *
  page143_i145
#ISCELL
  standard offpage *
  page143_i15
#ISCELL
  logical_power universal_gnd *
  page143_i16
#CELL
  pure_quanta mosfet_nch_dual *
  page143_i19
#CELL
  pure_quanta q_cap *
  page143_i2
#ISCELL
  logical_power universal_power *
  page143_i20
#CELL
  pure_quanta q_res *
  page143_i21
#ISCELL
  standard offpage *
  page143_i22
#CELL
  pure_quanta q_cap *
  page143_i23
#ISCELL
  logical_power universal_gnd *
  page143_i24
#ISCELL
  logical_power universal_gnd *
  page143_i25
#ISCELL
  logical_power universal_power *
  page143_i26
#CELL
  pure_quanta q_res *
  page143_i27
#ISCELL
  logical_power universal_gnd *
  page143_i28
#CELL
  pure_quanta mosfet_nch_dual *
  page143_i29
#ISCELL
  logical_power universal_gnd *
  page143_i3
#ISCELL
  logical_power universal_power *
  page143_i30
#CELL
  pure_quanta q_res *
  page143_i31
#CELL
  pure_quanta q_res *
  page143_i32
#ISCELL
  standard offpage *
  page143_i33
#ISCELL
  logical_power universal_gnd *
  page143_i34
#CELL
  pure_quanta mosfet_nch_dual *
  page143_i35
#CELL
  pure_quanta q_res *
  page143_i36
#ISCELL
  logical_power universal_power *
  page143_i37
#ISCELL
  logical_power universal_power *
  page143_i38
#ISCELL
  standard offpage *
  page143_i39
#ISCELL
  logical_power universal_power *
  page143_i4
#CELL
  pure_quanta q_cap *
  page143_i40
#ISCELL
  logical_power universal_gnd *
  page143_i41
#ISCELL
  logical_power universal_gnd *
  page143_i42
#CELL
  pure_quanta q_res *
  page143_i43
#CELL
  pure_quanta mosfet_nch_dual *
  page143_i44
#ISCELL
  logical_power universal_gnd *
  page143_i45
#ISCELL
  logical_power universal_power *
  page143_i46
#ISCELL
  standard offpage *
  page143_i48
#CELL
  pure_quanta q_res *
  page143_i49
#CELL
  pure_quanta q_res *
  page143_i5
#ISCELL
  logical_power universal_gnd *
  page143_i50
#ISCELL
  logical_power universal_power *
  page143_i51
#CELL
  pure_quanta q_res *
  page143_i52
#ISCELL
  standard offpage *
  page143_i53
#ISCELL
  standard offpage *
  page143_i54
#CELL
  pure_quanta q_cap *
  page143_i55
#ISCELL
  logical_power universal_gnd *
  page143_i56
#CELL
  pure_quanta q_cap *
  page143_i57
#ISCELL
  logical_power universal_gnd *
  page143_i58
#ISCELL
  logical_power universal_power *
  page143_i59
#CELL
  pure_quanta mosfet_nch_dual *
  page143_i6
#CELL
  pure_quanta q_res *
  page143_i60
#ISCELL
  standard offpage *
  page143_i61
#ISCELL
  logical_power universal_power *
  page143_i62
#ISCELL
  logical_power universal_gnd *
  page143_i63
#CELL
  pure_quanta q_res *
  page143_i64
#ISCELL
  logical_power universal_gnd *
  page143_i65
#CELL
  pure_quanta q_cap *
  page143_i66
#ISCELL
  logical_power universal_gnd *
  page143_i67
#ISCELL
  logical_power universal_gnd *
  page143_i68
#ISCELL
  logical_power universal_power *
  page143_i69
#ISCELL
  logical_power universal_gnd *
  page143_i7
#CELL
  pure_quanta mosfet_nch_dual *
  page143_i70
#CELL
  pure_quanta mosfet_nch_dual *
  page143_i71
#CELL
  pure_quanta q_res *
  page143_i72
#ISCELL
  logical_power universal_gnd *
  page143_i73
#CELL
  pure_quanta mosfet_nch_dual *
  page143_i74
#ISCELL
  logical_power universal_power *
  page143_i75
#CELL
  pure_quanta q_res *
  page143_i76
#CELL
  pure_quanta mosfet_nch_dual *
  page143_i77
#CELL
  pure_quanta mosfet_nch_dual *
  page143_i78
#ISCELL
  logical_power universal_gnd *
  page143_i79
#ISCELL
  logical_power universal_power *
  page143_i8
#ISCELL
  logical_power universal_power *
  page143_i80
#CELL
  pure_quanta q_res *
  page143_i81
#ISCELL
  logical_power universal_gnd *
  page143_i82
#CELL
  pure_quanta mosfet_nch_dual *
  page143_i83
#ISCELL
  logical_power universal_power *
  page143_i84
#CELL
  pure_quanta q_res *
  page143_i85
#CELL
  pure_quanta q_res *
  page143_i86
#ISCELL
  standard offpage *
  page143_i87
#ISCELL
  logical_power universal_gnd *
  page143_i88
#ISCELL
  logical_power universal_power *
  page143_i89
#CELL
  pure_quanta q_res *
  page143_i9
#CELL
  pure_quanta q_res *
  page143_i91
#ISCELL
  logical_power universal_gnd *
  page143_i92
#ISCELL
  logical_power universal_power *
  page143_i93
#ISCELL
  standard offpage *
  page143_i94
#CELL
  pure_quanta q_res *
  page143_i95
#CELL
  pure_quanta q_res *
  page143_i96
#ISCELL
  logical_power universal_gnd *
  page143_i97
#ISCELL
  standard offpage *
  page143_i98
#CELL
  pure_quanta mosfet_nch_dual *
  page143_i99
#ISCELL
  mstr_misc dns *
  *
#ISCELL
  pure_quanta quanta_title_block_c *
  *
#ISCELL
  standard offpage *
  page299_i1
#ISCELL
  logical_power universal_power *
  page299_i10
#ISCELL
  logical_power universal_gnd *
  page299_i11
#ISCELL
  standard offpage *
  page299_i12
#CELL
  pure_quanta q_cap *
  page299_i129
#CELL
  pure_quanta q_res *
  page299_i130
#CELL
  pure_quanta q_res *
  page299_i131
#CELL
  pure_quanta q_res *
  page299_i132
#CELL
  pure_quanta q_res *
  page299_i133
#CELL
  pure_quanta q_res *
  page299_i134
#CELL
  pure_quanta mosfet_nch_dual *
  page299_i135
#ISCELL
  logical_power universal_power *
  page299_i138
#ISCELL
  logical_power universal_gnd *
  page299_i139
#ISCELL
  standard offpage *
  page299_i143
#CELL
  pure_quanta q_res *
  page299_i144
#CELL
  pure_quanta q_res *
  page299_i145
#ISCELL
  logical_power universal_gnd *
  page299_i146
#CELL
  pure_quanta q_res *
  page299_i147
#ISCELL
  logical_power universal_gnd *
  page299_i148
#ISCELL
  standard offpage *
  page299_i149
#ISCELL
  logical_power universal_power *
  page299_i15
#ISCELL
  logical_power universal_power *
  page299_i150
#ISCELL
  standard offpage *
  page299_i151
#CELL
  pure_quanta q_cap *
  page299_i152
#ISCELL
  logical_power universal_gnd *
  page299_i153
#CELL
  pure_quanta q_res *
  page299_i154
#ISCELL
  logical_power universal_power *
  page299_i155
#ISCELL
  logical_power universal_gnd *
  page299_i156
#CELL
  pure_quanta mosfet_nch_dual *
  page299_i157
#CELL
  pure_quanta q_res *
  page299_i158
#ISCELL
  logical_power universal_gnd *
  page299_i159
#ISCELL
  logical_power universal_gnd *
  page299_i16
#CELL
  pure_quanta mosfet_nch_dual *
  page299_i160
#ISCELL
  logical_power universal_power *
  page299_i161
#CELL
  pure_quanta q_res *
  page299_i163
#ISCELL
  logical_power universal_gnd *
  page299_i164
#ISCELL
  standard offpage *
  page299_i165
#CELL
  pure_quanta q_res *
  page299_i166
#CELL
  pure_quanta q_res *
  page299_i167
#CELL
  pure_quanta mosfet_nch_dual *
  page299_i168
#CELL
  pure_quanta mosfet_nch_dual *
  page299_i169
#CELL
  pure_quanta q_res *
  page299_i17
#ISCELL
  standard offpage *
  page299_i170
#CELL
  pure_quanta q_cap *
  page299_i171
#ISCELL
  logical_power universal_gnd *
  page299_i172
#ISCELL
  logical_power universal_power *
  page299_i173
#CELL
  pure_quanta q_res *
  page299_i174
#ISCELL
  logical_power universal_gnd *
  page299_i175
#ISCELL
  logical_power universal_power *
  page299_i176
#CELL
  pure_quanta q_res *
  page299_i177
#ISCELL
  logical_power universal_gnd *
  page299_i178
#ISCELL
  logical_power universal_power *
  page299_i179
#ISCELL
  standard offpage *
  page299_i18
#CELL
  pure_quanta q_res *
  page299_i181
#ISCELL
  logical_power universal_gnd *
  page299_i182
#ISCELL
  standard offpage *
  page299_i183
#CELL
  pure_quanta q_res *
  page299_i184
#ISCELL
  standard offpage *
  page299_i185
#ISCELL
  logical_power universal_gnd *
  page299_i2
#ISCELL
  logical_power universal_power *
  page299_i20
#CELL
  pure_quanta mosfet_nch_dual *
  page299_i21
#ISCELL
  logical_power universal_gnd *
  page299_i22
#CELL
  pure_quanta q_res *
  page299_i23
#ISCELL
  logical_power universal_power *
  page299_i24
#ISCELL
  logical_power universal_gnd *
  page299_i25
#CELL
  pure_quanta mosfet_nch_dual *
  page299_i26
#CELL
  pure_quanta q_res *
  page299_i27
#ISCELL
  logical_power universal_power *
  page299_i28
#ISCELL
  logical_power universal_gnd *
  page299_i29
#CELL
  pure_quanta q_res *
  page299_i3
#CELL
  pure_quanta q_cap *
  page299_i30
#ISCELL
  standard offpage *
  page299_i31
#CELL
  pure_quanta mosfet_nch_dual *
  page299_i37
#ISCELL
  logical_power universal_gnd *
  page299_i38
#CELL
  pure_quanta q_res *
  page299_i39
#CELL
  pure_quanta mosfet_nch_dual *
  page299_i40
#ISCELL
  logical_power universal_power *
  page299_i41
#ISCELL
  logical_power universal_gnd *
  page299_i42
#CELL
  pure_quanta mosfet_nch_dual *
  page299_i43
#ISCELL
  logical_power universal_gnd *
  page299_i44
#CELL
  pure_quanta q_res *
  page299_i45
#ISCELL
  logical_power universal_power *
  page299_i46
#ISCELL
  logical_power universal_gnd *
  page299_i47
#CELL
  pure_quanta mosfet_nch_dual *
  page299_i48
#CELL
  pure_quanta q_res *
  page299_i49
#ISCELL
  logical_power universal_power *
  page299_i5
#ISCELL
  logical_power universal_power *
  page299_i50
#ISCELL
  logical_power universal_gnd *
  page299_i51
#CELL
  pure_quanta mosfet_nch_dual *
  page299_i52
#CELL
  pure_quanta q_res *
  page299_i53
#ISCELL
  logical_power universal_power *
  page299_i54
#CELL
  pure_quanta q_res *
  page299_i55
#ISCELL
  logical_power universal_power *
  page299_i56
#CELL
  pure_quanta mosfet_nch_dual *
  page299_i57
#ISCELL
  logical_power universal_gnd *
  page299_i58
#CELL
  pure_quanta q_res *
  page299_i59
#ISCELL
  standard offpage *
  page299_i6
#ISCELL
  logical_power universal_gnd *
  page299_i60
#ISCELL
  logical_power universal_gnd *
  page299_i61
#ISCELL
  standard offpage *
  page299_i62
#ISCELL
  logical_power universal_gnd *
  page299_i7
#CELL
  pure_quanta q_cap *
  page299_i71
#ISCELL
  standard offpage *
  page299_i72
#ISCELL
  logical_power universal_gnd *
  page299_i73
#CELL
  pure_quanta q_cap *
  page299_i74
#ISCELL
  standard offpage *
  page299_i75
#ISCELL
  logical_power universal_power *
  page299_i83
#ISCELL
  mstr_misc dns *
  *
#ISCELL
  pure_quanta quanta_title_block_c *
  *
#ISCELL
  logical_power universal_gnd *
  page145_i10
#CELL
  pure_quanta mosfet_nch_dual *
  page145_i100
#CELL
  pure_quanta q_res *
  page145_i101
#ISCELL
  logical_power universal_power *
  page145_i102
#ISCELL
  logical_power universal_gnd *
  page145_i103
#ISCELL
  logical_power universal_gnd *
  page145_i104
#CELL
  pure_quanta q_cap *
  page145_i105
#ISCELL
  standard offpage *
  page145_i106
#ISCELL
  logical_power universal_gnd *
  page145_i108
#CELL
  pure_quanta q_res *
  page145_i109
#ISCELL
  logical_power universal_gnd *
  page145_i11
#ISCELL
  logical_power universal_power *
  page145_i110
#CELL
  pure_quanta q_cap *
  page145_i111
#ISCELL
  logical_power universal_gnd *
  page145_i112
#ISCELL
  logical_power universal_gnd *
  page145_i113
#CELL
  pure_quanta q_cap *
  page145_i114
#ISCELL
  logical_power universal_gnd *
  page145_i115
#CELL
  pure_quanta q_cap *
  page145_i116
#CELL
  pure_quanta mosfet_nch_dual *
  page145_i117
#CELL
  pure_quanta mosfet_nch_dual *
  page145_i118
#CELL
  pure_quanta mosfet_nch_dual *
  page145_i119
#ISCELL
  logical_power universal_gnd *
  page145_i12
#CELL
  pure_quanta mosfet_nch_dual *
  page145_i120
#CELL
  pure_quanta mosfet_nch_dual *
  page145_i121
#CELL
  pure_quanta mosfet_nch_dual *
  page145_i122
#ISCELL
  logical_power universal_power *
  page145_i123
#ISCELL
  standard offpage *
  page145_i124
#CELL
  pure_quanta q_cap *
  page145_i125
#ISCELL
  logical_power universal_gnd *
  page145_i126
#CELL
  pure_quanta q_res *
  page145_i127
#ISCELL
  logical_power universal_power *
  page145_i128
#CELL
  pure_quanta q_res *
  page145_i129
#ISCELL
  logical_power universal_power *
  page145_i13
#ISCELL
  logical_power universal_gnd *
  page145_i130
#ISCELL
  logical_power universal_gnd *
  page145_i131
#ISCELL
  logical_power universal_power *
  page145_i132
#CELL
  pure_quanta q_res *
  page145_i134
#ISCELL
  logical_power universal_gnd *
  page145_i135
#ISCELL
  standard offpage *
  page145_i136
#ISCELL
  standard offpage *
  page145_i137
#ISCELL
  logical_power universal_gnd *
  page145_i138
#CELL
  pure_quanta q_res *
  page145_i139
#CELL
  pure_quanta q_res *
  page145_i14
#ISCELL
  logical_power universal_power *
  page145_i141
#ISCELL
  logical_power universal_gnd *
  page145_i142
#ISCELL
  logical_power universal_gnd *
  page145_i143
#CELL
  pure_quanta q_res *
  page145_i144
#ISCELL
  logical_power universal_power *
  page145_i145
#CELL
  pure_quanta q_res *
  page145_i146
#ISCELL
  logical_power universal_gnd *
  page145_i147
#CELL
  pure_quanta q_cap *
  page145_i148
#ISCELL
  standard offpage *
  page145_i149
#ISCELL
  logical_power universal_power *
  page145_i150
#CELL
  pure_quanta mosfet_nch_dual *
  page145_i151
#CELL
  pure_quanta mosfet_nch_dual *
  page145_i152
#ISCELL
  logical_power universal_power *
  page145_i153
#CELL
  pure_quanta mosfet_nch_dual *
  page145_i154
#ISCELL
  standard offpage *
  page145_i155
#CELL
  pure_quanta q_cap *
  page145_i156
#ISCELL
  logical_power universal_gnd *
  page145_i157
#CELL
  pure_quanta q_res *
  page145_i158
#CELL
  pure_quanta mosfet_nch_dual *
  page145_i159
#ISCELL
  logical_power universal_power *
  page145_i16
#ISCELL
  logical_power universal_gnd *
  page145_i160
#ISCELL
  logical_power universal_power *
  page145_i161
#CELL
  pure_quanta q_res *
  page145_i162
#ISCELL
  logical_power universal_gnd *
  page145_i163
#ISCELL
  logical_power universal_power *
  page145_i164
#ISCELL
  logical_power universal_gnd *
  page145_i167
#ISCELL
  standard offpage *
  page145_i168
#ISCELL
  standard offpage *
  page145_i169
#CELL
  pure_quanta q_res *
  page145_i171
#CELL
  pure_quanta q_res *
  page145_i172
#CELL
  pure_quanta q_res *
  page145_i173
#CELL
  pure_quanta q_res *
  page145_i174
#CELL
  pure_quanta q_res *
  page145_i175
#CELL
  pure_quanta q_res *
  page145_i176
#CELL
  pure_quanta q_res *
  page145_i18
#CELL
  pure_quanta q_res *
  page145_i19
#ISCELL
  logical_power universal_power *
  page145_i21
#ISCELL
  standard offpage *
  page145_i22
#ISCELL
  logical_power universal_gnd *
  page145_i23
#CELL
  pure_quanta q_res *
  page145_i24
#ISCELL
  logical_power universal_power *
  page145_i25
#ISCELL
  standard offpage *
  page145_i28
#ISCELL
  logical_power universal_gnd *
  page145_i29
#CELL
  pure_quanta q_res *
  page145_i30
#ISCELL
  logical_power universal_power *
  page145_i31
#CELL
  pure_quanta mosfet_nch_dual *
  page145_i33
#CELL
  pure_quanta mosfet_nch_dual *
  page145_i35
#CELL
  pure_quanta mosfet_nch_dual *
  page145_i37
#ISCELL
  logical_power universal_power *
  page145_i46
#ISCELL
  logical_power universal_power *
  page145_i47
#ISCELL
  logical_power universal_power *
  page145_i49
#ISCELL
  logical_power universal_power *
  page145_i51
#ISCELL
  logical_power universal_power *
  page145_i53
#ISCELL
  logical_power universal_gnd *
  page145_i55
#CELL
  pure_quanta q_res *
  page145_i56
#ISCELL
  logical_power universal_gnd *
  page145_i57
#CELL
  pure_quanta q_res *
  page145_i58
#ISCELL
  logical_power universal_gnd *
  page145_i59
#ISCELL
  standard offpage *
  page145_i6
#CELL
  pure_quanta q_res *
  page145_i60
#ISCELL
  logical_power universal_gnd *
  page145_i61
#CELL
  pure_quanta q_res *
  page145_i62
#ISCELL
  logical_power universal_gnd *
  page145_i63
#CELL
  pure_quanta q_res *
  page145_i66
#CELL
  pure_quanta q_res *
  page145_i67
#CELL
  pure_quanta q_res *
  page145_i68
#ISCELL
  standard offpage *
  page145_i7
#ISCELL
  standard offpage *
  page145_i8
#CELL
  pure_quanta q_res *
  page145_i80
#CELL
  pure_quanta mosfet_nch_dual *
  page145_i82
#ISCELL
  logical_power universal_gnd *
  page145_i83
#CELL
  pure_quanta q_res *
  page145_i84
#ISCELL
  logical_power universal_power *
  page145_i85
#ISCELL
  standard offpage *
  page145_i86
#ISCELL
  standard offpage *
  page145_i87
#CELL
  pure_quanta mosfet_nch_dual *
  page145_i88
#ISCELL
  logical_power universal_gnd *
  page145_i89
#ISCELL
  logical_power universal_power *
  page145_i90
#CELL
  pure_quanta q_res *
  page145_i91
#CELL
  pure_quanta q_cap *
  page145_i92
#ISCELL
  logical_power universal_gnd *
  page145_i93
#ISCELL
  standard offpage *
  page145_i94
#ISCELL
  logical_power universal_gnd *
  page145_i96
#CELL
  pure_quanta q_res *
  page145_i97
#ISCELL
  logical_power universal_power *
  page145_i98
#ISCELL
  standard offpage *
  page145_i99
#ISCELL
  mstr_misc dns *
  *
#ISCELL
  pure_quanta quanta_title_block_c *
  *
#CELL
  pure_quanta q_res *
  page160_i123
#CELL
  pure_quanta q_res *
  page160_i124
#ISCELL
  logical_power universal_power *
  page160_i125
#ISCELL
  logical_power universal_gnd *
  page160_i126
#CELL
  pure_quanta q_res *
  page160_i127
#ISCELL
  logical_power universal_gnd *
  page160_i137
#ISCELL
  logical_power universal_gnd *
  page160_i138
#CELL
  pure_quanta q_res *
  page160_i139
#ISCELL
  standard offpage *
  page160_i146
#CELL
  pure_quanta q_cap *
  page160_i148
#ISCELL
  logical_power universal_gnd *
  page160_i149
#CELL
  pure_quanta 74lvc2g17gw *
  page160_i153
#ISCELL
  logical_power universal_power *
  page160_i154
#ISCELL
  logical_power universal_gnd *
  page160_i16
#ISCELL
  standard offpage *
  page160_i161
#ISCELL
  logical_power universal_power *
  page160_i163
#CELL
  pure_quanta q_res *
  page160_i164
#CELL
  pure_quanta q_res *
  page160_i165
#ISCELL
  logical_power universal_gnd *
  page160_i166
#ISCELL
  logical_power universal_power *
  page160_i167
#CELL
  pure_quanta q_res *
  page160_i168
#ISCELL
  standard offpage *
  page160_i169
#CELL
  pure_quanta q_res *
  page160_i170
#ISCELL
  logical_power universal_gnd *
  page160_i171
#ISCELL
  standard offpage *
  page160_i172
#CELL
  pure_quanta 74lvc2g17gw *
  page160_i173
#ISCELL
  logical_power universal_power *
  page160_i174
#CELL
  pure_quanta q_cap *
  page160_i175
#ISCELL
  logical_power universal_gnd *
  page160_i176
#ISCELL
  logical_power universal_gnd *
  page160_i177
#ISCELL
  logical_power universal_gnd *
  page160_i178
#ISCELL
  standard offpage *
  page160_i179
#ISCELL
  standard offpage *
  page160_i18
#CELL
  pure_quanta q_res *
  page160_i181
#ISCELL
  standard offpage *
  page160_i182
#CELL
  pure_quanta q_res *
  page160_i184
#ISCELL
  logical_power universal_gnd *
  page160_i185
#ISCELL
  logical_power universal_power *
  page160_i186
#CELL
  pure_quanta q_res *
  page160_i187
#CELL
  pure_quanta q_res *
  page160_i188
#ISCELL
  logical_power universal_gnd *
  page160_i189
#ISCELL
  standard offpage *
  page160_i190
#ISCELL
  logical_power universal_power *
  page160_i191
#CELL
  pure_quanta q_res *
  page160_i192
#ISCELL
  standard offpage *
  page160_i194
#CELL
  pure_quanta q_res *
  page160_i195
#ISCELL
  logical_power universal_gnd *
  page160_i196
#CELL
  pure_quanta q_res *
  page160_i197
#CELL
  pure_quanta q_res *
  page160_i198
#CELL
  pure_quanta q_res *
  page160_i199
#ISCELL
  logical_power universal_power *
  page160_i20
#CELL
  pure_quanta q_res *
  page160_i200
#CELL
  pure_quanta q_res *
  page160_i201
#CELL
  pure_quanta q_res *
  page160_i202
#CELL
  pure_quanta 74lvc2g17gw *
  page160_i26
#ISCELL
  logical_power universal_gnd *
  page160_i27
#ISCELL
  logical_power universal_gnd *
  page160_i28
#CELL
  pure_quanta q_cap *
  page160_i29
#ISCELL
  logical_power universal_power *
  page160_i30
#ISCELL
  standard offpage *
  page160_i67
#CELL
  pure_quanta q_res *
  page160_i95
#ISCELL
  mstr_misc dns *
  *
#ISCELL
  pure_quanta quanta_title_block_c *
  *
#ISCELL
  logical_power universal_power *
  page296_i11
#ISCELL
  logical_power universal_gnd *
  page296_i12
#CELL
  pure_quanta q_cap *
  page296_i13
#CELL
  pure_quanta 74lvc2g07dw7 *
  page296_i16
#ISCELL
  logical_power universal_gnd *
  page296_i17
#ISCELL
  logical_power universal_power *
  page296_i28
#CELL
  pure_quanta q_res *
  page296_i29
#ISCELL
  logical_power universal_gnd *
  page296_i30
#CELL
  pure_quanta q_res *
  page296_i31
#ISCELL
  standard offpage *
  page296_i32
#CELL
  pure_quanta q_res *
  page296_i33
#ISCELL
  logical_power universal_power *
  page296_i34
#CELL
  pure_quanta q_res *
  page296_i35
#ISCELL
  standard offpage *
  page296_i36
#CELL
  pure_quanta q_res *
  page296_i37
#ISCELL
  logical_power universal_gnd *
  page296_i38
#ISCELL
  logical_power universal_power *
  page296_i39
#CELL
  pure_quanta q_res *
  page296_i40
#ISCELL
  standard offpage *
  page296_i41
#CELL
  pure_quanta q_res *
  page296_i42
#ISCELL
  logical_power universal_gnd *
  page296_i43
#ISCELL
  standard offpage *
  page296_i44
#CELL
  pure_quanta q_res *
  page296_i45
#ISCELL
  logical_power universal_power *
  page296_i46
#CELL
  pure_quanta q_res *
  page296_i47
#CELL
  pure_quanta q_res *
  page296_i48
#ISCELL
  logical_power universal_gnd *
  page296_i49
#CELL
  pure_quanta 74lvc2g07dw7 *
  page296_i50
#ISCELL
  standard offpage *
  page296_i51
#CELL
  pure_quanta q_res *
  page296_i53
#ISCELL
  logical_power universal_power *
  page296_i54
#CELL
  pure_quanta q_res *
  page296_i55
#ISCELL
  logical_power universal_power *
  page296_i56
#CELL
  pure_quanta q_res *
  page296_i57
#ISCELL
  standard offpage *
  page296_i58
#CELL
  pure_quanta q_res *
  page296_i62
#ISCELL
  logical_power universal_gnd *
  page296_i63
#ISCELL
  logical_power universal_power *
  page296_i66
#CELL
  pure_quanta q_cap *
  page296_i67
#ISCELL
  logical_power universal_gnd *
  page296_i68
#ISCELL
  logical_power universal_gnd *
  page296_i69
#CELL
  pure_quanta q_res *
  page296_i70
#ISCELL
  logical_power universal_gnd *
  page296_i74
#ISCELL
  mstr_misc dns *
  *
#ISCELL
  pure_quanta quanta_title_block_c *
  *
#CELL
  pure_quanta q_res *
  page140_i121
#ISCELL
  logical_power universal_gnd *
  page140_i122
#ISCELL
  logical_power universal_gnd *
  page140_i125
#CELL
  pure_quanta 74lvc2g17gw *
  page140_i127
#ISCELL
  standard offpage *
  page140_i129
#ISCELL
  logical_power universal_gnd *
  page140_i132
#ISCELL
  logical_power universal_power *
  page140_i139
#CELL
  pure_quanta q_cap *
  page140_i140
#ISCELL
  logical_power universal_gnd *
  page140_i141
#ISCELL
  logical_power universal_gnd *
  page140_i142
#ISCELL
  standard offpage *
  page140_i146
#CELL
  pure_quanta q_res *
  page140_i147
#ISCELL
  logical_power universal_power *
  page140_i148
#CELL
  pure_quanta q_res *
  page140_i153
#ISCELL
  logical_power universal_gnd *
  page140_i159
#CELL
  pure_quanta q_res *
  page140_i160
#ISCELL
  logical_power universal_power *
  page140_i161
#CELL
  pure_quanta q_res *
  page140_i162
#ISCELL
  logical_power universal_power *
  page140_i165
#CELL
  pure_quanta q_cap *
  page140_i166
#ISCELL
  logical_power universal_gnd *
  page140_i167
#CELL
  pure_quanta q_res *
  page140_i170
#ISCELL
  standard offpage *
  page140_i172
#ISCELL
  standard offpage *
  page140_i173
#ISCELL
  logical_power universal_power *
  page140_i174
#ISCELL
  standard offpage *
  page140_i177
#ISCELL
  logical_power universal_gnd *
  page140_i178
#ISCELL
  standard offpage *
  page140_i180
#ISCELL
  logical_power universal_power *
  page140_i183
#ISCELL
  logical_power universal_gnd *
  page140_i184
#CELL
  pure_quanta q_res *
  page140_i190
#CELL
  pure_quanta q_res *
  page140_i191
#CELL
  pure_quanta q_res *
  page140_i192
#CELL
  pure_quanta q_res *
  page140_i193
#CELL
  pure_quanta q_res *
  page140_i194
#CELL
  pure_quanta 74lvc1g126se7 *
  page140_i195
#ISCELL
  logical_power universal_gnd *
  page140_i196
#CELL
  pure_quanta q_res *
  page140_i197
#CELL
  pure_quanta q_res *
  page140_i198
#ISCELL
  logical_power universal_power *
  page140_i199
#CELL
  pure_quanta q_res *
  page140_i200
#ISCELL
  logical_power universal_power *
  page140_i201
#CELL
  pure_quanta q_res *
  page140_i202
#CELL
  pure_quanta q_res *
  page140_i203
#CELL
  pure_quanta q_res *
  page140_i204
#CELL
  pure_quanta q_res *
  page140_i205
#CELL
  pure_quanta q_res *
  page140_i206
#CELL
  pure_quanta q_res *
  page140_i207
#CELL
  pure_quanta q_res *
  page140_i208
#ISCELL
  standard offpage *
  page140_i209
#CELL
  pure_quanta 74lvc2g17gw *
  page140_i65
#ISCELL
  logical_power universal_power *
  page140_i67
#CELL
  pure_quanta q_res *
  page140_i68
#ISCELL
  logical_power universal_gnd *
  page140_i69
#ISCELL
  standard offpage *
  page140_i70
#ISCELL
  logical_power universal_power *
  page140_i71
#ISCELL
  logical_power universal_gnd *
  page140_i74
#ISCELL
  standard offpage *
  page140_i75
#ISCELL
  logical_power universal_gnd *
  page140_i76
#CELL
  pure_quanta q_res *
  page140_i78
#ISCELL
  standard offpage *
  page140_i79
#ISCELL
  logical_power universal_power *
  page140_i80
#ISCELL
  standard offpage *
  page140_i82
#ISCELL
  logical_power universal_power *
  page140_i83
#ISCELL
  logical_power universal_power *
  page140_i87
#ISCELL
  logical_power universal_gnd *
  page140_i88
#CELL
  pure_quanta q_cap *
  page140_i89
#CELL
  pure_quanta q_res *
  page140_i92
#CELL
  pure_quanta q_res *
  page140_i93
#ISCELL
  logical_power cad_note *
  *
#ISCELL
  mstr_misc dns *
  *
#ISCELL
  pure_quanta quanta_title_block_c *
  *
#CELL
  pure_quanta gl852gohy60 *
  page155_i100
#ISCELL
  logical_power universal_gnd *
  page155_i115
#ISCELL
  logical_power universal_gnd *
  page155_i116
#ISCELL
  logical_power universal_gnd *
  page155_i117
#ISCELL
  logical_power universal_gnd *
  page155_i118
#ISCELL
  logical_power universal_gnd *
  page155_i122
#ISCELL
  standard offpage *
  page155_i133
#ISCELL
  standard offpage *
  page155_i134
#ISCELL
  standard offpage *
  page155_i135
#ISCELL
  standard offpage *
  page155_i136
#CELL
  pure_quanta q_res *
  page155_i137
#CELL
  pure_quanta q_res *
  page155_i138
#CELL
  pure_quanta q_res *
  page155_i139
#ISCELL
  logical_power universal_gnd *
  page155_i140
#CELL
  pure_quanta q_cap *
  page155_i142
#CELL
  pure_quanta q_cap *
  page155_i143
#ISCELL
  logical_power universal_power *
  page155_i144
#CELL
  pure_quanta q_cap *
  page155_i145
#CELL
  pure_quanta q_cap *
  page155_i147
#CELL
  pure_quanta q_cap *
  page155_i148
#ISCELL
  logical_power universal_power *
  page155_i151
#CELL
  pure_quanta q_res *
  page155_i155
#ISCELL
  standard offpage *
  page155_i156
#ISCELL
  logical_power universal_gnd *
  page155_i157
#CELL
  pure_quanta q_cap *
  page155_i158
#CELL
  pure_quanta q_res *
  page155_i159
#CELL
  pure_quanta q_res *
  page155_i161
#CELL
  pure_quanta q_cap *
  page155_i162
#CELL
  pure_quanta q_cap *
  page155_i163
#CELL
  pure_quanta q_cap *
  page155_i164
#ISCELL
  logical_power universal_gnd *
  page155_i165
#ISCELL
  logical_power universal_gnd *
  page155_i166
#CELL
  pure_quanta q_res *
  page155_i167
#ISCELL
  standard offpage *
  page155_i168
#ISCELL
  standard offpage *
  page155_i169
#ISCELL
  standard offpage *
  page155_i170
#ISCELL
  standard offpage *
  page155_i171
#CELL
  pure_quanta q_res *
  page155_i182
#ISCELL
  logical_power universal_gnd *
  page155_i183
#ISCELL
  standard offpage *
  page155_i184
#ISCELL
  logical_power universal_power *
  page155_i185
#CELL
  pure_quanta q_res *
  page155_i186
#CELL
  pure_quanta q_res *
  page155_i187
#ISCELL
  logical_power universal_gnd *
  page155_i188
#ISCELL
  standard offpage *
  page155_i189
#ISCELL
  standard offpage *
  page155_i190
#ISCELL
  standard offpage *
  page155_i191
#ISCELL
  standard offpage *
  page155_i192
#ISCELL
  standard offpage *
  page155_i193
#CELL
  pure_quanta q_res *
  page155_i194
#CELL
  pure_quanta q_res *
  page155_i195
#CELL
  pure_quanta q_res *
  page155_i196
#ISCELL
  logical_power universal_power *
  page155_i197
#CELL
  pure_quanta q_res *
  page155_i198
#CELL
  pure_quanta q_res *
  page155_i199
#CELL
  pure_quanta q_xtal_4p_13bi_24gnd *
  page155_i200
#CELL
  pure_quanta q_res *
  page155_i201
#CELL
  pure_quanta q_res *
  page155_i202
#CELL
  pure_quanta q_res *
  page155_i203
#ISCELL
  logical_power universal_gnd *
  page155_i204
#ISCELL
  logical_power universal_gnd *
  page155_i205
#CELL
  pure_quanta q_res *
  page155_i206
#ISCELL
  logical_power universal_gnd *
  page155_i207
#CELL
  pure_quanta q_res *
  page155_i208
#ISCELL
  logical_power universal_gnd *
  page155_i209
#CELL
  pure_quanta q_cap *
  page155_i210
#CELL
  pure_quanta q_cap *
  page155_i211
#ISCELL
  standard offpage *
  page155_i76
#ISCELL
  standard offpage *
  page155_i77
#CELL
  pure_quanta q_res *
  page155_i78
#CELL
  pure_quanta q_res *
  page155_i79
#ISCELL
  logical_power universal_gnd *
  page155_i80
#CELL
  pure_quanta q_cap *
  page155_i81
#ISCELL
  logical_power universal_gnd *
  page155_i82
#CELL
  pure_quanta q_res *
  page155_i83
#CELL
  pure_quanta tusb211irwbr *
  page155_i84
#ISCELL
  logical_power universal_gnd *
  page155_i85
#ISCELL
  logical_power universal_gnd *
  page155_i86
#CELL
  pure_quanta q_cap *
  page155_i87
#CELL
  pure_quanta q_cap *
  page155_i88
#ISCELL
  logical_power universal_gnd *
  page155_i89
#CELL
  pure_quanta q_res *
  page155_i90
#CELL
  pure_quanta q_res *
  page155_i91
#CELL
  pure_quanta q_cap *
  page155_i92
#ISCELL
  standard offpage *
  page155_i93
#ISCELL
  standard offpage *
  page155_i94
#ISCELL
  logical_power universal_power *
  page155_i95
#CELL
  pure_quanta q_res *
  page155_i96
#CELL
  pure_quanta q_res *
  page155_i97
#CELL
  pure_quanta q_res *
  page155_i98
#CELL
  pure_quanta q_res *
  page155_i99
#ISCELL
  logical_power cad_note *
  *
#ISCELL
  mstr_misc dns *
  *
#ISCELL
  pure_quanta quanta_title_block_c *
  *
#ISCELL
  logical_power universal_gnd *
  page150_i1
#ISCELL
  standard offpage *
  page150_i10
#ISCELL
  standard tap *
  page150_i100
#ISCELL
  standard tap *
  page150_i101
#ISCELL
  standard tap *
  page150_i102
#ISCELL
  standard tap *
  page150_i103
#ISCELL
  standard tap *
  page150_i104
#ISCELL
  standard tap *
  page150_i105
#ISCELL
  standard tap *
  page150_i106
#ISCELL
  standard tap *
  page150_i107
#ISCELL
  standard tap *
  page150_i108
#ISCELL
  standard tap *
  page150_i109
#CELL
  pure_quanta q_cap *
  page150_i110
#CELL
  pure_quanta q_cap *
  page150_i111
#ISCELL
  logical_power universal_gnd *
  page150_i112
#CELL
  pure_quanta q_cap *
  page150_i113
#CELL
  pure_quanta q_cap *
  page150_i114
#CELL
  pure_quanta q_cap *
  page150_i115
#CELL
  pure_quanta q_cap *
  page150_i116
#ISCELL
  standard offpage *
  page150_i117
#CELL
  pure_quanta q_res *
  page150_i118
#CELL
  pure_quanta q_res *
  page150_i119
#ISCELL
  standard offpage *
  page150_i12
#ISCELL
  logical_power universal_power *
  page150_i120
#ISCELL
  standard offpage *
  page150_i121
#ISCELL
  standard offpage *
  page150_i122
#ISCELL
  standard tap *
  page150_i123
#ISCELL
  standard tap *
  page150_i124
#ISCELL
  standard tap *
  page150_i125
#ISCELL
  standard tap *
  page150_i126
#ISCELL
  standard tap *
  page150_i127
#ISCELL
  standard tap *
  page150_i128
#ISCELL
  standard tap *
  page150_i129
#ISCELL
  standard tap *
  page150_i130
#ISCELL
  standard tap *
  page150_i131
#ISCELL
  standard tap *
  page150_i132
#ISCELL
  standard tap *
  page150_i133
#ISCELL
  standard tap *
  page150_i134
#ISCELL
  standard tap *
  page150_i136
#ISCELL
  standard tap *
  page150_i137
#ISCELL
  standard tap *
  page150_i138
#ISCELL
  standard offpage *
  page150_i140
#ISCELL
  standard offpage *
  page150_i142
#ISCELL
  standard offpage *
  page150_i143
#ISCELL
  standard offpage *
  page150_i144
#ISCELL
  standard offpage *
  page150_i145
#ISCELL
  standard offpage *
  page150_i146
#ISCELL
  standard offpage *
  page150_i147
#ISCELL
  logical_power universal_gnd *
  page150_i148
#CELL
  pure_quanta q_res *
  page150_i149
#ISCELL
  standard offpage *
  page150_i15
#ISCELL
  standard offpage *
  page150_i150
#CELL
  pure_quanta q_res *
  page150_i151
#ISCELL
  standard offpage *
  page150_i152
#ISCELL
  standard offpage *
  page150_i153
#ISCELL
  standard offpage *
  page150_i154
#ISCELL
  standard offpage *
  page150_i155
#ISCELL
  standard offpage *
  page150_i156
#ISCELL
  standard offpage *
  page150_i157
#ISCELL
  standard offpage *
  page150_i158
#ISCELL
  standard offpage *
  page150_i159
#ISCELL
  standard offpage *
  page150_i16
#ISCELL
  standard offpage *
  page150_i160
#ISCELL
  standard offpage *
  page150_i161
#ISCELL
  standard offpage *
  page150_i162
#ISCELL
  standard offpage *
  page150_i163
#ISCELL
  standard offpage *
  page150_i164
#ISCELL
  logical_power universal_gnd *
  page150_i167
#CELL
  pure_quanta q_cap *
  page150_i168
#ISCELL
  standard tap *
  page150_i169
#ISCELL
  standard tap *
  page150_i17
#ISCELL
  standard offpage *
  page150_i171
#ISCELL
  logical_power universal_power *
  page150_i173
#ISCELL
  logical_power universal_power *
  page150_i174
#ISCELL
  standard tap *
  page150_i176
#ISCELL
  standard tap *
  page150_i177
#ISCELL
  standard tap *
  page150_i179
#ISCELL
  standard tap *
  page150_i180
#ISCELL
  standard tap *
  page150_i182
#ISCELL
  standard tap *
  page150_i183
#ISCELL
  standard tap *
  page150_i185
#ISCELL
  standard tap *
  page150_i186
#ISCELL
  standard tap *
  page150_i188
#ISCELL
  standard tap *
  page150_i189
#ISCELL
  standard tap *
  page150_i191
#ISCELL
  standard tap *
  page150_i192
#ISCELL
  standard tap *
  page150_i194
#ISCELL
  standard tap *
  page150_i195
#ISCELL
  standard tap *
  page150_i197
#ISCELL
  standard tap *
  page150_i198
#CELL
  pure_quanta sconn168_me1016810202011 *
  page150_i199
#CELL
  pure_quanta q_res *
  page150_i2
#ISCELL
  standard tap *
  page150_i20
#ISCELL
  standard tap *
  page150_i202
#ISCELL
  standard tap *
  page150_i203
#ISCELL
  standard tap *
  page150_i205
#ISCELL
  standard tap *
  page150_i206
#ISCELL
  standard tap *
  page150_i21
#ISCELL
  standard offpage *
  page150_i211
#CELL
  pure_quanta q_res *
  page150_i212
#ISCELL
  standard offpage *
  page150_i213
#CELL
  pure_quanta q_res *
  page150_i215
#CELL
  pure_quanta q_res *
  page150_i217
#CELL
  pure_quanta q_res *
  page150_i218
#ISCELL
  standard offpage *
  page150_i219
#CELL
  pure_quanta q_res *
  page150_i220
#ISCELL
  logical_power universal_gnd *
  page150_i25
#ISCELL
  standard tap *
  page150_i28
#ISCELL
  logical_power universal_gnd *
  page150_i3
#ISCELL
  standard tap *
  page150_i30
#ISCELL
  standard tap *
  page150_i32
#ISCELL
  logical_power universal_gnd *
  page150_i34
#CELL
  pure_quanta q_res *
  page150_i35
#CELL
  pure_quanta q_res *
  page150_i36
#CELL
  pure_quanta q_res *
  page150_i37
#ISCELL
  standard offpage *
  page150_i38
#ISCELL
  standard offpage *
  page150_i39
#CELL
  pure_quanta q_res *
  page150_i4
#ISCELL
  standard offpage *
  page150_i40
#ISCELL
  standard offpage *
  page150_i41
#ISCELL
  standard offpage *
  page150_i42
#ISCELL
  standard offpage *
  page150_i43
#ISCELL
  standard offpage *
  page150_i44
#ISCELL
  standard offpage *
  page150_i45
#ISCELL
  standard offpage *
  page150_i46
#ISCELL
  standard offpage *
  page150_i47
#ISCELL
  standard offpage *
  page150_i48
#CELL
  pure_quanta q_res *
  page150_i5
#ISCELL
  standard offpage *
  page150_i50
#CELL
  pure_quanta q_res *
  page150_i51
#CELL
  pure_quanta q_res *
  page150_i52
#CELL
  pure_quanta q_res *
  page150_i53
#CELL
  pure_quanta q_res *
  page150_i54
#ISCELL
  standard offpage *
  page150_i55
#CELL
  pure_quanta q_res *
  page150_i58
#ISCELL
  standard tap *
  page150_i59
#CELL
  pure_quanta q_res *
  page150_i6
#ISCELL
  standard tap *
  page150_i62
#ISCELL
  standard tap *
  page150_i63
#ISCELL
  standard tap *
  page150_i66
#ISCELL
  standard tap *
  page150_i69
#ISCELL
  logical_power universal_power *
  page150_i7
#ISCELL
  standard tap *
  page150_i70
#ISCELL
  standard tap *
  page150_i73
#ISCELL
  standard offpage *
  page150_i76
#ISCELL
  standard offpage *
  page150_i77
#ISCELL
  standard offpage *
  page150_i78
#ISCELL
  standard offpage *
  page150_i79
#ISCELL
  standard offpage *
  page150_i8
#ISCELL
  standard offpage *
  page150_i80
#ISCELL
  standard offpage *
  page150_i81
#ISCELL
  standard offpage *
  page150_i82
#ISCELL
  standard offpage *
  page150_i83
#ISCELL
  standard offpage *
  page150_i84
#ISCELL
  standard offpage *
  page150_i85
#ISCELL
  logical_power universal_gnd *
  page150_i88
#CELL
  pure_quanta q_cap *
  page150_i89
#ISCELL
  standard offpage *
  page150_i9
#CELL
  pure_quanta q_cap *
  page150_i90
#CELL
  pure_quanta q_cap *
  page150_i91
#ISCELL
  logical_power universal_power *
  page150_i92
#ISCELL
  logical_power universal_power *
  page150_i93
#ISCELL
  logical_power universal_gnd *
  page150_i94
#ISCELL
  standard tap *
  page150_i95
#ISCELL
  standard tap *
  page150_i96
#ISCELL
  standard tap *
  page150_i97
#ISCELL
  standard tap *
  page150_i98
#ISCELL
  standard tap *
  page150_i99
#ISCELL
  mstr_misc dns *
  *
#ISCELL
  pure_quanta quanta_title_block_c *
  *
#ISCELL
  standard offpage *
  page151_i1
#ISCELL
  standard offpage *
  page151_i10
#ISCELL
  logical_power universal_gnd *
  page151_i11
#ISCELL
  logical_power universal_gnd *
  page151_i12
#CELL
  pure_quanta q_res *
  page151_i13
#ISCELL
  standard offpage *
  page151_i14
#CELL
  pure_quanta 74lvc1g126se7 *
  page151_i15
#ISCELL
  logical_power universal_gnd *
  page151_i16
#CELL
  pure_quanta q_res *
  page151_i17
#CELL
  pure_quanta q_res *
  page151_i19
#ISCELL
  standard offpage *
  page151_i2
#ISCELL
  logical_power universal_gnd *
  page151_i20
#CELL
  pure_quanta q_res *
  page151_i21
#CELL
  pure_quanta q_cap *
  page151_i22
#ISCELL
  logical_power universal_gnd *
  page151_i23
#ISCELL
  logical_power universal_power *
  page151_i24
#ISCELL
  standard offpage *
  page151_i25
#ISCELL
  standard offpage *
  page151_i26
#ISCELL
  standard offpage *
  page151_i27
#ISCELL
  standard offpage *
  page151_i28
#ISCELL
  logical_power universal_gnd *
  page151_i29
#CELL
  pure_quanta q_res *
  page151_i3
#CELL
  pure_quanta 74cbtlv3126pw *
  page151_i30
#ISCELL
  logical_power universal_gnd *
  page151_i31
#CELL
  pure_quanta q_cap *
  page151_i32
#ISCELL
  logical_power universal_power *
  page151_i33
#ISCELL
  standard offpage *
  page151_i34
#ISCELL
  standard offpage *
  page151_i35
#ISCELL
  standard offpage *
  page151_i36
#ISCELL
  standard offpage *
  page151_i37
#ISCELL
  logical_power universal_gnd *
  page151_i38
#CELL
  pure_quanta 74cbtlv3126pw *
  page151_i39
#ISCELL
  standard offpage *
  page151_i4
#CELL
  pure_quanta q_cap *
  page151_i40
#ISCELL
  logical_power universal_gnd *
  page151_i41
#ISCELL
  logical_power universal_power *
  page151_i42
#CELL
  pure_quanta q_res *
  page151_i43
#ISCELL
  standard offpage *
  page151_i44
#ISCELL
  standard offpage *
  page151_i45
#ISCELL
  standard offpage *
  page151_i46
#ISCELL
  standard offpage *
  page151_i47
#ISCELL
  standard offpage *
  page151_i48
#ISCELL
  standard offpage *
  page151_i49
#CELL
  pure_quanta q_res *
  page151_i5
#CELL
  pure_quanta q_res *
  page151_i50
#ISCELL
  logical_power universal_gnd *
  page151_i51
#CELL
  pure_quanta q_res *
  page151_i52
#CELL
  pure_quanta q_res *
  page151_i53
#CELL
  pure_quanta q_res *
  page151_i54
#CELL
  pure_quanta q_res *
  page151_i55
#CELL
  pure_quanta q_res *
  page151_i56
#ISCELL
  standard offpage *
  page151_i57
#ISCELL
  standard offpage *
  page151_i58
#ISCELL
  standard offpage *
  page151_i59
#ISCELL
  logical_power universal_gnd *
  page151_i6
#ISCELL
  logical_power universal_gnd *
  page151_i60
#CELL
  pure_quanta q_res *
  page151_i61
#ISCELL
  standard offpage *
  page151_i62
#ISCELL
  standard offpage *
  page151_i63
#ISCELL
  standard offpage *
  page151_i64
#CELL
  pure_quanta q_res *
  page151_i65
#CELL
  pure_quanta q_res *
  page151_i66
#CELL
  pure_quanta q_res *
  page151_i67
#CELL
  pure_quanta q_res *
  page151_i68
#CELL
  pure_quanta q_res *
  page151_i69
#CELL
  pure_quanta 74lvc1g126se7 *
  page151_i7
#ISCELL
  standard offpage *
  page151_i70
#CELL
  pure_quanta q_res *
  page151_i71
#CELL
  pure_quanta q_res *
  page151_i72
#CELL
  pure_quanta q_res *
  page151_i73
#ISCELL
  standard offpage *
  page151_i74
#ISCELL
  standard offpage *
  page151_i75
#ISCELL
  standard offpage *
  page151_i76
#ISCELL
  standard offpage *
  page151_i77
#ISCELL
  standard offpage *
  page151_i78
#ISCELL
  standard offpage *
  page151_i79
#CELL
  pure_quanta q_cap *
  page151_i8
#CELL
  pure_quanta q_res *
  page151_i80
#CELL
  pure_quanta q_res *
  page151_i81
#ISCELL
  standard offpage *
  page151_i82
#CELL
  pure_quanta q_res *
  page151_i83
#ISCELL
  logical_power universal_power *
  page151_i9
#ISCELL
  logical_power cad_note *
  *
#ISCELL
  mstr_misc dns *
  *
#ISCELL
  pure_quanta quanta_title_block_c *
  *
#CELL
  pure_quanta 74lvc1g17gw *
  page152_i1
#CELL
  pure_quanta q_res *
  page152_i10
#ISCELL
  standard offpage *
  page152_i11
#ISCELL
  standard offpage *
  page152_i12
#CELL
  pure_quanta q_res *
  page152_i13
#ISCELL
  logical_power universal_gnd *
  page152_i14
#ISCELL
  standard offpage *
  page152_i2
#ISCELL
  standard offpage *
  page152_i21
#CELL
  pure_quanta q_cap *
  page152_i24
#ISCELL
  logical_power universal_gnd *
  page152_i25
#CELL
  pure_quanta q_res *
  page152_i26
#ISCELL
  standard offpage *
  page152_i29
#ISCELL
  logical_power universal_gnd *
  page152_i3
#ISCELL
  logical_power universal_gnd *
  page152_i32
#ISCELL
  logical_power universal_power *
  page152_i36
#CELL
  pure_quanta q_res *
  page152_i37
#ISCELL
  logical_power universal_power *
  page152_i38
#ISCELL
  standard offpage *
  page152_i39
#CELL
  pure_quanta q_cap *
  page152_i4
#CELL
  pure_quanta q_res *
  page152_i40
#ISCELL
  logical_power universal_power *
  page152_i41
#CELL
  pure_quanta q_res *
  page152_i42
#ISCELL
  logical_power universal_power *
  page152_i43
#CELL
  pure_quanta q_cap *
  page152_i44
#ISCELL
  logical_power universal_gnd *
  page152_i45
#CELL
  pure_quanta pi6cv304le *
  page152_i46
#ISCELL
  logical_power universal_power *
  page152_i47
#ISCELL
  logical_power universal_power *
  page152_i48
#CELL
  pure_quanta q_cap *
  page152_i49
#ISCELL
  logical_power universal_power *
  page152_i5
#ISCELL
  standard offpage *
  page152_i50
#ISCELL
  standard offpage *
  page152_i51
#CELL
  pure_quanta q_res *
  page152_i52
#CELL
  pure_quanta q_res *
  page152_i53
#ISCELL
  logical_power universal_gnd *
  page152_i54
#ISCELL
  logical_power universal_gnd *
  page152_i55
#CELL
  pure_quanta q_res *
  page152_i56
#ISCELL
  logical_power universal_gnd *
  page152_i57
#CELL
  pure_quanta q_cap *
  page152_i59
#CELL
  pure_quanta q_res *
  page152_i6
#ISCELL
  logical_power universal_gnd *
  page152_i60
#CELL
  pure_quanta q_res *
  page152_i61
#CELL
  pure_quanta q_res *
  page152_i62
#CELL
  pure_quanta 74lvc1g07gv *
  page152_i63
#CELL
  pure_quanta 74lvc1g07gv *
  page152_i65
#ISCELL
  logical_power universal_gnd *
  page152_i66
#ISCELL
  logical_power universal_power *
  page152_i67
#CELL
  pure_quanta q_cap *
  page152_i68
#ISCELL
  logical_power universal_gnd *
  page152_i69
#ISCELL
  standard offpage *
  page152_i7
#ISCELL
  standard offpage *
  page152_i70
#CELL
  pure_quanta q_res *
  page152_i71
#ISCELL
  logical_power universal_power *
  page152_i72
#ISCELL
  logical_power universal_power *
  page152_i73
#CELL
  pure_quanta q_res *
  page152_i74
#CELL
  pure_quanta q_res *
  page152_i75
#CELL
  pure_quanta q_osc4p *
  page152_i76
#ISCELL
  standard offpage *
  page152_i77
#CELL
  pure_quanta q_res *
  page152_i78
#CELL
  pure_quanta 74lvc1g126se7 *
  page152_i79
#CELL
  pure_quanta q_res *
  page152_i8
#ISCELL
  logical_power universal_gnd *
  page152_i80
#ISCELL
  standard offpage *
  page152_i83
#ISCELL
  logical_power universal_gnd *
  page152_i84
#ISCELL
  logical_power universal_power *
  page152_i85
#ISCELL
  logical_power universal_gnd *
  page152_i86
#CELL
  pure_quanta q_cap *
  page152_i87
#ISCELL
  standard offpage *
  page152_i88
#ISCELL
  standard offpage *
  page152_i9
#CELL
  pure_quanta q_res *
  page152_i90
#ISCELL
  standard offpage *
  page152_i91
#CELL
  pure_quanta 74lvc1g66gv *
  page152_i92
#ISCELL
  logical_power cad_note *
  *
#ISCELL
  mstr_misc dns *
  *
#ISCELL
  pure_quanta quanta_title_block_c *
  *
#ISCELL
  logical_power universal_gnd *
  page153_i1
#ISCELL
  logical_power gnd *
  page153_i10
#ISCELL
  standard offpage *
  page153_i100
#CELL
  pure_quanta q_cap *
  page153_i101
#CELL
  pure_quanta q_res *
  page153_i102
#CELL
  pure_quanta q_res *
  page153_i103
#CELL
  pure_quanta schottky_ac *
  page153_i104
#CELL
  pure_quanta q_res *
  page153_i105
#ISCELL
  logical_power gnd *
  page153_i106
#CELL
  pure_quanta q_cap *
  page153_i107
#CELL
  pure_quanta q_res *
  page153_i108
#ISCELL
  logical_power vccaux15 *
  page153_i109
#ISCELL
  standard offpage *
  page153_i11
#CELL
  pure_quanta q_res *
  page153_i110
#CELL
  pure_quanta q_cap *
  page153_i111
#ISCELL
  logical_power gnd *
  page153_i112
#CELL
  pure_quanta q_cap *
  page153_i113
#ISCELL
  logical_power universal_power *
  page153_i114
#ISCELL
  standard offpage *
  page153_i115
#ISCELL
  standard offpage *
  page153_i12
#CELL
  pure_quanta q_res *
  page153_i13
#ISCELL
  logical_power universal_power *
  page153_i14
#CELL
  pure_quanta q_res *
  page153_i15
#ISCELL
  logical_power universal_power *
  page153_i16
#CELL
  pure_quanta mosfet_nch_dual *
  page153_i17
#ISCELL
  logical_power gnd *
  page153_i18
#CELL
  pure_quanta q_res *
  page153_i19
#ISCELL
  logical_power universal_gnd *
  page153_i2
#CELL
  pure_quanta q_res *
  page153_i20
#CELL
  pure_quanta mosfet_nch_dual *
  page153_i21
#CELL
  pure_quanta q_res *
  page153_i22
#CELL
  pure_quanta 74lvc2g07dw7 *
  page153_i23
#ISCELL
  logical_power universal_gnd *
  page153_i24
#CELL
  pure_quanta q_res *
  page153_i25
#CELL
  pure_quanta 74lvc2g07dw7 *
  page153_i26
#CELL
  pure_quanta q_cap *
  page153_i27
#ISCELL
  logical_power universal_power *
  page153_i28
#ISCELL
  logical_power universal_gnd *
  page153_i29
#ISCELL
  standard offpage *
  page153_i3
#CELL
  pure_quanta q_cap *
  page153_i30
#ISCELL
  logical_power universal_power *
  page153_i31
#ISCELL
  logical_power gnd *
  page153_i32
#CELL
  pure_quanta q_res *
  page153_i33
#ISCELL
  logical_power gnd *
  page153_i34
#ISCELL
  logical_power gnd *
  page153_i35
#CELL
  pure_quanta mosfet_nch_dual *
  page153_i36
#ISCELL
  logical_power gnd *
  page153_i37
#CELL
  pure_quanta diode_tvs *
  page153_i38
#CELL
  pure_quanta q_res *
  page153_i39
#CELL
  pure_quanta q_res *
  page153_i4
#ISCELL
  logical_power gnd *
  page153_i40
#CELL
  pure_quanta q_res *
  page153_i41
#CELL
  pure_quanta q_res *
  page153_i42
#ISCELL
  logical_power universal_power *
  page153_i43
#CELL
  pure_quanta q_cap *
  page153_i44
#CELL
  pure_quanta q_res *
  page153_i45
#CELL
  pure_quanta q_res *
  page153_i46
#CELL
  pure_quanta q_res *
  page153_i47
#ISCELL
  logical_power gnd *
  page153_i48
#CELL
  pure_quanta q_res *
  page153_i49
#ISCELL
  standard offpage *
  page153_i5
#CELL
  pure_quanta q_res *
  page153_i50
#CELL
  pure_quanta max15090bewit *
  page153_i51
#ISCELL
  logical_power universal_power *
  page153_i52
#ISCELL
  logical_power gnd *
  page153_i53
#CELL
  pure_quanta q_cap *
  page153_i54
#CELL
  pure_quanta q_cap *
  page153_i55
#CELL
  pure_quanta q_res *
  page153_i56
#ISCELL
  logical_power gnd *
  page153_i57
#CELL
  pure_quanta q_res *
  page153_i58
#ISCELL
  logical_power gnd *
  page153_i59
#ISCELL
  standard offpage *
  page153_i6
#CELL
  pure_quanta q_res *
  page153_i60
#CELL
  pure_quanta max15090bewit *
  page153_i61
#CELL
  pure_quanta q_res *
  page153_i62
#ISCELL
  logical_power universal_power *
  page153_i63
#CELL
  pure_quanta q_res *
  page153_i64
#ISCELL
  logical_power gnd *
  page153_i65
#CELL
  pure_quanta q_cap *
  page153_i66
#ISCELL
  logical_power universal_power *
  page153_i67
#CELL
  pure_quanta q_res *
  page153_i68
#ISCELL
  logical_power gnd *
  page153_i69
#CELL
  pure_quanta q_res *
  page153_i7
#CELL
  pure_quanta q_res *
  page153_i70
#CELL
  pure_quanta q_cap *
  page153_i71
#CELL
  pure_quanta q_cap *
  page153_i72
#CELL
  pure_quanta q_res *
  page153_i73
#CELL
  pure_quanta q_res *
  page153_i74
#ISCELL
  standard offpage *
  page153_i75
#CELL
  pure_quanta q_res *
  page153_i76
#ISCELL
  standard offpage *
  page153_i77
#ISCELL
  standard offpage *
  page153_i78
#ISCELL
  logical_power gnd *
  page153_i79
#ISCELL
  logical_power universal_power *
  page153_i8
#CELL
  pure_quanta q_res *
  page153_i80
#CELL
  pure_quanta q_cap *
  page153_i81
#CELL
  pure_quanta q_res *
  page153_i82
#CELL
  pure_quanta q_cap *
  page153_i83
#CELL
  pure_quanta q_res *
  page153_i84
#ISCELL
  logical_power gnd *
  page153_i85
#CELL
  pure_quanta schottky_ac *
  page153_i86
#CELL
  pure_quanta q_res *
  page153_i87
#CELL
  pure_quanta q_res *
  page153_i88
#ISCELL
  logical_power gnd *
  page153_i89
#CELL
  pure_quanta mosfet_nch_dual *
  page153_i9
#CELL
  pure_quanta q_res *
  page153_i90
#ISCELL
  logical_power vccaux15 *
  page153_i91
#CELL
  pure_quanta q_res *
  page153_i92
#CELL
  pure_quanta q_cap *
  page153_i93
#CELL
  pure_quanta q_cap *
  page153_i94
#ISCELL
  logical_power gnd *
  page153_i95
#CELL
  pure_quanta q_cap *
  page153_i96
#ISCELL
  logical_power universal_power *
  page153_i97
#ISCELL
  standard offpage *
  page153_i98
#ISCELL
  standard offpage *
  page153_i99
#ISCELL
  logical_power cad_note *
  *
#ISCELL
  mstr_misc dns *
  *
#ISCELL
  pure_quanta quanta_title_block_c *
  *
#ISCELL
  standard offpage *
  page236_i31
#ISCELL
  logical_power universal_gnd *
  page236_i41
#CELL
  pure_quanta q_cap *
  page236_i42
#CELL
  pure_quanta q_res *
  page236_i43
#ISCELL
  logical_power universal_gnd *
  page236_i44
#CELL
  pure_quanta q_res *
  page236_i45
#CELL
  pure_quanta q_res *
  page236_i46
#ISCELL
  logical_power universal_gnd *
  page236_i47
#ISCELL
  logical_power universal_gnd *
  page236_i48
#CELL
  pure_quanta q_cap *
  page236_i49
#CELL
  pure_quanta mp5016gqhlz *
  page236_i50
#ISCELL
  logical_power universal_gnd *
  page236_i51
#CELL
  pure_quanta q_cap *
  page236_i52
#ISCELL
  logical_power universal_gnd *
  page236_i53
#CELL
  pure_quanta q_cap *
  page236_i54
#CELL
  pure_quanta q_cap *
  page236_i55
#ISCELL
  logical_power universal_power *
  page236_i56
#ISCELL
  logical_power universal_power *
  page236_i57
#ISCELL
  standard offpage *
  page236_i58
#ISCELL
  logical_power gnd *
  page236_i59
#CELL
  pure_quanta q_cap *
  page236_i60
#ISCELL
  logical_power gnd *
  page236_i61
#CELL
  pure_quanta q_res *
  page236_i62
#CELL
  pure_quanta q_cap *
  page236_i63
#ISCELL
  logical_power gnd *
  page236_i64
#CELL
  pure_quanta q_res *
  page236_i65
#ISCELL
  logical_power gnd *
  page236_i66
#ISCELL
  logical_power gnd *
  page236_i67
#CELL
  pure_quanta q_cap *
  page236_i68
#ISCELL
  logical_power gnd *
  page236_i69
#CELL
  pure_quanta rs31312r *
  page236_i70
#ISCELL
  logical_power universal_power *
  page236_i71
#CELL
  pure_quanta q_res *
  page236_i72
#ISCELL
  logical_power gnd *
  page236_i73
#CELL
  pure_quanta q_cap *
  page236_i74
#CELL
  pure_quanta q_res *
  page236_i75
#CELL
  pure_quanta q_res *
  page236_i76
#CELL
  pure_quanta q_res *
  page236_i77
#ISCELL
  standard offpage *
  page236_i78
#ISCELL
  standard offpage *
  page236_i79
#ISCELL
  logical_power vccaux15 *
  page236_i80
#CELL
  pure_quanta q_res *
  page236_i81
#CELL
  pure_quanta q_res *
  page236_i82
#CELL
  pure_quanta q_res *
  page236_i83
#ISCELL
  logical_power gnd *
  page236_i84
#CELL
  pure_quanta q_res *
  page236_i85
#CELL
  pure_quanta q_res *
  page236_i86
#ISCELL
  logical_power vccaux15 *
  page236_i87
#CELL
  pure_quanta q_cap *
  page236_i88
#CELL
  pure_quanta q_res *
  page236_i89
#ISCELL
  logical_power universal_power *
  page236_i90
#CELL
  pure_quanta q_cap *
  page236_i91
#ISCELL
  logical_power gnd *
  page236_i92
#ISCELL
  standard offpage *
  page236_i93
#ISCELL
  logical_power universal_power *
  page236_i94
#ISCELL
  standard offpage *
  page236_i95
#ISCELL
  standard offpage *
  page236_i96
#ISCELL
  mstr_misc dns *
  *
#ISCELL
  pure_quanta quanta_title_block_c *
  *
#ISCELL
  standard offpage *
  page154_i120
#ISCELL
  standard offpage *
  page154_i121
#ISCELL
  logical_power universal_gnd *
  page154_i126
#CELL
  pure_quanta q_res *
  page154_i130
#CELL
  pure_quanta q_res *
  page154_i131
#CELL
  pure_quanta q_res *
  page154_i132
#CELL
  pure_quanta q_res *
  page154_i133
#CELL
  pure_quanta q_res *
  page154_i134
#ISCELL
  standard offpage *
  page154_i135
#ISCELL
  standard offpage *
  page154_i136
#CELL
  pure_quanta q_res *
  page154_i137
#ISCELL
  logical_power universal_gnd *
  page154_i138
#ISCELL
  logical_power universal_gnd *
  page154_i139
#CELL
  pure_quanta q_res *
  page154_i140
#ISCELL
  logical_power universal_power *
  page154_i141
#CELL
  pure_quanta q_res *
  page154_i142
#CELL
  pure_quanta q_res *
  page154_i143
#ISCELL
  logical_power universal_gnd *
  page154_i144
#ISCELL
  logical_power universal_power *
  page154_i145
#ISCELL
  standard offpage *
  page154_i146
#CELL
  pure_quanta q_cap *
  page154_i148
#ISCELL
  logical_power universal_gnd *
  page154_i149
#ISCELL
  logical_power universal_gnd *
  page154_i151
#ISCELL
  standard offpage *
  page154_i156
#ISCELL
  standard offpage *
  page154_i163
#ISCELL
  standard offpage *
  page154_i166
#ISCELL
  standard offpage *
  page154_i167
#ISCELL
  logical_power universal_power *
  page154_i168
#CELL
  pure_quanta q_cap *
  page154_i169
#ISCELL
  logical_power universal_gnd *
  page154_i170
#ISCELL
  logical_power universal_power *
  page154_i171
#CELL
  pure_quanta q_res *
  page154_i172
#ISCELL
  standard offpage *
  page154_i173
#ISCELL
  logical_power universal_gnd *
  page154_i174
#ISCELL
  logical_power universal_gnd *
  page154_i176
#CELL
  pure_quanta mosfet_n *
  page154_i177
#ISCELL
  standard offpage *
  page154_i178
#ISCELL
  standard offpage *
  page154_i179
#CELL
  pure_quanta 74lvc1g08w57 *
  page154_i189
#CELL
  pure_quanta 74lvc1g08w57 *
  page154_i190
#CELL
  pure_quanta q_cap *
  page154_i192
#ISCELL
  logical_power universal_gnd *
  page154_i193
#ISCELL
  logical_power universal_power *
  page154_i194
#ISCELL
  standard offpage *
  page154_i201
#ISCELL
  standard offpage *
  page154_i202
#ISCELL
  standard offpage *
  page154_i203
#ISCELL
  standard offpage *
  page154_i205
#CELL
  pure_quanta pca9555apw *
  page154_i206
#ISCELL
  standard offpage *
  page154_i207
#ISCELL
  standard offpage *
  page154_i208
#CELL
  pure_quanta 74lvc1g08w57 *
  page154_i221
#ISCELL
  logical_power universal_power *
  page154_i222
#CELL
  pure_quanta q_cap *
  page154_i223
#ISCELL
  logical_power universal_gnd *
  page154_i224
#ISCELL
  logical_power universal_gnd *
  page154_i225
#ISCELL
  logical_power universal_gnd *
  page154_i226
#ISCELL
  logical_power universal_power *
  page154_i227
#CELL
  pure_quanta apx80929sag7 *
  page154_i228
#CELL
  pure_quanta q_cap *
  page154_i229
#ISCELL
  logical_power universal_gnd *
  page154_i230
#CELL
  pure_quanta q_res *
  page154_i232
#ISCELL
  standard offpage *
  page154_i233
#CELL
  pure_quanta q_res *
  page154_i235
#ISCELL
  logical_power universal_power *
  page154_i236
#CELL
  pure_quanta q_res *
  page154_i237
#CELL
  pure_quanta q_res *
  page154_i238
#ISCELL
  standard offpage *
  page154_i239
#ISCELL
  logical_power universal_power *
  page154_i240
#CELL
  pure_quanta q_cap *
  page154_i241
#ISCELL
  logical_power universal_gnd *
  page154_i242
#CELL
  pure_quanta 74lvc1g08w57 *
  page154_i243
#ISCELL
  logical_power universal_gnd *
  page154_i244
#CELL
  pure_quanta q_res *
  page154_i245
#ISCELL
  standard offpage *
  page154_i246
#CELL
  pure_quanta q_res *
  page154_i247
#ISCELL
  standard offpage *
  page154_i248
#CELL
  pure_quanta q_res *
  page154_i249
#ISCELL
  standard offpage *
  page154_i250
#CELL
  pure_quanta q_res *
  page154_i253
#CELL
  pure_quanta q_res *
  page154_i254
#ISCELL
  logical_power universal_power *
  page154_i255
#CELL
  pure_quanta q_res *
  page154_i256
#CELL
  pure_quanta q_res *
  page154_i257
#ISCELL
  logical_power universal_power *
  page154_i258
#ISCELL
  logical_power cad_note *
  *
#ISCELL
  mstr_misc dns *
  *
#ISCELL
  pure_quanta quanta_title_block_c *
  *
#ISCELL
  standard offpage *
  page146_i10
#ISCELL
  standard offpage *
  page146_i11
#ISCELL
  standard offpage *
  page146_i12
#ISCELL
  logical_power universal_gnd *
  page146_i124
#ISCELL
  standard offpage *
  page146_i125
#ISCELL
  standard offpage *
  page146_i126
#ISCELL
  standard offpage *
  page146_i127
#ISCELL
  standard offpage *
  page146_i128
#ISCELL
  standard offpage *
  page146_i13
#ISCELL
  standard offpage *
  page146_i134
#ISCELL
  standard offpage *
  page146_i135
#ISCELL
  standard offpage *
  page146_i136
#ISCELL
  standard offpage *
  page146_i137
#ISCELL
  standard offpage *
  page146_i138
#ISCELL
  standard offpage *
  page146_i139
#ISCELL
  standard offpage *
  page146_i14
#ISCELL
  standard offpage *
  page146_i140
#ISCELL
  standard offpage *
  page146_i141
#ISCELL
  standard offpage *
  page146_i142
#ISCELL
  standard offpage *
  page146_i143
#ISCELL
  logical_power universal_gnd *
  page146_i144
#CELL
  pure_quanta q_res *
  page146_i147
#CELL
  pure_quanta q_res *
  page146_i148
#ISCELL
  standard offpage *
  page146_i149
#ISCELL
  standard offpage *
  page146_i15
#ISCELL
  standard offpage *
  page146_i150
#ISCELL
  logical_power universal_gnd *
  page146_i151
#CELL
  pure_quanta q_res *
  page146_i152
#ISCELL
  standard offpage *
  page146_i153
#ISCELL
  standard offpage *
  page146_i156
#ISCELL
  standard offpage *
  page146_i158
#ISCELL
  standard offpage *
  page146_i159
#ISCELL
  logical_power universal_gnd *
  page146_i16
#ISCELL
  logical_power universal_gnd *
  page146_i163
#ISCELL
  logical_power universal_power *
  page146_i164
#CELL
  pure_quanta q_res *
  page146_i165
#CELL
  pure_quanta q_cap *
  page146_i166
#CELL
  pure_quanta q_cap *
  page146_i167
#CELL
  pure_quanta q_cap *
  page146_i168
#CELL
  pure_quanta q_cap *
  page146_i169
#ISCELL
  logical_power universal_power *
  page146_i170
#CELL
  pure_quanta q_cap *
  page146_i171
#ISCELL
  logical_power universal_gnd *
  page146_i172
#CELL
  pure_quanta q_cap *
  page146_i173
#CELL
  pure_quanta q_cap *
  page146_i174
#CELL
  pure_quanta q_cap *
  page146_i175
#ISCELL
  logical_power universal_gnd *
  page146_i176
#CELL
  pure_quanta q_cap *
  page146_i177
#ISCELL
  logical_power universal_power *
  page146_i178
#CELL
  pure_quanta q_cap *
  page146_i179
#CELL
  pure_quanta q_cap *
  page146_i180
#ISCELL
  standard offpage *
  page146_i183
#ISCELL
  standard offpage *
  page146_i184
#ISCELL
  standard offpage *
  page146_i186
#ISCELL
  standard tap *
  page146_i188
#ISCELL
  standard tap *
  page146_i189
#ISCELL
  logical_power universal_gnd *
  page146_i19
#ISCELL
  standard tap *
  page146_i191
#ISCELL
  standard tap *
  page146_i194
#ISCELL
  standard tap *
  page146_i196
#ISCELL
  standard tap *
  page146_i198
#ISCELL
  standard tap *
  page146_i199
#CELL
  pure_quanta q_res *
  page146_i20
#ISCELL
  standard tap *
  page146_i201
#ISCELL
  standard tap *
  page146_i203
#ISCELL
  standard tap *
  page146_i208
#ISCELL
  standard offpage *
  page146_i21
#ISCELL
  standard tap *
  page146_i210
#ISCELL
  standard tap *
  page146_i212
#ISCELL
  standard tap *
  page146_i213
#ISCELL
  standard tap *
  page146_i214
#ISCELL
  standard tap *
  page146_i216
#ISCELL
  standard tap *
  page146_i218
#ISCELL
  standard offpage *
  page146_i22
#ISCELL
  standard offpage *
  page146_i220
#ISCELL
  standard offpage *
  page146_i221
#ISCELL
  standard offpage *
  page146_i222
#ISCELL
  standard offpage *
  page146_i223
#ISCELL
  standard tap *
  page146_i224
#ISCELL
  standard tap *
  page146_i225
#ISCELL
  standard tap *
  page146_i226
#ISCELL
  standard tap *
  page146_i227
#ISCELL
  standard tap *
  page146_i228
#ISCELL
  standard tap *
  page146_i229
#CELL
  pure_quanta q_res *
  page146_i23
#ISCELL
  standard tap *
  page146_i230
#ISCELL
  standard tap *
  page146_i231
#ISCELL
  standard tap *
  page146_i232
#ISCELL
  standard tap *
  page146_i233
#ISCELL
  standard tap *
  page146_i234
#ISCELL
  standard tap *
  page146_i235
#ISCELL
  standard tap *
  page146_i236
#ISCELL
  standard tap *
  page146_i237
#ISCELL
  standard tap *
  page146_i238
#ISCELL
  standard tap *
  page146_i239
#ISCELL
  logical_power universal_power *
  page146_i24
#ISCELL
  standard tap *
  page146_i240
#ISCELL
  standard tap *
  page146_i241
#ISCELL
  standard tap *
  page146_i242
#ISCELL
  standard tap *
  page146_i243
#ISCELL
  standard tap *
  page146_i244
#ISCELL
  standard tap *
  page146_i245
#ISCELL
  standard tap *
  page146_i246
#ISCELL
  standard tap *
  page146_i247
#ISCELL
  standard tap *
  page146_i248
#ISCELL
  standard tap *
  page146_i249
#CELL
  pure_quanta q_res *
  page146_i25
#ISCELL
  standard tap *
  page146_i250
#ISCELL
  standard tap *
  page146_i251
#ISCELL
  standard tap *
  page146_i252
#ISCELL
  standard tap *
  page146_i253
#ISCELL
  standard tap *
  page146_i254
#ISCELL
  standard tap *
  page146_i255
#ISCELL
  logical_power universal_power *
  page146_i257
#CELL
  pure_quanta q_res *
  page146_i26
#ISCELL
  standard offpage *
  page146_i27
#ISCELL
  standard offpage *
  page146_i28
#ISCELL
  standard offpage *
  page146_i29
#ISCELL
  standard offpage *
  page146_i3
#ISCELL
  standard offpage *
  page146_i30
#CELL
  pure_quanta sconn168_me1016810202011 *
  page146_i303
#ISCELL
  standard tap *
  page146_i306
#ISCELL
  standard tap *
  page146_i307
#ISCELL
  standard tap *
  page146_i309
#CELL
  pure_quanta q_res *
  page146_i31
#ISCELL
  standard tap *
  page146_i310
#ISCELL
  standard tap *
  page146_i312
#ISCELL
  standard tap *
  page146_i313
#ISCELL
  standard tap *
  page146_i315
#ISCELL
  standard tap *
  page146_i316
#ISCELL
  standard tap *
  page146_i318
#ISCELL
  standard tap *
  page146_i319
#CELL
  pure_quanta q_res *
  page146_i32
#ISCELL
  standard tap *
  page146_i321
#ISCELL
  standard tap *
  page146_i322
#ISCELL
  standard tap *
  page146_i324
#ISCELL
  standard tap *
  page146_i325
#ISCELL
  standard tap *
  page146_i327
#ISCELL
  standard tap *
  page146_i328
#CELL
  pure_quanta q_res *
  page146_i33
#CELL
  pure_quanta q_res *
  page146_i333
#CELL
  pure_quanta q_res *
  page146_i334
#ISCELL
  standard offpage *
  page146_i335
#CELL
  pure_quanta q_res *
  page146_i336
#ISCELL
  standard offpage *
  page146_i337
#CELL
  pure_quanta q_res *
  page146_i338
#CELL
  pure_quanta q_res *
  page146_i339
#ISCELL
  standard offpage *
  page146_i34
#ISCELL
  standard offpage *
  page146_i35
#CELL
  pure_quanta q_res *
  page146_i36
#CELL
  pure_quanta q_res *
  page146_i37
#CELL
  pure_quanta q_res *
  page146_i38
#ISCELL
  standard offpage *
  page146_i39
#ISCELL
  standard offpage *
  page146_i40
#ISCELL
  standard offpage *
  page146_i41
#ISCELL
  logical_power universal_gnd *
  page146_i42
#CELL
  pure_quanta q_res *
  page146_i43
#ISCELL
  standard offpage *
  page146_i44
#ISCELL
  standard offpage *
  page146_i45
#ISCELL
  standard offpage *
  page146_i46
#ISCELL
  standard offpage *
  page146_i47
#ISCELL
  standard offpage *
  page146_i48
#ISCELL
  standard offpage *
  page146_i49
#CELL
  pure_quanta q_res *
  page146_i5
#ISCELL
  logical_power universal_power *
  page146_i51
#ISCELL
  standard offpage *
  page146_i6
#ISCELL
  standard offpage *
  page146_i7
#ISCELL
  standard offpage *
  page146_i8
#ISCELL
  standard offpage *
  page146_i9
#ISCELL
  mstr_misc dns *
  *
#ISCELL
  pure_quanta quanta_title_block_c *
  *
#CELL
  pure_quanta q_res *
  page307_i12
#ISCELL
  logical_power universal_gnd *
  page307_i14
#CELL
  pure_quanta q_res *
  page307_i15
#CELL
  pure_quanta q_cap *
  page307_i17
#ISCELL
  logical_power universal_gnd *
  page307_i18
#ISCELL
  logical_power universal_power *
  page307_i19
#ISCELL
  standard offpage *
  page307_i20
#ISCELL
  standard offpage *
  page307_i21
#ISCELL
  standard offpage *
  page307_i22
#ISCELL
  standard offpage *
  page307_i23
#ISCELL
  logical_power universal_gnd *
  page307_i24
#ISCELL
  logical_power universal_gnd *
  page307_i25
#ISCELL
  logical_power universal_power *
  page307_i26
#ISCELL
  standard offpage *
  page307_i27
#ISCELL
  standard offpage *
  page307_i28
#ISCELL
  standard offpage *
  page307_i29
#ISCELL
  standard offpage *
  page307_i3
#ISCELL
  standard offpage *
  page307_i30
#ISCELL
  logical_power universal_gnd *
  page307_i31
#CELL
  pure_quanta 74cbtlv3126pw *
  page307_i32
#CELL
  pure_quanta q_cap *
  page307_i33
#ISCELL
  logical_power universal_gnd *
  page307_i34
#ISCELL
  logical_power universal_power *
  page307_i35
#CELL
  pure_quanta q_res *
  page307_i37
#CELL
  pure_quanta q_res *
  page307_i38
#ISCELL
  logical_power universal_gnd *
  page307_i39
#CELL
  pure_quanta q_res *
  page307_i40
#ISCELL
  standard offpage *
  page307_i44
#ISCELL
  standard offpage *
  page307_i45
#ISCELL
  standard offpage *
  page307_i46
#CELL
  pure_quanta q_res *
  page307_i56
#CELL
  pure_quanta q_res *
  page307_i60
#CELL
  pure_quanta q_res *
  page307_i61
#CELL
  pure_quanta q_res *
  page307_i62
#CELL
  pure_quanta q_res *
  page307_i63
#CELL
  pure_quanta q_res *
  page307_i64
#CELL
  pure_quanta q_res *
  page307_i65
#ISCELL
  standard offpage *
  page307_i66
#ISCELL
  standard offpage *
  page307_i67
#ISCELL
  standard offpage *
  page307_i68
#ISCELL
  standard offpage *
  page307_i69
#ISCELL
  standard offpage *
  page307_i73
#ISCELL
  standard offpage *
  page307_i74
#ISCELL
  standard offpage *
  page307_i75
#ISCELL
  standard offpage *
  page307_i76
#CELL
  pure_quanta q_cap *
  page307_i77
#CELL
  pure_quanta 74cbtlv3126pw *
  page307_i78
#CELL
  pure_quanta q_res *
  page307_i79
#CELL
  pure_quanta 74lvc1g126se7 *
  page307_i80
#CELL
  pure_quanta q_res *
  page307_i81
#ISCELL
  standard offpage *
  page307_i82
#ISCELL
  logical_power universal_gnd *
  page307_i83
#ISCELL
  standard offpage *
  page307_i84
#CELL
  pure_quanta q_res *
  page307_i85
#ISCELL
  standard offpage *
  page307_i9
#ISCELL
  logical_power cad_note *
  *
#ISCELL
  mstr_misc dns *
  *
#ISCELL
  pure_quanta quanta_title_block_c *
  *
#ISCELL
  standard offpage *
  page156_i10
#ISCELL
  logical_power universal_gnd *
  page156_i11
#CELL
  pure_quanta q_cap *
  page156_i12
#ISCELL
  logical_power universal_gnd *
  page156_i19
#CELL
  pure_quanta q_res *
  page156_i24
#ISCELL
  logical_power universal_power *
  page156_i25
#ISCELL
  logical_power universal_gnd *
  page156_i26
#CELL
  pure_quanta q_cap *
  page156_i27
#CELL
  pure_quanta q_res *
  page156_i28
#ISCELL
  logical_power universal_power *
  page156_i29
#ISCELL
  logical_power universal_gnd *
  page156_i30
#CELL
  pure_quanta 74lvc1g07gv *
  page156_i31
#ISCELL
  logical_power universal_gnd *
  page156_i32
#CELL
  pure_quanta q_cap *
  page156_i33
#ISCELL
  logical_power universal_gnd *
  page156_i34
#CELL
  pure_quanta 74lvc1g17gw *
  page156_i35
#ISCELL
  logical_power universal_power *
  page156_i36
#ISCELL
  logical_power universal_power *
  page156_i37
#CELL
  pure_quanta q_res *
  page156_i38
#CELL
  pure_quanta q_res *
  page156_i39
#CELL
  pure_quanta q_res *
  page156_i40
#CELL
  pure_quanta q_res *
  page156_i41
#CELL
  pure_quanta q_res *
  page156_i42
#ISCELL
  logical_power universal_power *
  page156_i43
#CELL
  pure_quanta q_res *
  page156_i44
#ISCELL
  logical_power universal_power *
  page156_i45
#ISCELL
  logical_power universal_gnd *
  page156_i46
#CELL
  pure_quanta q_cap *
  page156_i47
#ISCELL
  standard offpage *
  page156_i48
#ISCELL
  standard offpage *
  page156_i49
#ISCELL
  standard offpage *
  page156_i5
#ISCELL
  standard offpage *
  page156_i50
#ISCELL
  standard offpage *
  page156_i51
#ISCELL
  standard offpage *
  page156_i52
#CELL
  pure_quanta q_res *
  page156_i55
#ISCELL
  standard offpage *
  page156_i58
#CELL
  pure_quanta q_res *
  page156_i59
#CELL
  pure_quanta q_res *
  page156_i6
#ISCELL
  logical_power universal_power *
  page156_i60
#CELL
  pure_quanta 74lvc1g07gv *
  page156_i61
#ISCELL
  logical_power universal_gnd *
  page156_i64
#CELL
  pure_quanta q_cap *
  page156_i65
#ISCELL
  logical_power universal_power *
  page156_i69
#CELL
  pure_quanta q_res *
  page156_i7
#CELL
  pure_quanta q_res *
  page156_i70
#ISCELL
  logical_power universal_gnd *
  page156_i71
#CELL
  pure_quanta q_res *
  page156_i72
#ISCELL
  standard offpage *
  page156_i73
#CELL
  pure_quanta 74lvc1g126se7 *
  page156_i74
#CELL
  pure_quanta q_res *
  page156_i75
#ISCELL
  standard offpage *
  page156_i76
#ISCELL
  standard offpage *
  page156_i77
#ISCELL
  logical_power universal_gnd *
  page156_i78
#CELL
  pure_quanta 74lvc1g126se7 *
  page156_i79
#ISCELL
  logical_power universal_power *
  page156_i8
#ISCELL
  logical_power universal_gnd *
  page156_i80
#CELL
  pure_quanta q_cap *
  page156_i81
#ISCELL
  logical_power universal_power *
  page156_i82
#ISCELL
  standard offpage *
  page156_i83
#ISCELL
  logical_power universal_gnd *
  page156_i84
#ISCELL
  logical_power universal_gnd *
  page156_i86
#ISCELL
  standard offpage *
  page156_i87
#ISCELL
  standard offpage *
  page156_i9
#CELL
  pure_quanta q_res *
  page156_i90
#ISCELL
  standard offpage *
  page156_i91
#CELL
  pure_quanta 74lvc1g66gv *
  page156_i92
#ISCELL
  logical_power cad_note *
  *
#ISCELL
  mstr_misc dns *
  *
#ISCELL
  pure_quanta quanta_title_block_c *
  *
#ISCELL
  standard offpage *
  page131_i1
#ISCELL
  logical_power gnd *
  page131_i10
#CELL
  pure_quanta q_cap *
  page131_i100
#ISCELL
  logical_power gnd *
  page131_i101
#CELL
  pure_quanta q_cap *
  page131_i102
#ISCELL
  logical_power universal_power *
  page131_i103
#ISCELL
  logical_power gnd *
  page131_i104
#CELL
  pure_quanta q_cap *
  page131_i105
#CELL
  pure_quanta q_res *
  page131_i106
#CELL
  pure_quanta schottky_ac *
  page131_i107
#CELL
  pure_quanta q_res *
  page131_i108
#CELL
  pure_quanta q_cap *
  page131_i109
#CELL
  pure_quanta q_res *
  page131_i11
#CELL
  pure_quanta q_res *
  page131_i110
#ISCELL
  logical_power vccaux15 *
  page131_i111
#ISCELL
  logical_power gnd *
  page131_i112
#CELL
  pure_quanta q_cap *
  page131_i113
#ISCELL
  logical_power universal_power *
  page131_i114
#ISCELL
  standard offpage *
  page131_i115
#ISCELL
  logical_power universal_power *
  page131_i12
#CELL
  pure_quanta q_res *
  page131_i13
#CELL
  pure_quanta q_res *
  page131_i14
#ISCELL
  logical_power universal_power *
  page131_i15
#CELL
  pure_quanta mosfet_nch_dual *
  page131_i16
#ISCELL
  logical_power gnd *
  page131_i17
#ISCELL
  logical_power universal_gnd *
  page131_i18
#CELL
  pure_quanta 74lvc2g07dw7 *
  page131_i19
#ISCELL
  standard offpage *
  page131_i2
#ISCELL
  logical_power universal_gnd *
  page131_i20
#CELL
  pure_quanta q_cap *
  page131_i21
#ISCELL
  logical_power universal_power *
  page131_i22
#ISCELL
  logical_power universal_gnd *
  page131_i23
#ISCELL
  logical_power universal_gnd *
  page131_i24
#CELL
  pure_quanta 74lvc2g07dw7 *
  page131_i25
#CELL
  pure_quanta q_cap *
  page131_i26
#ISCELL
  logical_power universal_power *
  page131_i27
#ISCELL
  logical_power gnd *
  page131_i28
#CELL
  pure_quanta q_res *
  page131_i29
#CELL
  pure_quanta q_res *
  page131_i3
#CELL
  pure_quanta q_res *
  page131_i30
#ISCELL
  logical_power gnd *
  page131_i31
#CELL
  pure_quanta q_res *
  page131_i32
#CELL
  pure_quanta q_res *
  page131_i33
#ISCELL
  standard offpage *
  page131_i34
#CELL
  pure_quanta q_res *
  page131_i35
#ISCELL
  logical_power gnd *
  page131_i36
#CELL
  pure_quanta q_res *
  page131_i37
#CELL
  pure_quanta mosfet_nch_dual *
  page131_i38
#ISCELL
  logical_power gnd *
  page131_i39
#ISCELL
  logical_power universal_power *
  page131_i4
#CELL
  pure_quanta q_res *
  page131_i40
#ISCELL
  logical_power universal_power *
  page131_i41
#CELL
  pure_quanta mosfet_nch_dual *
  page131_i42
#ISCELL
  logical_power gnd *
  page131_i43
#CELL
  pure_quanta diode_tvs *
  page131_i44
#ISCELL
  logical_power universal_power *
  page131_i45
#CELL
  pure_quanta q_cap *
  page131_i46
#CELL
  pure_quanta q_res *
  page131_i47
#CELL
  pure_quanta q_res *
  page131_i48
#ISCELL
  logical_power gnd *
  page131_i49
#CELL
  pure_quanta q_res *
  page131_i5
#CELL
  pure_quanta q_res *
  page131_i50
#ISCELL
  logical_power gnd *
  page131_i51
#CELL
  pure_quanta q_cap *
  page131_i52
#CELL
  pure_quanta q_res *
  page131_i53
#ISCELL
  logical_power universal_power *
  page131_i54
#CELL
  pure_quanta q_res *
  page131_i55
#CELL
  pure_quanta q_res *
  page131_i56
#CELL
  pure_quanta q_res *
  page131_i57
#ISCELL
  logical_power gnd *
  page131_i58
#CELL
  pure_quanta q_res *
  page131_i59
#CELL
  pure_quanta q_res *
  page131_i6
#ISCELL
  logical_power gnd *
  page131_i60
#CELL
  pure_quanta q_cap *
  page131_i61
#CELL
  pure_quanta q_cap *
  page131_i62
#CELL
  pure_quanta max15090bewit *
  page131_i63
#CELL
  pure_quanta q_res *
  page131_i64
#ISCELL
  logical_power universal_power *
  page131_i65
#CELL
  pure_quanta q_res *
  page131_i66
#ISCELL
  standard offpage *
  page131_i67
#ISCELL
  standard offpage *
  page131_i68
#ISCELL
  standard offpage *
  page131_i69
#CELL
  pure_quanta mosfet_nch_dual *
  page131_i7
#CELL
  pure_quanta q_res *
  page131_i70
#ISCELL
  logical_power gnd *
  page131_i71
#CELL
  pure_quanta q_res *
  page131_i72
#CELL
  pure_quanta q_cap *
  page131_i73
#CELL
  pure_quanta q_res *
  page131_i74
#CELL
  pure_quanta q_res *
  page131_i75
#CELL
  pure_quanta q_cap *
  page131_i76
#CELL
  pure_quanta q_res *
  page131_i77
#CELL
  pure_quanta q_res *
  page131_i78
#ISCELL
  logical_power gnd *
  page131_i79
#ISCELL
  standard offpage *
  page131_i8
#CELL
  pure_quanta q_res *
  page131_i80
#CELL
  pure_quanta q_res *
  page131_i81
#ISCELL
  standard offpage *
  page131_i82
#ISCELL
  standard offpage *
  page131_i83
#ISCELL
  standard offpage *
  page131_i84
#CELL
  pure_quanta q_res *
  page131_i85
#ISCELL
  logical_power gnd *
  page131_i86
#CELL
  pure_quanta q_cap *
  page131_i87
#ISCELL
  logical_power gnd *
  page131_i88
#CELL
  pure_quanta q_res *
  page131_i89
#ISCELL
  standard offpage *
  page131_i9
#CELL
  pure_quanta max15090bewit *
  page131_i90
#CELL
  pure_quanta q_cap *
  page131_i91
#CELL
  pure_quanta q_res *
  page131_i92
#CELL
  pure_quanta schottky_ac *
  page131_i93
#ISCELL
  logical_power gnd *
  page131_i94
#CELL
  pure_quanta q_res *
  page131_i95
#CELL
  pure_quanta q_cap *
  page131_i96
#CELL
  pure_quanta q_res *
  page131_i97
#CELL
  pure_quanta q_cap *
  page131_i98
#ISCELL
  logical_power vccaux15 *
  page131_i99
#ISCELL
  logical_power cad_note *
  *
#ISCELL
  mstr_misc dns *
  *
#ISCELL
  pure_quanta quanta_title_block_c *
  *
#ISCELL
  standard offpage *
  page237_i33
#ISCELL
  logical_power universal_gnd *
  page237_i34
#CELL
  pure_quanta q_cap *
  page237_i35
#CELL
  pure_quanta q_res *
  page237_i43
#CELL
  pure_quanta q_res *
  page237_i44
#ISCELL
  logical_power universal_gnd *
  page237_i45
#CELL
  pure_quanta q_res *
  page237_i46
#ISCELL
  logical_power universal_gnd *
  page237_i47
#CELL
  pure_quanta q_cap *
  page237_i48
#ISCELL
  logical_power universal_gnd *
  page237_i49
#CELL
  pure_quanta q_cap *
  page237_i50
#CELL
  pure_quanta mp5016gqhlz *
  page237_i51
#ISCELL
  logical_power universal_power *
  page237_i52
#ISCELL
  logical_power universal_gnd *
  page237_i53
#CELL
  pure_quanta q_cap *
  page237_i54
#ISCELL
  logical_power universal_gnd *
  page237_i55
#CELL
  pure_quanta q_cap *
  page237_i56
#ISCELL
  logical_power universal_power *
  page237_i57
#ISCELL
  standard offpage *
  page237_i58
#ISCELL
  logical_power gnd *
  page237_i59
#ISCELL
  logical_power gnd *
  page237_i60
#CELL
  pure_quanta q_res *
  page237_i61
#CELL
  pure_quanta q_cap *
  page237_i62
#ISCELL
  logical_power gnd *
  page237_i63
#ISCELL
  logical_power gnd *
  page237_i64
#CELL
  pure_quanta q_cap *
  page237_i65
#CELL
  pure_quanta q_res *
  page237_i66
#ISCELL
  logical_power gnd *
  page237_i67
#CELL
  pure_quanta q_cap *
  page237_i68
#ISCELL
  logical_power gnd *
  page237_i69
#CELL
  pure_quanta rs31312r *
  page237_i70
#ISCELL
  logical_power gnd *
  page237_i71
#CELL
  pure_quanta q_res *
  page237_i72
#CELL
  pure_quanta q_cap *
  page237_i73
#CELL
  pure_quanta q_res *
  page237_i74
#CELL
  pure_quanta q_res *
  page237_i75
#ISCELL
  logical_power vccaux15 *
  page237_i76
#CELL
  pure_quanta q_res *
  page237_i77
#ISCELL
  standard offpage *
  page237_i78
#ISCELL
  logical_power vccaux15 *
  page237_i79
#CELL
  pure_quanta q_res *
  page237_i80
#CELL
  pure_quanta q_res *
  page237_i81
#ISCELL
  logical_power gnd *
  page237_i82
#CELL
  pure_quanta q_res *
  page237_i83
#CELL
  pure_quanta q_res *
  page237_i84
#CELL
  pure_quanta q_res *
  page237_i85
#ISCELL
  logical_power universal_power *
  page237_i86
#CELL
  pure_quanta q_res *
  page237_i87
#ISCELL
  standard offpage *
  page237_i88
#ISCELL
  logical_power universal_power *
  page237_i89
#ISCELL
  logical_power gnd *
  page237_i90
#CELL
  pure_quanta q_cap *
  page237_i91
#ISCELL
  logical_power universal_power *
  page237_i92
#ISCELL
  standard offpage *
  page237_i93
#ISCELL
  standard offpage *
  page237_i94
#CELL
  pure_quanta q_cap *
  page237_i95
#ISCELL
  standard offpage *
  page237_i96
#ISCELL
  mstr_misc dns *
  *
#ISCELL
  pure_quanta quanta_title_block_c *
  *
#ISCELL
  standard offpage *
  page132_i1
#CELL
  pure_quanta q_res *
  page132_i100
#ISCELL
  standard offpage *
  page132_i101
#ISCELL
  standard offpage *
  page132_i102
#CELL
  pure_quanta q_res *
  page132_i103
#CELL
  pure_quanta q_res *
  page132_i104
#CELL
  pure_quanta q_res *
  page132_i105
#ISCELL
  logical_power universal_power *
  page132_i106
#CELL
  pure_quanta q_res *
  page132_i107
#CELL
  pure_quanta 74lvc1g08w57 *
  page132_i108
#ISCELL
  logical_power universal_gnd *
  page132_i109
#CELL
  pure_quanta q_cap *
  page132_i110
#CELL
  pure_quanta q_res *
  page132_i111
#CELL
  pure_quanta q_res *
  page132_i112
#ISCELL
  logical_power universal_power *
  page132_i113
#ISCELL
  standard offpage *
  page132_i115
#ISCELL
  logical_power universal_gnd *
  page132_i116
#ISCELL
  standard offpage *
  page132_i117
#ISCELL
  logical_power universal_power *
  page132_i118
#CELL
  pure_quanta q_res *
  page132_i119
#ISCELL
  logical_power universal_gnd *
  page132_i14
#CELL
  pure_quanta q_cap *
  page132_i15
#ISCELL
  logical_power universal_power *
  page132_i16
#ISCELL
  standard offpage *
  page132_i17
#ISCELL
  standard offpage *
  page132_i18
#ISCELL
  standard offpage *
  page132_i2
#CELL
  pure_quanta q_res *
  page132_i23
#ISCELL
  logical_power universal_gnd *
  page132_i24
#CELL
  pure_quanta q_res *
  page132_i25
#ISCELL
  logical_power universal_gnd *
  page132_i26
#CELL
  pure_quanta q_res *
  page132_i27
#ISCELL
  logical_power universal_gnd *
  page132_i28
#CELL
  pure_quanta q_res *
  page132_i29
#CELL
  pure_quanta mosfet_n *
  page132_i3
#ISCELL
  logical_power universal_power *
  page132_i30
#CELL
  pure_quanta q_res *
  page132_i31
#CELL
  pure_quanta q_res *
  page132_i32
#CELL
  pure_quanta q_res *
  page132_i33
#CELL
  pure_quanta q_res *
  page132_i34
#ISCELL
  standard offpage *
  page132_i37
#ISCELL
  logical_power universal_gnd *
  page132_i38
#CELL
  pure_quanta q_cap *
  page132_i39
#ISCELL
  logical_power universal_gnd *
  page132_i4
#ISCELL
  logical_power universal_power *
  page132_i40
#ISCELL
  logical_power universal_gnd *
  page132_i41
#ISCELL
  standard offpage *
  page132_i42
#ISCELL
  standard offpage *
  page132_i43
#ISCELL
  standard offpage *
  page132_i44
#ISCELL
  standard offpage *
  page132_i45
#ISCELL
  standard offpage *
  page132_i46
#ISCELL
  standard offpage *
  page132_i47
#ISCELL
  logical_power universal_gnd *
  page132_i5
#ISCELL
  standard offpage *
  page132_i50
#ISCELL
  logical_power universal_gnd *
  page132_i55
#CELL
  pure_quanta 74lvc1g08w57 *
  page132_i56
#ISCELL
  logical_power universal_gnd *
  page132_i57
#CELL
  pure_quanta q_cap *
  page132_i58
#ISCELL
  logical_power universal_power *
  page132_i59
#ISCELL
  standard offpage *
  page132_i6
#ISCELL
  standard offpage *
  page132_i60
#ISCELL
  standard offpage *
  page132_i63
#ISCELL
  standard offpage *
  page132_i64
#CELL
  pure_quanta q_res *
  page132_i65
#CELL
  pure_quanta pca9555apw *
  page132_i66
#ISCELL
  standard offpage *
  page132_i67
#ISCELL
  standard offpage *
  page132_i68
#CELL
  pure_quanta q_res *
  page132_i7
#ISCELL
  logical_power universal_power *
  page132_i8
#ISCELL
  logical_power universal_gnd *
  page132_i81
#ISCELL
  logical_power universal_gnd *
  page132_i84
#CELL
  pure_quanta apx80929sag7 *
  page132_i85
#ISCELL
  logical_power universal_power *
  page132_i86
#CELL
  pure_quanta q_cap *
  page132_i87
#ISCELL
  standard offpage *
  page132_i88
#ISCELL
  logical_power universal_power *
  page132_i89
#CELL
  pure_quanta 74lvc1g08w57 *
  page132_i9
#CELL
  pure_quanta q_cap *
  page132_i90
#ISCELL
  logical_power universal_gnd *
  page132_i91
#CELL
  pure_quanta 74lvc1g08w57 *
  page132_i92
#ISCELL
  logical_power universal_gnd *
  page132_i93
#ISCELL
  logical_power universal_power *
  page132_i94
#CELL
  pure_quanta q_res *
  page132_i95
#CELL
  pure_quanta q_res *
  page132_i96
#ISCELL
  standard offpage *
  page132_i98
#CELL
  pure_quanta q_res *
  page132_i99
#ISCELL
  mstr_misc dns *
  *
#ISCELL
  pure_quanta quanta_title_block_c *
  *
#CELL
  pure_quanta 74lvc2g08dp *
  page170_i1
#ISCELL
  standard offpage *
  page170_i10
#CELL
  pure_quanta 74lvc2g08dp *
  page170_i11
#CELL
  pure_quanta 74lvc2g08dp *
  page170_i12
#CELL
  pure_quanta 74lvc2g08dp *
  page170_i13
#CELL
  pure_quanta 74lvc2g08dp *
  page170_i14
#CELL
  pure_quanta nc7sb3157 *
  page170_i15
#CELL
  pure_quanta nc7sb3157 *
  page170_i16
#CELL
  pure_quanta nc7sb3157 *
  page170_i17
#CELL
  pure_quanta nc7sb3157 *
  page170_i18
#ISCELL
  logical_power universal_gnd *
  page170_i19
#CELL
  pure_quanta 74lvc2g08dp *
  page170_i2
#ISCELL
  logical_power universal_power *
  page170_i20
#CELL
  pure_quanta q_cap *
  page170_i21
#CELL
  pure_quanta q_cap *
  page170_i22
#ISCELL
  logical_power universal_power *
  page170_i23
#ISCELL
  logical_power universal_gnd *
  page170_i24
#ISCELL
  logical_power universal_gnd *
  page170_i25
#ISCELL
  logical_power universal_gnd *
  page170_i26
#CELL
  pure_quanta q_cap *
  page170_i27
#ISCELL
  logical_power universal_gnd *
  page170_i28
#ISCELL
  logical_power universal_power *
  page170_i29
#ISCELL
  standard offpage *
  page170_i3
#ISCELL
  logical_power universal_power *
  page170_i30
#CELL
  pure_quanta q_cap *
  page170_i31
#ISCELL
  logical_power universal_gnd *
  page170_i32
#ISCELL
  logical_power universal_power *
  page170_i33
#CELL
  pure_quanta q_cap *
  page170_i34
#ISCELL
  logical_power universal_gnd *
  page170_i35
#ISCELL
  logical_power universal_gnd *
  page170_i36
#CELL
  pure_quanta q_cap *
  page170_i37
#ISCELL
  logical_power universal_power *
  page170_i38
#ISCELL
  logical_power universal_gnd *
  page170_i39
#ISCELL
  standard offpage *
  page170_i4
#ISCELL
  logical_power universal_power *
  page170_i40
#CELL
  pure_quanta q_cap *
  page170_i41
#ISCELL
  logical_power universal_gnd *
  page170_i42
#CELL
  pure_quanta q_res *
  page170_i44
#CELL
  pure_quanta q_res *
  page170_i45
#CELL
  pure_quanta q_res *
  page170_i46
#CELL
  pure_quanta q_res *
  page170_i47
#ISCELL
  standard offpage *
  page170_i48
#ISCELL
  standard offpage *
  page170_i49
#ISCELL
  standard offpage *
  page170_i5
#CELL
  pure_quanta q_res *
  page170_i50
#ISCELL
  standard offpage *
  page170_i51
#CELL
  pure_quanta q_res *
  page170_i52
#ISCELL
  standard offpage *
  page170_i53
#ISCELL
  standard offpage *
  page170_i54
#ISCELL
  standard offpage *
  page170_i56
#ISCELL
  standard offpage *
  page170_i58
#ISCELL
  standard offpage *
  page170_i59
#ISCELL
  standard offpage *
  page170_i6
#ISCELL
  logical_power universal_gnd *
  page170_i60
#ISCELL
  logical_power universal_gnd *
  page170_i61
#ISCELL
  logical_power universal_gnd *
  page170_i62
#ISCELL
  logical_power universal_gnd *
  page170_i63
#ISCELL
  standard offpage *
  page170_i7
#ISCELL
  standard offpage *
  page170_i8
#ISCELL
  standard offpage *
  page170_i9
#ISCELL
  mstr_misc dns *
  *
#ISCELL
  pure_quanta quanta_title_block_c *
  *
#ISCELL
  logical_power universal_gnd *
  page136_i1
#ISCELL
  logical_power universal_power *
  page136_i10
#ISCELL
  logical_power universal_gnd *
  page136_i11
#CELL
  pure_quanta q_res *
  page136_i12
#ISCELL
  logical_power universal_gnd *
  page136_i13
#CELL
  pure_quanta q_res *
  page136_i14
#CELL
  pure_quanta q_res *
  page136_i15
#CELL
  pure_quanta q_res *
  page136_i16
#ISCELL
  logical_power universal_gnd *
  page136_i17
#CELL
  pure_quanta q_res *
  page136_i18
#ISCELL
  logical_power universal_gnd *
  page136_i19
#CELL
  pure_quanta q_res *
  page136_i2
#CELL
  pure_quanta q_res *
  page136_i20
#CELL
  pure_quanta q_res *
  page136_i21
#ISCELL
  logical_power universal_gnd *
  page136_i22
#CELL
  pure_quanta q_res *
  page136_i23
#ISCELL
  logical_power universal_gnd *
  page136_i24
#CELL
  pure_quanta q_res *
  page136_i25
#ISCELL
  logical_power universal_gnd *
  page136_i26
#CELL
  pure_quanta q_res *
  page136_i27
#ISCELL
  standard offpage *
  page136_i28
#ISCELL
  standard offpage *
  page136_i29
#ISCELL
  logical_power universal_gnd *
  page136_i3
#ISCELL
  standard offpage *
  page136_i30
#ISCELL
  standard offpage *
  page136_i31
#CELL
  pure_quanta q_res *
  page136_i32
#ISCELL
  logical_power universal_power *
  page136_i33
#ISCELL
  logical_power universal_power *
  page136_i34
#ISCELL
  standard offpage *
  page136_i35
#ISCELL
  standard offpage *
  page136_i36
#ISCELL
  standard offpage *
  page136_i37
#ISCELL
  standard offpage *
  page136_i38
#ISCELL
  standard offpage *
  page136_i39
#CELL
  pure_quanta q_res *
  page136_i4
#ISCELL
  standard offpage *
  page136_i40
#ISCELL
  standard offpage *
  page136_i41
#ISCELL
  standard offpage *
  page136_i42
#ISCELL
  standard offpage *
  page136_i43
#ISCELL
  standard offpage *
  page136_i44
#ISCELL
  standard offpage *
  page136_i45
#ISCELL
  standard offpage *
  page136_i46
#ISCELL
  logical_power universal_gnd *
  page136_i47
#CELL
  pure_quanta q_cap *
  page136_i48
#CELL
  pure_quanta q_cap *
  page136_i49
#ISCELL
  logical_power universal_gnd *
  page136_i5
#CELL
  pure_quanta pi3eqx12902azlex *
  page136_i50
#CELL
  pure_quanta q_cap *
  page136_i51
#CELL
  pure_quanta q_cap *
  page136_i52
#CELL
  pure_quanta q_cap *
  page136_i53
#ISCELL
  logical_power universal_power *
  page136_i54
#ISCELL
  logical_power universal_gnd *
  page136_i55
#CELL
  pure_quanta q_res *
  page136_i56
#CELL
  pure_quanta q_res *
  page136_i57
#ISCELL
  standard offpage *
  page136_i58
#ISCELL
  standard offpage *
  page136_i59
#CELL
  pure_quanta q_res *
  page136_i6
#ISCELL
  logical_power universal_gnd *
  page136_i60
#CELL
  pure_quanta q_res *
  page136_i61
#ISCELL
  logical_power universal_gnd *
  page136_i62
#CELL
  pure_quanta q_res *
  page136_i63
#CELL
  pure_quanta q_res *
  page136_i64
#ISCELL
  logical_power universal_gnd *
  page136_i65
#CELL
  pure_quanta q_res *
  page136_i66
#ISCELL
  logical_power universal_gnd *
  page136_i67
#CELL
  pure_quanta q_res *
  page136_i68
#CELL
  pure_quanta q_res *
  page136_i69
#ISCELL
  logical_power universal_gnd *
  page136_i7
#ISCELL
  standard offpage *
  page136_i70
#ISCELL
  standard offpage *
  page136_i71
#ISCELL
  logical_power universal_gnd *
  page136_i72
#CELL
  pure_quanta q_res *
  page136_i73
#ISCELL
  logical_power universal_power *
  page136_i74
#ISCELL
  standard offpage *
  page136_i75
#ISCELL
  standard offpage *
  page136_i76
#ISCELL
  standard offpage *
  page136_i77
#ISCELL
  standard offpage *
  page136_i78
#ISCELL
  standard offpage *
  page136_i79
#CELL
  pure_quanta q_res *
  page136_i8
#ISCELL
  standard offpage *
  page136_i80
#ISCELL
  logical_power universal_gnd *
  page136_i81
#CELL
  pure_quanta q_res *
  page136_i82
#ISCELL
  logical_power universal_gnd *
  page136_i83
#CELL
  pure_quanta q_res *
  page136_i84
#CELL
  pure_quanta q_res *
  page136_i85
#ISCELL
  logical_power universal_power *
  page136_i86
#ISCELL
  logical_power universal_gnd *
  page136_i87
#CELL
  pure_quanta q_res *
  page136_i88
#CELL
  pure_quanta q_res *
  page136_i89
#CELL
  pure_quanta q_res *
  page136_i9
#ISCELL
  logical_power universal_power *
  page136_i90
#ISCELL
  standard offpage *
  page136_i91
#ISCELL
  standard offpage *
  page136_i92
#ISCELL
  mstr_misc dns *
  *
#ISCELL
  pure_quanta quanta_title_block_c *
  *
#ISCELL
  logical_power universal_gnd *
  page159_i1
#CELL
  pure_quanta q_res *
  page159_i10
#CELL
  pure_quanta q_cap *
  page159_i100
#ISCELL
  logical_power universal_gnd *
  page159_i101
#CELL
  pure_quanta q_res *
  page159_i102
#ISCELL
  standard offpage *
  page159_i103
#ISCELL
  standard offpage *
  page159_i104
#ISCELL
  standard offpage *
  page159_i105
#ISCELL
  standard offpage *
  page159_i106
#ISCELL
  standard offpage *
  page159_i107
#ISCELL
  standard offpage *
  page159_i108
#ISCELL
  standard offpage *
  page159_i109
#CELL
  pure_quanta q_res *
  page159_i11
#ISCELL
  standard offpage *
  page159_i110
#ISCELL
  standard offpage *
  page159_i111
#ISCELL
  logical_power universal_power *
  page159_i12
#CELL
  pure_quanta q_res *
  page159_i13
#ISCELL
  logical_power universal_gnd *
  page159_i14
#CELL
  pure_quanta q_res *
  page159_i15
#CELL
  pure_quanta q_res *
  page159_i16
#ISCELL
  standard offpage *
  page159_i17
#ISCELL
  standard offpage *
  page159_i18
#ISCELL
  standard offpage *
  page159_i19
#CELL
  pure_quanta q_res *
  page159_i2
#ISCELL
  standard offpage *
  page159_i20
#ISCELL
  standard offpage *
  page159_i21
#ISCELL
  standard offpage *
  page159_i22
#ISCELL
  standard offpage *
  page159_i23
#ISCELL
  standard offpage *
  page159_i24
#ISCELL
  standard offpage *
  page159_i25
#ISCELL
  standard offpage *
  page159_i26
#CELL
  pure_quanta q_cap *
  page159_i27
#CELL
  pure_quanta q_cap *
  page159_i28
#CELL
  pure_quanta q_cap *
  page159_i29
#ISCELL
  logical_power universal_gnd *
  page159_i3
#CELL
  pure_quanta q_cap *
  page159_i30
#CELL
  pure_quanta q_cap *
  page159_i31
#CELL
  pure_quanta q_cap *
  page159_i32
#CELL
  pure_quanta q_cap *
  page159_i33
#CELL
  pure_quanta q_cap *
  page159_i34
#CELL
  pure_quanta q_res *
  page159_i35
#CELL
  pure_quanta q_res *
  page159_i36
#ISCELL
  standard offpage *
  page159_i37
#ISCELL
  standard offpage *
  page159_i38
#ISCELL
  standard offpage *
  page159_i39
#CELL
  pure_quanta q_res *
  page159_i4
#ISCELL
  standard offpage *
  page159_i40
#CELL
  pure_quanta q_res *
  page159_i41
#CELL
  pure_quanta q_res *
  page159_i42
#CELL
  pure_quanta q_res *
  page159_i43
#CELL
  pure_quanta q_res *
  page159_i44
#CELL
  pure_quanta q_res *
  page159_i45
#CELL
  pure_quanta q_res *
  page159_i46
#ISCELL
  standard offpage *
  page159_i47
#ISCELL
  standard offpage *
  page159_i48
#ISCELL
  standard offpage *
  page159_i49
#ISCELL
  standard offpage *
  page159_i5
#ISCELL
  standard offpage *
  page159_i50
#ISCELL
  standard offpage *
  page159_i51
#ISCELL
  logical_power universal_gnd *
  page159_i52
#CELL
  pure_quanta q_res *
  page159_i53
#ISCELL
  standard offpage *
  page159_i54
#ISCELL
  standard offpage *
  page159_i55
#ISCELL
  standard offpage *
  page159_i56
#ISCELL
  standard offpage *
  page159_i57
#ISCELL
  standard offpage *
  page159_i58
#ISCELL
  standard offpage *
  page159_i59
#ISCELL
  standard offpage *
  page159_i6
#ISCELL
  logical_power universal_gnd *
  page159_i60
#CELL
  pure_quanta q_res *
  page159_i61
#CELL
  pure_quanta q_res *
  page159_i62
#ISCELL
  standard offpage *
  page159_i63
#ISCELL
  logical_power universal_gnd *
  page159_i64
#CELL
  pure_quanta q_res *
  page159_i65
#CELL
  pure_quanta q_res *
  page159_i66
#CELL
  pure_quanta q_res *
  page159_i67
#ISCELL
  logical_power universal_gnd *
  page159_i68
#ISCELL
  logical_power universal_power *
  page159_i69
#CELL
  pure_quanta q_res *
  page159_i7
#ISCELL
  logical_power universal_gnd *
  page159_i70
#CELL
  pure_quanta q_res *
  page159_i71
#CELL
  pure_quanta q_res *
  page159_i72
#ISCELL
  logical_power universal_power *
  page159_i73
#CELL
  pure_quanta q_res *
  page159_i74
#ISCELL
  logical_power universal_power *
  page159_i75
#ISCELL
  standard offpage *
  page159_i76
#ISCELL
  standard offpage *
  page159_i77
#ISCELL
  standard offpage *
  page159_i78
#ISCELL
  logical_power universal_gnd *
  page159_i79
#ISCELL
  logical_power universal_power *
  page159_i8
#CELL
  pure_quanta q_res *
  page159_i80
#CELL
  pure_quanta q_res *
  page159_i81
#ISCELL
  standard offpage *
  page159_i82
#ISCELL
  logical_power universal_power *
  page159_i83
#ISCELL
  standard offpage *
  page159_i84
#ISCELL
  standard offpage *
  page159_i85
#ISCELL
  standard offpage *
  page159_i86
#ISCELL
  standard offpage *
  page159_i87
#ISCELL
  standard offpage *
  page159_i88
#ISCELL
  standard offpage *
  page159_i89
#ISCELL
  logical_power universal_gnd *
  page159_i9
#ISCELL
  standard offpage *
  page159_i90
#ISCELL
  standard offpage *
  page159_i91
#ISCELL
  standard offpage *
  page159_i92
#ISCELL
  standard offpage *
  page159_i93
#ISCELL
  logical_power universal_gnd *
  page159_i94
#CELL
  pure_quanta ds125br111rtwr *
  page159_i95
#CELL
  pure_quanta q_cap *
  page159_i96
#ISCELL
  logical_power universal_power *
  page159_i97
#CELL
  pure_quanta q_cap *
  page159_i98
#CELL
  pure_quanta q_cap *
  page159_i99
#ISCELL
  pure_quanta quanta_title_block_c *
  *
#ISCELL
  mstr_misc dns *
  *
#ISCELL
  pure_quanta quanta_title_block_c *
  *
#ISCELL
  logical_power universal_gnd *
  page162_i1
#ISCELL
  logical_power universal_gnd *
  page162_i10
#CELL
  pure_quanta q_res *
  page162_i11
#CELL
  pure_quanta q_res *
  page162_i12
#ISCELL
  logical_power universal_power *
  page162_i13
#ISCELL
  standard offpage *
  page162_i14
#ISCELL
  standard offpage *
  page162_i15
#ISCELL
  logical_power universal_gnd *
  page162_i16
#CELL
  pure_quanta q_res *
  page162_i17
#CELL
  pure_quanta q_res *
  page162_i18
#ISCELL
  standard offpage *
  page162_i19
#CELL
  pure_quanta q_res *
  page162_i2
#ISCELL
  standard offpage *
  page162_i20
#ISCELL
  logical_power universal_gnd *
  page162_i21
#ISCELL
  logical_power universal_gnd *
  page162_i22
#CELL
  pure_quanta q_res *
  page162_i23
#CELL
  pure_quanta q_res *
  page162_i24
#CELL
  pure_quanta q_cap_diffbus *
  page162_i25
#CELL
  pure_quanta q_cap_diffbus *
  page162_i26
#ISCELL
  standard offpage *
  page162_i27
#ISCELL
  standard offpage *
  page162_i28
#ISCELL
  standard offpage *
  page162_i29
#CELL
  pure_quanta q_res *
  page162_i3
#ISCELL
  standard offpage *
  page162_i30
#ISCELL
  standard offpage *
  page162_i31
#ISCELL
  standard offpage *
  page162_i32
#ISCELL
  standard offpage *
  page162_i33
#ISCELL
  standard offpage *
  page162_i34
#CELL
  pure_quanta q_inductor *
  page162_i35
#ISCELL
  logical_power universal_gnd *
  page162_i36
#CELL
  pure_quanta q_cap *
  page162_i37
#ISCELL
  logical_power universal_power *
  page162_i38
#ISCELL
  logical_power universal_gnd *
  page162_i39
#ISCELL
  logical_power universal_power *
  page162_i4
#CELL
  pure_quanta q_res *
  page162_i40
#CELL
  pure_quanta q_res *
  page162_i41
#ISCELL
  logical_power universal_power *
  page162_i42
#CELL
  pure_quanta pi3eqx1002ezrex *
  page162_i43
#CELL
  pure_quanta q_cap *
  page162_i44
#CELL
  pure_quanta q_cap *
  page162_i45
#ISCELL
  logical_power universal_gnd *
  page162_i46
#ISCELL
  logical_power universal_gnd *
  page162_i47
#CELL
  pure_quanta q_res *
  page162_i48
#CELL
  pure_quanta q_res *
  page162_i49
#ISCELL
  logical_power universal_gnd *
  page162_i5
#ISCELL
  standard offpage *
  page162_i50
#ISCELL
  standard offpage *
  page162_i51
#ISCELL
  standard offpage *
  page162_i52
#ISCELL
  standard offpage *
  page162_i53
#CELL
  pure_quanta q_cap *
  page162_i54
#CELL
  pure_quanta q_cap *
  page162_i55
#CELL
  pure_quanta q_cap *
  page162_i56
#CELL
  pure_quanta q_cap *
  page162_i57
#ISCELL
  standard offpage *
  page162_i58
#ISCELL
  standard offpage *
  page162_i59
#CELL
  pure_quanta q_res *
  page162_i6
#ISCELL
  standard offpage *
  page162_i60
#ISCELL
  standard offpage *
  page162_i61
#ISCELL
  logical_power universal_gnd *
  page162_i62
#CELL
  pure_quanta q_res *
  page162_i63
#ISCELL
  standard offpage *
  page162_i64
#CELL
  pure_quanta q_res *
  page162_i65
#ISCELL
  logical_power universal_power *
  page162_i66
#ISCELL
  logical_power universal_gnd *
  page162_i67
#CELL
  pure_quanta q_res *
  page162_i68
#CELL
  pure_quanta q_res *
  page162_i69
#CELL
  pure_quanta q_res *
  page162_i7
#ISCELL
  logical_power universal_power *
  page162_i70
#ISCELL
  standard offpage *
  page162_i71
#ISCELL
  standard offpage *
  page162_i8
#ISCELL
  standard offpage *
  page162_i9
#ISCELL
  mstr_misc dns *
  *
#ISCELL
  pure_quanta quanta_title_block_c *
  *
#ISCELL
  logical_power universal_power *
  page161_i100
#CELL
  pure_quanta q_res *
  page161_i101
#CELL
  pure_quanta q_res *
  page161_i102
#ISCELL
  logical_power universal_gnd *
  page161_i103
#CELL
  pure_quanta q_cap *
  page161_i104
#ISCELL
  logical_power universal_gnd *
  page161_i105
#ISCELL
  logical_power universal_gnd *
  page161_i106
#CELL
  pure_quanta q_res *
  page161_i107
#CELL
  pure_quanta q_res *
  page161_i108
#CELL
  pure_quanta q_res *
  page161_i109
#ISCELL
  standard offpage *
  page161_i110
#ISCELL
  standard offpage *
  page161_i111
#ISCELL
  standard offpage *
  page161_i112
#ISCELL
  standard offpage *
  page161_i113
#CELL
  pure_quanta q_res *
  page161_i114
#CELL
  pure_quanta q_res *
  page161_i115
#CELL
  pure_quanta q_res *
  page161_i116
#ISCELL
  logical_power universal_gnd *
  page161_i117
#ISCELL
  logical_power universal_gnd *
  page161_i118
#CELL
  pure_quanta q_cap *
  page161_i119
#ISCELL
  logical_power universal_gnd *
  page161_i120
#CELL
  pure_quanta q_res *
  page161_i121
#CELL
  pure_quanta q_res *
  page161_i122
#ISCELL
  logical_power universal_power *
  page161_i123
#ISCELL
  logical_power universal_gnd *
  page161_i124
#CELL
  pure_quanta q_res *
  page161_i125
#ISCELL
  logical_power universal_gnd *
  page161_i126
#CELL
  pure_quanta q_res *
  page161_i127
#CELL
  pure_quanta q_res *
  page161_i128
#CELL
  pure_quanta q_res *
  page161_i129
#ISCELL
  logical_power universal_power *
  page161_i130
#ISCELL
  standard offpage *
  page161_i132
#ISCELL
  standard offpage *
  page161_i133
#CELL
  pure_quanta q_res *
  page161_i134
#CELL
  pure_quanta q_res *
  page161_i135
#CELL
  pure_quanta q_res *
  page161_i136
#ISCELL
  logical_power universal_gnd *
  page161_i137
#ISCELL
  logical_power universal_gnd *
  page161_i138
#CELL
  pure_quanta q_cap *
  page161_i139
#ISCELL
  logical_power universal_gnd *
  page161_i140
#CELL
  pure_quanta q_res *
  page161_i141
#CELL
  pure_quanta q_res *
  page161_i142
#ISCELL
  logical_power universal_power *
  page161_i143
#ISCELL
  logical_power universal_gnd *
  page161_i144
#CELL
  pure_quanta q_res *
  page161_i145
#ISCELL
  logical_power universal_gnd *
  page161_i146
#CELL
  pure_quanta q_res *
  page161_i147
#CELL
  pure_quanta q_res *
  page161_i148
#CELL
  pure_quanta q_res *
  page161_i149
#ISCELL
  logical_power universal_power *
  page161_i15
#ISCELL
  logical_power universal_power *
  page161_i150
#ISCELL
  logical_power universal_power *
  page161_i153
#ISCELL
  logical_power universal_power *
  page161_i154
#ISCELL
  logical_power universal_power *
  page161_i156
#ISCELL
  logical_power universal_power *
  page161_i159
#CELL
  pure_quanta q_cap *
  page161_i16
#ISCELL
  standard offpage *
  page161_i160
#ISCELL
  standard offpage *
  page161_i161
#ISCELL
  standard offpage *
  page161_i162
#ISCELL
  standard offpage *
  page161_i163
#CELL
  pure_quanta lm75bd *
  page161_i164
#CELL
  pure_quanta lm75bd *
  page161_i165
#CELL
  pure_quanta lm75bd *
  page161_i166
#CELL
  pure_quanta lm75bd *
  page161_i167
#CELL
  pure_quanta q_res *
  page161_i168
#CELL
  pure_quanta q_res *
  page161_i169
#ISCELL
  logical_power universal_gnd *
  page161_i17
#CELL
  pure_quanta q_res *
  page161_i170
#CELL
  pure_quanta q_res *
  page161_i171
#ISCELL
  logical_power universal_gnd *
  page161_i21
#ISCELL
  standard offpage *
  page161_i75
#ISCELL
  standard offpage *
  page161_i76
#CELL
  pure_quanta q_res *
  page161_i77
#CELL
  pure_quanta q_res *
  page161_i78
#CELL
  pure_quanta q_res *
  page161_i79
#ISCELL
  logical_power universal_gnd *
  page161_i80
#CELL
  pure_quanta q_res *
  page161_i81
#CELL
  pure_quanta q_res *
  page161_i82
#ISCELL
  logical_power universal_power *
  page161_i83
#ISCELL
  logical_power universal_gnd *
  page161_i84
#CELL
  pure_quanta q_res *
  page161_i85
#CELL
  pure_quanta q_res *
  page161_i86
#CELL
  pure_quanta q_res *
  page161_i89
#ISCELL
  logical_power universal_gnd *
  page161_i90
#CELL
  pure_quanta q_res *
  page161_i91
#ISCELL
  logical_power universal_power *
  page161_i93
#CELL
  pure_quanta q_res *
  page161_i94
#CELL
  pure_quanta q_res *
  page161_i95
#CELL
  pure_quanta q_res *
  page161_i96
#ISCELL
  logical_power universal_gnd *
  page161_i97
#CELL
  pure_quanta q_res *
  page161_i98
#ISCELL
  logical_power universal_gnd *
  page161_i99
#ISCELL
  mstr_misc dns *
  *
#ISCELL
  pure_quanta quanta_title_block_c *
  *
#ISCELL
  standard offpage *
  page295_i121
#CELL
  pure_quanta q_res *
  page295_i122
#ISCELL
  logical_power universal_power *
  page295_i123
#ISCELL
  logical_power universal_gnd *
  page295_i124
#CELL
  pure_quanta q_cap *
  page295_i125
#ISCELL
  logical_power universal_gnd *
  page295_i128
#CELL
  pure_quanta ina230airgtr *
  page295_i129
#CELL
  pure_quanta q_res *
  page295_i130
#CELL
  pure_quanta q_res *
  page295_i131
#CELL
  pure_quanta q_res *
  page295_i132
#CELL
  pure_quanta q_cap *
  page295_i133
#CELL
  pure_quanta q_res *
  page295_i134
#CELL
  pure_quanta q_res *
  page295_i135
#CELL
  pure_quanta q_res *
  page295_i136
#ISCELL
  logical_power universal_gnd *
  page295_i137
#ISCELL
  standard offpage *
  page295_i138
#ISCELL
  standard offpage *
  page295_i139
#ISCELL
  logical_power universal_power *
  page295_i140
#CELL
  pure_quanta q_cap *
  page295_i142
#ISCELL
  logical_power universal_gnd *
  page295_i143
#ISCELL
  logical_power universal_power *
  page295_i145
#CELL
  pure_quanta q_res *
  page295_i146
#ISCELL
  logical_power universal_power *
  page295_i147
#ISCELL
  logical_power universal_power *
  page295_i148
#CELL
  pure_quanta q_res *
  page295_i149
#ISCELL
  logical_power universal_power *
  page295_i150
#CELL
  pure_quanta q_res *
  page295_i151
#CELL
  pure_quanta q_res *
  page295_i152
#CELL
  pure_quanta q_res *
  page295_i153
#CELL
  pure_quanta ina230airgtr *
  page295_i30
#CELL
  pure_quanta q_res *
  page295_i31
#ISCELL
  standard offpage *
  page295_i32
#ISCELL
  logical_power universal_power *
  page295_i33
#CELL
  pure_quanta q_cap *
  page295_i34
#CELL
  pure_quanta q_res *
  page295_i35
#ISCELL
  logical_power universal_gnd *
  page295_i36
#ISCELL
  logical_power universal_gnd *
  page295_i37
#CELL
  pure_quanta q_res *
  page295_i38
#CELL
  pure_quanta q_res *
  page295_i39
#CELL
  pure_quanta q_res *
  page295_i40
#CELL
  pure_quanta q_res *
  page295_i41
#CELL
  pure_quanta q_res *
  page295_i43
#ISCELL
  logical_power universal_gnd *
  page295_i45
#ISCELL
  standard offpage *
  page295_i46
#ISCELL
  standard offpage *
  page295_i47
#ISCELL
  logical_power universal_gnd *
  page295_i49
#CELL
  pure_quanta q_cap *
  page295_i50
#CELL
  pure_quanta q_cap *
  page295_i77
#ISCELL
  logical_power universal_power *
  page295_i79
#ISCELL
  logical_power universal_power *
  page295_i80
#ISCELL
  logical_power universal_power *
  page295_i81
#ISCELL
  logical_power universal_power *
  page295_i87
#CELL
  pure_quanta q_res *
  page295_i88
#CELL
  pure_quanta q_res *
  page295_i89
#ISCELL
  mstr_misc dns *
  *
#ISCELL
  pure_quanta quanta_title_block_c *
  *
#CELL
  pure_quanta q_res *
  page163_i100
#CELL
  pure_quanta q_res *
  page163_i101
#CELL
  pure_quanta q_res *
  page163_i102
#CELL
  pure_quanta q_res *
  page163_i103
#CELL
  pure_quanta q_res *
  page163_i104
#ISCELL
  logical_power universal_gnd *
  page163_i105
#ISCELL
  standard offpage *
  page163_i106
#ISCELL
  logical_power universal_gnd *
  page163_i107
#CELL
  pure_quanta q_cap *
  page163_i108
#CELL
  pure_quanta q_res *
  page163_i109
#CELL
  pure_quanta q_res *
  page163_i110
#ISCELL
  standard offpage *
  page163_i111
#ISCELL
  logical_power universal_power *
  page163_i112
#ISCELL
  logical_power universal_power *
  page163_i113
#CELL
  pure_quanta q_cap *
  page163_i114
#ISCELL
  logical_power universal_gnd *
  page163_i115
#ISCELL
  logical_power universal_power *
  page163_i117
#ISCELL
  logical_power universal_power *
  page163_i118
#ISCELL
  logical_power universal_power *
  page163_i119
#ISCELL
  logical_power universal_power *
  page163_i120
#ISCELL
  logical_power universal_power *
  page163_i121
#CELL
  pure_quanta q_res *
  page163_i122
#ISCELL
  logical_power universal_power *
  page163_i123
#CELL
  pure_quanta q_res *
  page163_i124
#ISCELL
  logical_power universal_power *
  page163_i125
#CELL
  pure_quanta q_res *
  page163_i126
#CELL
  pure_quanta q_res *
  page163_i127
#CELL
  pure_quanta q_res *
  page163_i128
#CELL
  pure_quanta q_res *
  page163_i129
#ISCELL
  logical_power universal_power *
  page163_i24
#CELL
  pure_quanta q_cap *
  page163_i26
#ISCELL
  logical_power universal_gnd *
  page163_i27
#ISCELL
  standard offpage *
  page163_i29
#ISCELL
  standard offpage *
  page163_i30
#ISCELL
  logical_power universal_gnd *
  page163_i31
#ISCELL
  logical_power universal_power *
  page163_i32
#CELL
  pure_quanta q_res *
  page163_i33
#CELL
  pure_quanta q_res *
  page163_i35
#CELL
  pure_quanta q_res *
  page163_i36
#CELL
  pure_quanta q_res *
  page163_i37
#CELL
  pure_quanta q_res *
  page163_i38
#ISCELL
  logical_power universal_gnd *
  page163_i39
#ISCELL
  logical_power universal_gnd *
  page163_i40
#CELL
  pure_quanta q_res *
  page163_i41
#CELL
  pure_quanta q_cap *
  page163_i42
#ISCELL
  logical_power universal_power *
  page163_i43
#ISCELL
  standard offpage *
  page163_i44
#CELL
  pure_quanta q_res *
  page163_i45
#CELL
  pure_quanta ina230airgtr *
  page163_i46
#CELL
  pure_quanta q_cap *
  page163_i49
#ISCELL
  logical_power universal_gnd *
  page163_i50
#ISCELL
  standard offpage *
  page163_i52
#ISCELL
  standard offpage *
  page163_i53
#ISCELL
  logical_power universal_gnd *
  page163_i54
#CELL
  pure_quanta q_res *
  page163_i56
#CELL
  pure_quanta q_res *
  page163_i58
#CELL
  pure_quanta q_res *
  page163_i59
#CELL
  pure_quanta q_res *
  page163_i60
#CELL
  pure_quanta q_res *
  page163_i61
#ISCELL
  logical_power universal_gnd *
  page163_i62
#ISCELL
  logical_power universal_gnd *
  page163_i63
#CELL
  pure_quanta q_res *
  page163_i64
#CELL
  pure_quanta q_cap *
  page163_i65
#ISCELL
  logical_power universal_power *
  page163_i66
#ISCELL
  standard offpage *
  page163_i67
#CELL
  pure_quanta q_res *
  page163_i68
#CELL
  pure_quanta ina230airgtr *
  page163_i69
#CELL
  pure_quanta q_cap *
  page163_i71
#CELL
  pure_quanta q_cap *
  page163_i72
#ISCELL
  logical_power universal_power *
  page163_i76
#ISCELL
  logical_power universal_power *
  page163_i85
#CELL
  pure_quanta q_res *
  page163_i86
#CELL
  pure_quanta q_res *
  page163_i87
#ISCELL
  logical_power universal_power *
  page163_i88
#CELL
  pure_quanta q_res *
  page163_i89
#CELL
  pure_quanta q_res *
  page163_i90
#CELL
  pure_quanta ina230airgtr *
  page163_i94
#ISCELL
  standard offpage *
  page163_i95
#CELL
  pure_quanta q_res *
  page163_i96
#ISCELL
  logical_power universal_power *
  page163_i97
#CELL
  pure_quanta q_cap *
  page163_i98
#ISCELL
  logical_power universal_gnd *
  page163_i99
#ISCELL
  pure_quanta quanta_title_block_c *
  *
#ISCELL
  standard offpage *
  page164_i1
#ISCELL
  standard tap *
  page164_i10
#ISCELL
  standard tap *
  page164_i100
#ISCELL
  standard tap *
  page164_i101
#ISCELL
  standard tap *
  page164_i102
#ISCELL
  standard tap *
  page164_i103
#ISCELL
  standard tap *
  page164_i104
#ISCELL
  standard offpage *
  page164_i105
#ISCELL
  standard offpage *
  page164_i106
#ISCELL
  standard offpage *
  page164_i107
#ISCELL
  standard offpage *
  page164_i108
#ISCELL
  standard tap *
  page164_i109
#ISCELL
  standard tap *
  page164_i11
#ISCELL
  standard tap *
  page164_i110
#ISCELL
  standard tap *
  page164_i111
#ISCELL
  standard tap *
  page164_i112
#ISCELL
  standard tap *
  page164_i113
#ISCELL
  standard tap *
  page164_i114
#ISCELL
  standard tap *
  page164_i115
#ISCELL
  standard tap *
  page164_i116
#ISCELL
  standard tap *
  page164_i117
#ISCELL
  standard tap *
  page164_i118
#ISCELL
  standard tap *
  page164_i119
#ISCELL
  standard tap *
  page164_i12
#ISCELL
  standard tap *
  page164_i120
#CELL
  pure_quanta q_cap_diffbus *
  page164_i121
#CELL
  pure_quanta q_cap_diffbus *
  page164_i122
#CELL
  pure_quanta q_cap_diffbus *
  page164_i123
#CELL
  pure_quanta q_cap_diffbus *
  page164_i124
#CELL
  pure_quanta q_cap_diffbus *
  page164_i125
#CELL
  pure_quanta q_cap_diffbus *
  page164_i126
#CELL
  pure_quanta q_cap_diffbus *
  page164_i127
#CELL
  pure_quanta q_cap_diffbus *
  page164_i128
#ISCELL
  standard tap *
  page164_i129
#ISCELL
  standard tap *
  page164_i13
#ISCELL
  standard tap *
  page164_i130
#ISCELL
  standard tap *
  page164_i131
#ISCELL
  standard tap *
  page164_i132
#CELL
  pure_quanta q_cap_diffbus *
  page164_i133
#CELL
  pure_quanta q_cap_diffbus *
  page164_i134
#CELL
  pure_quanta q_cap_diffbus *
  page164_i135
#CELL
  pure_quanta q_cap_diffbus *
  page164_i136
#CELL
  pure_quanta q_cap_diffbus *
  page164_i137
#ISCELL
  standard tap *
  page164_i138
#ISCELL
  standard tap *
  page164_i139
#ISCELL
  standard tap *
  page164_i14
#ISCELL
  standard tap *
  page164_i140
#ISCELL
  standard tap *
  page164_i141
#ISCELL
  standard tap *
  page164_i142
#ISCELL
  standard tap *
  page164_i143
#ISCELL
  standard tap *
  page164_i144
#ISCELL
  standard tap *
  page164_i145
#ISCELL
  standard tap *
  page164_i146
#ISCELL
  standard tap *
  page164_i147
#ISCELL
  standard tap *
  page164_i148
#ISCELL
  standard tap *
  page164_i149
#ISCELL
  standard tap *
  page164_i15
#ISCELL
  standard tap *
  page164_i150
#CELL
  pure_quanta q_cap_diffbus *
  page164_i151
#CELL
  pure_quanta q_cap_diffbus *
  page164_i152
#CELL
  pure_quanta q_cap_diffbus *
  page164_i153
#CELL
  pure_quanta q_cap_diffbus *
  page164_i154
#CELL
  pure_quanta q_cap_diffbus *
  page164_i155
#CELL
  pure_quanta q_cap_diffbus *
  page164_i156
#CELL
  pure_quanta q_cap_diffbus *
  page164_i157
#CELL
  pure_quanta q_cap_diffbus *
  page164_i158
#CELL
  pure_quanta q_cap_diffbus *
  page164_i159
#ISCELL
  standard tap *
  page164_i16
#CELL
  pure_quanta q_cap_diffbus *
  page164_i160
#ISCELL
  standard tap *
  page164_i161
#ISCELL
  standard tap *
  page164_i162
#ISCELL
  standard tap *
  page164_i163
#CELL
  pure_quanta q_cap_diffbus *
  page164_i164
#CELL
  pure_quanta q_cap_diffbus *
  page164_i165
#CELL
  pure_quanta q_cap_diffbus *
  page164_i166
#CELL
  pure_quanta q_cap_diffbus *
  page164_i167
#CELL
  pure_quanta q_cap_diffbus *
  page164_i168
#CELL
  pure_quanta q_cap_diffbus *
  page164_i169
#ISCELL
  standard tap *
  page164_i17
#ISCELL
  standard tap *
  page164_i170
#ISCELL
  standard tap *
  page164_i171
#ISCELL
  standard tap *
  page164_i172
#ISCELL
  standard tap *
  page164_i173
#ISCELL
  standard tap *
  page164_i174
#ISCELL
  standard tap *
  page164_i175
#ISCELL
  standard tap *
  page164_i176
#ISCELL
  standard tap *
  page164_i177
#ISCELL
  standard tap *
  page164_i178
#ISCELL
  standard tap *
  page164_i179
#ISCELL
  standard tap *
  page164_i18
#ISCELL
  standard tap *
  page164_i180
#ISCELL
  standard tap *
  page164_i181
#ISCELL
  standard tap *
  page164_i182
#ISCELL
  standard tap *
  page164_i183
#ISCELL
  standard tap *
  page164_i184
#ISCELL
  standard offpage *
  page164_i185
#ISCELL
  standard offpage *
  page164_i186
#ISCELL
  standard tap *
  page164_i187
#ISCELL
  standard tap *
  page164_i188
#ISCELL
  standard tap *
  page164_i189
#ISCELL
  standard tap *
  page164_i19
#ISCELL
  standard tap *
  page164_i190
#ISCELL
  standard tap *
  page164_i191
#ISCELL
  standard tap *
  page164_i192
#ISCELL
  standard tap *
  page164_i193
#ISCELL
  standard tap *
  page164_i194
#ISCELL
  standard tap *
  page164_i195
#ISCELL
  standard tap *
  page164_i196
#ISCELL
  standard tap *
  page164_i197
#ISCELL
  standard tap *
  page164_i198
#ISCELL
  standard tap *
  page164_i199
#ISCELL
  standard offpage *
  page164_i2
#ISCELL
  standard tap *
  page164_i20
#ISCELL
  standard tap *
  page164_i200
#ISCELL
  standard tap *
  page164_i201
#ISCELL
  standard tap *
  page164_i202
#ISCELL
  standard offpage *
  page164_i203
#ISCELL
  standard offpage *
  page164_i204
#ISCELL
  standard tap *
  page164_i205
#CELL
  pure_quanta q_cap_diffbus *
  page164_i206
#CELL
  pure_quanta q_cap_diffbus *
  page164_i207
#CELL
  pure_quanta q_cap_diffbus *
  page164_i208
#CELL
  pure_quanta q_cap_diffbus *
  page164_i21
#CELL
  pure_quanta q_cap_diffbus *
  page164_i22
#CELL
  pure_quanta q_cap_diffbus *
  page164_i23
#CELL
  pure_quanta q_cap_diffbus *
  page164_i24
#CELL
  pure_quanta q_cap_diffbus *
  page164_i25
#CELL
  pure_quanta q_cap_diffbus *
  page164_i26
#CELL
  pure_quanta q_cap_diffbus *
  page164_i27
#CELL
  pure_quanta q_cap_diffbus *
  page164_i28
#CELL
  pure_quanta q_cap_diffbus *
  page164_i29
#ISCELL
  standard offpage *
  page164_i3
#CELL
  pure_quanta q_cap_diffbus *
  page164_i30
#CELL
  pure_quanta q_cap_diffbus *
  page164_i31
#CELL
  pure_quanta q_cap_diffbus *
  page164_i32
#CELL
  pure_quanta q_cap_diffbus *
  page164_i33
#CELL
  pure_quanta q_cap_diffbus *
  page164_i34
#CELL
  pure_quanta q_cap_diffbus *
  page164_i35
#CELL
  pure_quanta q_cap_diffbus *
  page164_i36
#ISCELL
  standard tap *
  page164_i37
#ISCELL
  standard tap *
  page164_i38
#ISCELL
  standard tap *
  page164_i39
#ISCELL
  standard offpage *
  page164_i4
#ISCELL
  standard tap *
  page164_i40
#ISCELL
  standard tap *
  page164_i41
#ISCELL
  standard tap *
  page164_i42
#ISCELL
  standard tap *
  page164_i43
#ISCELL
  standard tap *
  page164_i44
#ISCELL
  standard tap *
  page164_i45
#ISCELL
  standard tap *
  page164_i46
#ISCELL
  standard tap *
  page164_i47
#ISCELL
  standard tap *
  page164_i48
#ISCELL
  standard tap *
  page164_i49
#ISCELL
  standard tap *
  page164_i5
#ISCELL
  standard tap *
  page164_i50
#ISCELL
  standard tap *
  page164_i51
#ISCELL
  standard tap *
  page164_i52
#CELL
  pure_quanta q_cap_diffbus *
  page164_i53
#CELL
  pure_quanta q_cap_diffbus *
  page164_i54
#CELL
  pure_quanta q_cap_diffbus *
  page164_i55
#CELL
  pure_quanta q_cap_diffbus *
  page164_i56
#CELL
  pure_quanta q_cap_diffbus *
  page164_i57
#CELL
  pure_quanta q_cap_diffbus *
  page164_i58
#CELL
  pure_quanta q_cap_diffbus *
  page164_i59
#ISCELL
  standard tap *
  page164_i6
#CELL
  pure_quanta q_cap_diffbus *
  page164_i60
#CELL
  pure_quanta q_cap_diffbus *
  page164_i61
#CELL
  pure_quanta q_cap_diffbus *
  page164_i62
#CELL
  pure_quanta q_cap_diffbus *
  page164_i63
#CELL
  pure_quanta q_cap_diffbus *
  page164_i64
#CELL
  pure_quanta q_cap_diffbus *
  page164_i65
#CELL
  pure_quanta q_cap_diffbus *
  page164_i66
#CELL
  pure_quanta q_cap_diffbus *
  page164_i67
#CELL
  pure_quanta q_cap_diffbus *
  page164_i68
#ISCELL
  standard tap *
  page164_i69
#ISCELL
  standard tap *
  page164_i7
#ISCELL
  standard tap *
  page164_i70
#ISCELL
  standard tap *
  page164_i71
#ISCELL
  standard tap *
  page164_i72
#ISCELL
  standard tap *
  page164_i73
#ISCELL
  standard tap *
  page164_i74
#ISCELL
  standard tap *
  page164_i75
#ISCELL
  standard tap *
  page164_i76
#ISCELL
  standard tap *
  page164_i77
#ISCELL
  standard tap *
  page164_i78
#ISCELL
  standard tap *
  page164_i79
#ISCELL
  standard tap *
  page164_i8
#ISCELL
  standard tap *
  page164_i80
#ISCELL
  standard tap *
  page164_i81
#ISCELL
  standard tap *
  page164_i82
#ISCELL
  standard tap *
  page164_i83
#ISCELL
  standard tap *
  page164_i84
#ISCELL
  standard tap *
  page164_i85
#ISCELL
  standard tap *
  page164_i86
#ISCELL
  standard tap *
  page164_i87
#ISCELL
  standard tap *
  page164_i88
#ISCELL
  standard tap *
  page164_i89
#ISCELL
  standard tap *
  page164_i9
#ISCELL
  standard tap *
  page164_i90
#ISCELL
  standard tap *
  page164_i91
#ISCELL
  standard tap *
  page164_i92
#ISCELL
  standard offpage *
  page164_i93
#ISCELL
  standard offpage *
  page164_i94
#ISCELL
  standard offpage *
  page164_i95
#ISCELL
  standard offpage *
  page164_i96
#ISCELL
  standard tap *
  page164_i97
#ISCELL
  standard tap *
  page164_i98
#ISCELL
  standard tap *
  page164_i99
#ISCELL
  pure_quanta quanta_title_block_c *
  *
#ISCELL
  standard offpage *
  page165_i1
#ISCELL
  standard tap *
  page165_i10
#ISCELL
  standard tap *
  page165_i100
#ISCELL
  standard tap *
  page165_i101
#ISCELL
  standard tap *
  page165_i102
#ISCELL
  standard tap *
  page165_i103
#ISCELL
  standard tap *
  page165_i104
#ISCELL
  standard offpage *
  page165_i105
#ISCELL
  standard offpage *
  page165_i106
#ISCELL
  standard offpage *
  page165_i107
#ISCELL
  standard offpage *
  page165_i108
#ISCELL
  standard tap *
  page165_i109
#ISCELL
  standard tap *
  page165_i11
#ISCELL
  standard tap *
  page165_i110
#ISCELL
  standard tap *
  page165_i111
#ISCELL
  standard tap *
  page165_i112
#ISCELL
  standard tap *
  page165_i113
#ISCELL
  standard tap *
  page165_i114
#ISCELL
  standard tap *
  page165_i115
#ISCELL
  standard tap *
  page165_i116
#ISCELL
  standard tap *
  page165_i117
#ISCELL
  standard tap *
  page165_i118
#ISCELL
  standard tap *
  page165_i119
#ISCELL
  standard tap *
  page165_i12
#CELL
  pure_quanta q_cap_diffbus *
  page165_i120
#CELL
  pure_quanta q_cap_diffbus *
  page165_i121
#CELL
  pure_quanta q_cap_diffbus *
  page165_i122
#CELL
  pure_quanta q_cap_diffbus *
  page165_i123
#CELL
  pure_quanta q_cap_diffbus *
  page165_i124
#CELL
  pure_quanta q_cap_diffbus *
  page165_i125
#CELL
  pure_quanta q_cap_diffbus *
  page165_i126
#CELL
  pure_quanta q_cap_diffbus *
  page165_i127
#CELL
  pure_quanta q_cap_diffbus *
  page165_i128
#ISCELL
  standard tap *
  page165_i129
#ISCELL
  standard tap *
  page165_i13
#ISCELL
  standard tap *
  page165_i130
#ISCELL
  standard tap *
  page165_i131
#CELL
  pure_quanta q_cap_diffbus *
  page165_i132
#CELL
  pure_quanta q_cap_diffbus *
  page165_i133
#CELL
  pure_quanta q_cap_diffbus *
  page165_i134
#CELL
  pure_quanta q_cap_diffbus *
  page165_i135
#CELL
  pure_quanta q_cap_diffbus *
  page165_i136
#CELL
  pure_quanta q_cap_diffbus *
  page165_i137
#ISCELL
  standard tap *
  page165_i138
#ISCELL
  standard tap *
  page165_i139
#ISCELL
  standard tap *
  page165_i14
#ISCELL
  standard tap *
  page165_i140
#ISCELL
  standard tap *
  page165_i141
#ISCELL
  standard tap *
  page165_i142
#ISCELL
  standard tap *
  page165_i143
#ISCELL
  standard tap *
  page165_i144
#ISCELL
  standard tap *
  page165_i145
#ISCELL
  standard tap *
  page165_i146
#ISCELL
  standard tap *
  page165_i147
#ISCELL
  standard tap *
  page165_i148
#ISCELL
  standard tap *
  page165_i149
#ISCELL
  standard tap *
  page165_i15
#ISCELL
  standard tap *
  page165_i150
#CELL
  pure_quanta q_cap_diffbus *
  page165_i151
#CELL
  pure_quanta q_cap_diffbus *
  page165_i152
#CELL
  pure_quanta q_cap_diffbus *
  page165_i153
#CELL
  pure_quanta q_cap_diffbus *
  page165_i154
#CELL
  pure_quanta q_cap_diffbus *
  page165_i155
#CELL
  pure_quanta q_cap_diffbus *
  page165_i156
#CELL
  pure_quanta q_cap_diffbus *
  page165_i157
#CELL
  pure_quanta q_cap_diffbus *
  page165_i158
#CELL
  pure_quanta q_cap_diffbus *
  page165_i159
#ISCELL
  standard tap *
  page165_i16
#CELL
  pure_quanta q_cap_diffbus *
  page165_i160
#ISCELL
  standard tap *
  page165_i161
#ISCELL
  standard tap *
  page165_i162
#ISCELL
  standard tap *
  page165_i163
#CELL
  pure_quanta q_cap_diffbus *
  page165_i164
#CELL
  pure_quanta q_cap_diffbus *
  page165_i165
#CELL
  pure_quanta q_cap_diffbus *
  page165_i166
#CELL
  pure_quanta q_cap_diffbus *
  page165_i167
#CELL
  pure_quanta q_cap_diffbus *
  page165_i168
#CELL
  pure_quanta q_cap_diffbus *
  page165_i169
#ISCELL
  standard tap *
  page165_i17
#ISCELL
  standard tap *
  page165_i170
#ISCELL
  standard tap *
  page165_i171
#ISCELL
  standard tap *
  page165_i172
#ISCELL
  standard tap *
  page165_i173
#ISCELL
  standard tap *
  page165_i174
#ISCELL
  standard tap *
  page165_i175
#ISCELL
  standard tap *
  page165_i176
#ISCELL
  standard tap *
  page165_i177
#ISCELL
  standard tap *
  page165_i178
#ISCELL
  standard tap *
  page165_i179
#ISCELL
  standard tap *
  page165_i18
#ISCELL
  standard tap *
  page165_i180
#ISCELL
  standard tap *
  page165_i181
#ISCELL
  standard tap *
  page165_i182
#ISCELL
  standard tap *
  page165_i183
#ISCELL
  standard tap *
  page165_i184
#ISCELL
  standard tap *
  page165_i185
#ISCELL
  standard offpage *
  page165_i186
#ISCELL
  standard offpage *
  page165_i187
#ISCELL
  standard tap *
  page165_i188
#ISCELL
  standard tap *
  page165_i189
#ISCELL
  standard tap *
  page165_i19
#ISCELL
  standard tap *
  page165_i190
#ISCELL
  standard tap *
  page165_i191
#ISCELL
  standard tap *
  page165_i192
#ISCELL
  standard tap *
  page165_i193
#ISCELL
  standard tap *
  page165_i194
#ISCELL
  standard tap *
  page165_i195
#ISCELL
  standard tap *
  page165_i196
#ISCELL
  standard tap *
  page165_i197
#ISCELL
  standard tap *
  page165_i198
#ISCELL
  standard tap *
  page165_i199
#ISCELL
  standard offpage *
  page165_i2
#ISCELL
  standard tap *
  page165_i20
#ISCELL
  standard tap *
  page165_i200
#ISCELL
  standard tap *
  page165_i201
#ISCELL
  standard tap *
  page165_i202
#ISCELL
  standard tap *
  page165_i203
#ISCELL
  standard offpage *
  page165_i204
#ISCELL
  standard offpage *
  page165_i205
#CELL
  pure_quanta q_cap_diffbus *
  page165_i206
#ISCELL
  standard tap *
  page165_i207
#ISCELL
  standard tap *
  page165_i208
#CELL
  pure_quanta q_cap_diffbus *
  page165_i21
#CELL
  pure_quanta q_cap_diffbus *
  page165_i22
#CELL
  pure_quanta q_cap_diffbus *
  page165_i23
#CELL
  pure_quanta q_cap_diffbus *
  page165_i24
#CELL
  pure_quanta q_cap_diffbus *
  page165_i25
#CELL
  pure_quanta q_cap_diffbus *
  page165_i26
#CELL
  pure_quanta q_cap_diffbus *
  page165_i27
#CELL
  pure_quanta q_cap_diffbus *
  page165_i28
#CELL
  pure_quanta q_cap_diffbus *
  page165_i29
#ISCELL
  standard offpage *
  page165_i3
#CELL
  pure_quanta q_cap_diffbus *
  page165_i30
#ISCELL
  standard tap *
  page165_i31
#ISCELL
  standard tap *
  page165_i32
#ISCELL
  standard tap *
  page165_i33
#ISCELL
  standard tap *
  page165_i34
#ISCELL
  standard tap *
  page165_i35
#CELL
  pure_quanta q_cap_diffbus *
  page165_i36
#CELL
  pure_quanta q_cap_diffbus *
  page165_i37
#CELL
  pure_quanta q_cap_diffbus *
  page165_i38
#CELL
  pure_quanta q_cap_diffbus *
  page165_i39
#ISCELL
  standard offpage *
  page165_i4
#CELL
  pure_quanta q_cap_diffbus *
  page165_i40
#CELL
  pure_quanta q_cap_diffbus *
  page165_i41
#ISCELL
  standard tap *
  page165_i42
#ISCELL
  standard tap *
  page165_i43
#ISCELL
  standard tap *
  page165_i44
#ISCELL
  standard tap *
  page165_i45
#ISCELL
  standard tap *
  page165_i46
#ISCELL
  standard tap *
  page165_i47
#ISCELL
  standard tap *
  page165_i48
#ISCELL
  standard tap *
  page165_i49
#ISCELL
  standard tap *
  page165_i5
#ISCELL
  standard tap *
  page165_i50
#ISCELL
  standard tap *
  page165_i51
#ISCELL
  standard tap *
  page165_i52
#ISCELL
  standard tap *
  page165_i53
#ISCELL
  standard tap *
  page165_i54
#ISCELL
  standard tap *
  page165_i55
#ISCELL
  standard tap *
  page165_i56
#ISCELL
  standard tap *
  page165_i57
#ISCELL
  standard tap *
  page165_i58
#ISCELL
  standard tap *
  page165_i59
#ISCELL
  standard tap *
  page165_i6
#ISCELL
  standard tap *
  page165_i60
#CELL
  pure_quanta q_cap_diffbus *
  page165_i61
#CELL
  pure_quanta q_cap_diffbus *
  page165_i62
#CELL
  pure_quanta q_cap_diffbus *
  page165_i63
#CELL
  pure_quanta q_cap_diffbus *
  page165_i64
#CELL
  pure_quanta q_cap_diffbus *
  page165_i65
#CELL
  pure_quanta q_cap_diffbus *
  page165_i66
#CELL
  pure_quanta q_cap_diffbus *
  page165_i67
#CELL
  pure_quanta q_cap_diffbus *
  page165_i68
#CELL
  pure_quanta q_cap_diffbus *
  page165_i69
#ISCELL
  standard tap *
  page165_i7
#CELL
  pure_quanta q_cap_diffbus *
  page165_i70
#ISCELL
  standard tap *
  page165_i71
#ISCELL
  standard tap *
  page165_i72
#ISCELL
  standard tap *
  page165_i73
#ISCELL
  standard tap *
  page165_i74
#ISCELL
  standard tap *
  page165_i75
#CELL
  pure_quanta q_cap_diffbus *
  page165_i76
#CELL
  pure_quanta q_cap_diffbus *
  page165_i77
#CELL
  pure_quanta q_cap_diffbus *
  page165_i78
#CELL
  pure_quanta q_cap_diffbus *
  page165_i79
#ISCELL
  standard tap *
  page165_i8
#CELL
  pure_quanta q_cap_diffbus *
  page165_i80
#CELL
  pure_quanta q_cap_diffbus *
  page165_i81
#ISCELL
  standard tap *
  page165_i82
#ISCELL
  standard tap *
  page165_i83
#ISCELL
  standard tap *
  page165_i84
#ISCELL
  standard tap *
  page165_i85
#ISCELL
  standard tap *
  page165_i86
#ISCELL
  standard tap *
  page165_i87
#ISCELL
  standard tap *
  page165_i88
#ISCELL
  standard tap *
  page165_i89
#ISCELL
  standard tap *
  page165_i9
#ISCELL
  standard tap *
  page165_i90
#ISCELL
  standard tap *
  page165_i91
#ISCELL
  standard tap *
  page165_i92
#ISCELL
  standard offpage *
  page165_i93
#ISCELL
  standard offpage *
  page165_i94
#ISCELL
  standard offpage *
  page165_i95
#ISCELL
  standard offpage *
  page165_i96
#ISCELL
  standard tap *
  page165_i97
#ISCELL
  standard tap *
  page165_i98
#ISCELL
  standard tap *
  page165_i99
#ISCELL
  pure_quanta quanta_title_block_c *
  *
#ISCELL
  standard offpage *
  page166_i209
#ISCELL
  standard offpage *
  page166_i210
#ISCELL
  standard offpage *
  page166_i211
#ISCELL
  standard offpage *
  page166_i212
#ISCELL
  standard tap *
  page166_i213
#ISCELL
  standard tap *
  page166_i214
#ISCELL
  standard tap *
  page166_i215
#ISCELL
  standard tap *
  page166_i216
#ISCELL
  standard tap *
  page166_i217
#ISCELL
  standard tap *
  page166_i218
#ISCELL
  standard tap *
  page166_i219
#ISCELL
  standard tap *
  page166_i220
#ISCELL
  standard tap *
  page166_i221
#ISCELL
  standard tap *
  page166_i222
#ISCELL
  standard tap *
  page166_i223
#ISCELL
  standard tap *
  page166_i224
#ISCELL
  standard tap *
  page166_i225
#ISCELL
  standard tap *
  page166_i226
#ISCELL
  standard tap *
  page166_i227
#ISCELL
  standard tap *
  page166_i228
#CELL
  pure_quanta q_cap_diffbus *
  page166_i229
#CELL
  pure_quanta q_cap_diffbus *
  page166_i230
#CELL
  pure_quanta q_cap_diffbus *
  page166_i231
#CELL
  pure_quanta q_cap_diffbus *
  page166_i232
#CELL
  pure_quanta q_cap_diffbus *
  page166_i233
#CELL
  pure_quanta q_cap_diffbus *
  page166_i234
#CELL
  pure_quanta q_cap_diffbus *
  page166_i235
#CELL
  pure_quanta q_cap_diffbus *
  page166_i236
#CELL
  pure_quanta q_cap_diffbus *
  page166_i237
#CELL
  pure_quanta q_cap_diffbus *
  page166_i238
#CELL
  pure_quanta q_cap_diffbus *
  page166_i239
#CELL
  pure_quanta q_cap_diffbus *
  page166_i240
#CELL
  pure_quanta q_cap_diffbus *
  page166_i241
#CELL
  pure_quanta q_cap_diffbus *
  page166_i242
#ISCELL
  standard tap *
  page166_i243
#ISCELL
  standard tap *
  page166_i244
#ISCELL
  standard tap *
  page166_i245
#ISCELL
  standard tap *
  page166_i246
#ISCELL
  standard tap *
  page166_i247
#ISCELL
  standard tap *
  page166_i248
#ISCELL
  standard tap *
  page166_i249
#ISCELL
  standard tap *
  page166_i250
#ISCELL
  standard tap *
  page166_i251
#ISCELL
  standard tap *
  page166_i252
#ISCELL
  standard tap *
  page166_i253
#ISCELL
  standard tap *
  page166_i254
#ISCELL
  standard tap *
  page166_i255
#ISCELL
  standard tap *
  page166_i256
#ISCELL
  standard tap *
  page166_i257
#ISCELL
  standard tap *
  page166_i258
#CELL
  pure_quanta q_cap_diffbus *
  page166_i259
#CELL
  pure_quanta q_cap_diffbus *
  page166_i260
#CELL
  pure_quanta q_cap_diffbus *
  page166_i261
#CELL
  pure_quanta q_cap_diffbus *
  page166_i262
#CELL
  pure_quanta q_cap_diffbus *
  page166_i263
#CELL
  pure_quanta q_cap_diffbus *
  page166_i264
#CELL
  pure_quanta q_cap_diffbus *
  page166_i265
#CELL
  pure_quanta q_cap_diffbus *
  page166_i266
#CELL
  pure_quanta q_cap_diffbus *
  page166_i267
#CELL
  pure_quanta q_cap_diffbus *
  page166_i268
#CELL
  pure_quanta q_cap_diffbus *
  page166_i269
#CELL
  pure_quanta q_cap_diffbus *
  page166_i270
#CELL
  pure_quanta q_cap_diffbus *
  page166_i271
#CELL
  pure_quanta q_cap_diffbus *
  page166_i272
#CELL
  pure_quanta q_cap_diffbus *
  page166_i273
#CELL
  pure_quanta q_cap_diffbus *
  page166_i274
#ISCELL
  standard tap *
  page166_i275
#ISCELL
  standard tap *
  page166_i276
#ISCELL
  standard tap *
  page166_i277
#ISCELL
  standard tap *
  page166_i278
#ISCELL
  standard tap *
  page166_i279
#ISCELL
  standard tap *
  page166_i280
#ISCELL
  standard tap *
  page166_i281
#ISCELL
  standard tap *
  page166_i282
#ISCELL
  standard tap *
  page166_i283
#ISCELL
  standard tap *
  page166_i284
#ISCELL
  standard tap *
  page166_i285
#ISCELL
  standard tap *
  page166_i286
#ISCELL
  standard tap *
  page166_i287
#ISCELL
  standard tap *
  page166_i288
#ISCELL
  standard tap *
  page166_i289
#ISCELL
  standard tap *
  page166_i290
#ISCELL
  standard offpage *
  page166_i291
#ISCELL
  standard offpage *
  page166_i292
#ISCELL
  standard tap *
  page166_i293
#ISCELL
  standard tap *
  page166_i294
#ISCELL
  standard tap *
  page166_i295
#ISCELL
  standard tap *
  page166_i296
#ISCELL
  standard tap *
  page166_i297
#ISCELL
  standard tap *
  page166_i298
#ISCELL
  standard tap *
  page166_i299
#ISCELL
  standard tap *
  page166_i300
#ISCELL
  standard tap *
  page166_i301
#ISCELL
  standard tap *
  page166_i302
#ISCELL
  standard tap *
  page166_i303
#ISCELL
  standard tap *
  page166_i304
#ISCELL
  standard tap *
  page166_i305
#ISCELL
  standard tap *
  page166_i306
#ISCELL
  standard tap *
  page166_i307
#ISCELL
  standard tap *
  page166_i308
#ISCELL
  standard offpage *
  page166_i309
#ISCELL
  standard offpage *
  page166_i310
#CELL
  pure_quanta q_cap_diffbus *
  page166_i311
#CELL
  pure_quanta q_cap_diffbus *
  page166_i312
#ISCELL
  standard offpage *
  page166_i313
#ISCELL
  standard offpage *
  page166_i314
#ISCELL
  standard offpage *
  page166_i315
#ISCELL
  standard offpage *
  page166_i316
#ISCELL
  standard tap *
  page166_i317
#ISCELL
  standard tap *
  page166_i318
#ISCELL
  standard tap *
  page166_i319
#ISCELL
  standard tap *
  page166_i320
#ISCELL
  standard tap *
  page166_i321
#ISCELL
  standard tap *
  page166_i322
#ISCELL
  standard tap *
  page166_i323
#ISCELL
  standard tap *
  page166_i324
#ISCELL
  standard tap *
  page166_i325
#ISCELL
  standard tap *
  page166_i326
#ISCELL
  standard tap *
  page166_i327
#ISCELL
  standard tap *
  page166_i328
#ISCELL
  standard tap *
  page166_i329
#ISCELL
  standard tap *
  page166_i330
#ISCELL
  standard tap *
  page166_i331
#ISCELL
  standard tap *
  page166_i332
#CELL
  pure_quanta q_cap_diffbus *
  page166_i333
#CELL
  pure_quanta q_cap_diffbus *
  page166_i334
#CELL
  pure_quanta q_cap_diffbus *
  page166_i335
#CELL
  pure_quanta q_cap_diffbus *
  page166_i336
#CELL
  pure_quanta q_cap_diffbus *
  page166_i337
#CELL
  pure_quanta q_cap_diffbus *
  page166_i338
#CELL
  pure_quanta q_cap_diffbus *
  page166_i339
#CELL
  pure_quanta q_cap_diffbus *
  page166_i340
#CELL
  pure_quanta q_cap_diffbus *
  page166_i341
#CELL
  pure_quanta q_cap_diffbus *
  page166_i342
#CELL
  pure_quanta q_cap_diffbus *
  page166_i343
#CELL
  pure_quanta q_cap_diffbus *
  page166_i344
#CELL
  pure_quanta q_cap_diffbus *
  page166_i345
#CELL
  pure_quanta q_cap_diffbus *
  page166_i346
#ISCELL
  standard tap *
  page166_i347
#ISCELL
  standard tap *
  page166_i348
#ISCELL
  standard tap *
  page166_i349
#ISCELL
  standard tap *
  page166_i350
#ISCELL
  standard tap *
  page166_i351
#ISCELL
  standard tap *
  page166_i352
#ISCELL
  standard tap *
  page166_i353
#ISCELL
  standard tap *
  page166_i354
#ISCELL
  standard tap *
  page166_i355
#ISCELL
  standard tap *
  page166_i356
#ISCELL
  standard tap *
  page166_i357
#ISCELL
  standard tap *
  page166_i358
#ISCELL
  standard tap *
  page166_i359
#ISCELL
  standard tap *
  page166_i360
#ISCELL
  standard tap *
  page166_i361
#ISCELL
  standard tap *
  page166_i362
#CELL
  pure_quanta q_cap_diffbus *
  page166_i363
#CELL
  pure_quanta q_cap_diffbus *
  page166_i364
#CELL
  pure_quanta q_cap_diffbus *
  page166_i365
#CELL
  pure_quanta q_cap_diffbus *
  page166_i366
#CELL
  pure_quanta q_cap_diffbus *
  page166_i367
#CELL
  pure_quanta q_cap_diffbus *
  page166_i368
#CELL
  pure_quanta q_cap_diffbus *
  page166_i369
#CELL
  pure_quanta q_cap_diffbus *
  page166_i370
#CELL
  pure_quanta q_cap_diffbus *
  page166_i371
#CELL
  pure_quanta q_cap_diffbus *
  page166_i372
#CELL
  pure_quanta q_cap_diffbus *
  page166_i373
#CELL
  pure_quanta q_cap_diffbus *
  page166_i374
#CELL
  pure_quanta q_cap_diffbus *
  page166_i375
#CELL
  pure_quanta q_cap_diffbus *
  page166_i376
#CELL
  pure_quanta q_cap_diffbus *
  page166_i377
#CELL
  pure_quanta q_cap_diffbus *
  page166_i378
#ISCELL
  standard tap *
  page166_i379
#ISCELL
  standard tap *
  page166_i380
#ISCELL
  standard tap *
  page166_i381
#ISCELL
  standard tap *
  page166_i382
#ISCELL
  standard tap *
  page166_i383
#ISCELL
  standard tap *
  page166_i384
#ISCELL
  standard tap *
  page166_i385
#ISCELL
  standard tap *
  page166_i386
#ISCELL
  standard tap *
  page166_i387
#ISCELL
  standard tap *
  page166_i388
#ISCELL
  standard tap *
  page166_i389
#ISCELL
  standard tap *
  page166_i390
#ISCELL
  standard tap *
  page166_i391
#ISCELL
  standard tap *
  page166_i392
#ISCELL
  standard tap *
  page166_i393
#ISCELL
  standard offpage *
  page166_i394
#ISCELL
  standard offpage *
  page166_i395
#ISCELL
  standard tap *
  page166_i396
#ISCELL
  standard tap *
  page166_i397
#ISCELL
  standard tap *
  page166_i398
#ISCELL
  standard tap *
  page166_i399
#ISCELL
  standard tap *
  page166_i400
#ISCELL
  standard tap *
  page166_i401
#ISCELL
  standard tap *
  page166_i402
#ISCELL
  standard tap *
  page166_i403
#ISCELL
  standard tap *
  page166_i404
#ISCELL
  standard tap *
  page166_i405
#ISCELL
  standard tap *
  page166_i406
#ISCELL
  standard tap *
  page166_i407
#ISCELL
  standard tap *
  page166_i408
#ISCELL
  standard tap *
  page166_i409
#ISCELL
  standard tap *
  page166_i410
#ISCELL
  standard tap *
  page166_i411
#ISCELL
  standard offpage *
  page166_i412
#ISCELL
  standard offpage *
  page166_i413
#ISCELL
  standard tap *
  page166_i414
#CELL
  pure_quanta q_cap_diffbus *
  page166_i415
#CELL
  pure_quanta q_cap_diffbus *
  page166_i416
#ISCELL
  pure_quanta quanta_title_block_c *
  *
#ISCELL
  standard offpage *
  page167_i107
#ISCELL
  standard offpage *
  page167_i108
#ISCELL
  standard tap *
  page167_i109
#ISCELL
  standard tap *
  page167_i110
#ISCELL
  standard tap *
  page167_i111
#ISCELL
  standard tap *
  page167_i112
#ISCELL
  standard tap *
  page167_i113
#ISCELL
  standard tap *
  page167_i114
#ISCELL
  standard tap *
  page167_i115
#ISCELL
  standard tap *
  page167_i116
#ISCELL
  standard tap *
  page167_i117
#ISCELL
  standard tap *
  page167_i118
#ISCELL
  standard tap *
  page167_i119
#ISCELL
  standard tap *
  page167_i120
#ISCELL
  standard tap *
  page167_i121
#CELL
  pure_quanta q_cap_diffbus *
  page167_i122
#CELL
  pure_quanta q_cap_diffbus *
  page167_i123
#CELL
  pure_quanta q_cap_diffbus *
  page167_i124
#CELL
  pure_quanta q_cap_diffbus *
  page167_i125
#CELL
  pure_quanta q_cap_diffbus *
  page167_i126
#CELL
  pure_quanta q_cap_diffbus *
  page167_i127
#CELL
  pure_quanta q_cap_diffbus *
  page167_i128
#CELL
  pure_quanta q_cap_diffbus *
  page167_i129
#CELL
  pure_quanta q_cap_diffbus *
  page167_i130
#CELL
  pure_quanta q_cap_diffbus *
  page167_i131
#ISCELL
  standard tap *
  page167_i132
#ISCELL
  standard tap *
  page167_i133
#ISCELL
  standard tap *
  page167_i134
#CELL
  pure_quanta q_cap_diffbus *
  page167_i135
#CELL
  pure_quanta q_cap_diffbus *
  page167_i136
#CELL
  pure_quanta q_cap_diffbus *
  page167_i137
#CELL
  pure_quanta q_cap_diffbus *
  page167_i138
#CELL
  pure_quanta q_cap_diffbus *
  page167_i139
#CELL
  pure_quanta q_cap_diffbus *
  page167_i140
#ISCELL
  standard tap *
  page167_i141
#ISCELL
  standard tap *
  page167_i142
#ISCELL
  standard tap *
  page167_i143
#ISCELL
  standard tap *
  page167_i144
#ISCELL
  standard tap *
  page167_i145
#ISCELL
  standard tap *
  page167_i146
#ISCELL
  standard tap *
  page167_i147
#ISCELL
  standard tap *
  page167_i148
#ISCELL
  standard tap *
  page167_i149
#ISCELL
  standard tap *
  page167_i150
#ISCELL
  standard tap *
  page167_i151
#ISCELL
  standard tap *
  page167_i152
#ISCELL
  standard tap *
  page167_i153
#CELL
  pure_quanta q_cap_diffbus *
  page167_i154
#CELL
  pure_quanta q_cap_diffbus *
  page167_i155
#CELL
  pure_quanta q_cap_diffbus *
  page167_i156
#CELL
  pure_quanta q_cap_diffbus *
  page167_i157
#CELL
  pure_quanta q_cap_diffbus *
  page167_i158
#CELL
  pure_quanta q_cap_diffbus *
  page167_i159
#CELL
  pure_quanta q_cap_diffbus *
  page167_i160
#CELL
  pure_quanta q_cap_diffbus *
  page167_i161
#CELL
  pure_quanta q_cap_diffbus *
  page167_i162
#CELL
  pure_quanta q_cap_diffbus *
  page167_i163
#ISCELL
  standard tap *
  page167_i164
#ISCELL
  standard tap *
  page167_i165
#ISCELL
  standard tap *
  page167_i166
#CELL
  pure_quanta q_cap_diffbus *
  page167_i167
#CELL
  pure_quanta q_cap_diffbus *
  page167_i168
#CELL
  pure_quanta q_cap_diffbus *
  page167_i169
#CELL
  pure_quanta q_cap_diffbus *
  page167_i170
#CELL
  pure_quanta q_cap_diffbus *
  page167_i171
#CELL
  pure_quanta q_cap_diffbus *
  page167_i172
#ISCELL
  standard tap *
  page167_i173
#ISCELL
  standard tap *
  page167_i174
#ISCELL
  standard tap *
  page167_i175
#ISCELL
  standard tap *
  page167_i176
#ISCELL
  standard tap *
  page167_i177
#ISCELL
  standard tap *
  page167_i178
#ISCELL
  standard tap *
  page167_i179
#ISCELL
  standard tap *
  page167_i180
#ISCELL
  standard tap *
  page167_i181
#ISCELL
  standard tap *
  page167_i182
#ISCELL
  standard tap *
  page167_i183
#ISCELL
  standard tap *
  page167_i184
#ISCELL
  standard tap *
  page167_i185
#ISCELL
  standard tap *
  page167_i186
#ISCELL
  standard tap *
  page167_i187
#ISCELL
  standard tap *
  page167_i188
#ISCELL
  standard offpage *
  page167_i189
#ISCELL
  standard offpage *
  page167_i190
#ISCELL
  standard tap *
  page167_i191
#ISCELL
  standard tap *
  page167_i192
#ISCELL
  standard tap *
  page167_i193
#ISCELL
  standard tap *
  page167_i194
#ISCELL
  standard tap *
  page167_i195
#ISCELL
  standard tap *
  page167_i196
#ISCELL
  standard tap *
  page167_i197
#ISCELL
  standard tap *
  page167_i198
#ISCELL
  standard tap *
  page167_i199
#ISCELL
  standard tap *
  page167_i200
#ISCELL
  standard tap *
  page167_i201
#ISCELL
  standard tap *
  page167_i202
#ISCELL
  standard tap *
  page167_i203
#ISCELL
  standard tap *
  page167_i204
#ISCELL
  standard tap *
  page167_i205
#ISCELL
  standard tap *
  page167_i206
#ISCELL
  standard offpage *
  page167_i207
#ISCELL
  standard offpage *
  page167_i208
#ISCELL
  standard offpage *
  page167_i209
#ISCELL
  standard offpage *
  page167_i210
#ISCELL
  standard offpage *
  page167_i211
#ISCELL
  standard offpage *
  page167_i212
#ISCELL
  standard tap *
  page167_i213
#ISCELL
  standard tap *
  page167_i214
#ISCELL
  standard tap *
  page167_i215
#ISCELL
  standard tap *
  page167_i216
#ISCELL
  standard tap *
  page167_i217
#ISCELL
  standard tap *
  page167_i218
#ISCELL
  standard tap *
  page167_i219
#ISCELL
  standard tap *
  page167_i220
#ISCELL
  standard tap *
  page167_i221
#ISCELL
  standard tap *
  page167_i222
#ISCELL
  standard tap *
  page167_i223
#ISCELL
  standard tap *
  page167_i224
#ISCELL
  standard tap *
  page167_i225
#ISCELL
  standard tap *
  page167_i226
#ISCELL
  standard tap *
  page167_i227
#ISCELL
  standard tap *
  page167_i228
#CELL
  pure_quanta q_cap_diffbus *
  page167_i229
#CELL
  pure_quanta q_cap_diffbus *
  page167_i230
#CELL
  pure_quanta q_cap_diffbus *
  page167_i231
#CELL
  pure_quanta q_cap_diffbus *
  page167_i232
#CELL
  pure_quanta q_cap_diffbus *
  page167_i233
#CELL
  pure_quanta q_cap_diffbus *
  page167_i234
#CELL
  pure_quanta q_cap_diffbus *
  page167_i235
#CELL
  pure_quanta q_cap_diffbus *
  page167_i236
#CELL
  pure_quanta q_cap_diffbus *
  page167_i237
#ISCELL
  standard tap *
  page167_i238
#ISCELL
  standard tap *
  page167_i239
#ISCELL
  standard tap *
  page167_i240
#ISCELL
  standard tap *
  page167_i241
#ISCELL
  standard tap *
  page167_i242
#ISCELL
  standard tap *
  page167_i243
#ISCELL
  standard tap *
  page167_i244
#ISCELL
  standard tap *
  page167_i245
#CELL
  pure_quanta q_cap_diffbus *
  page167_i246
#CELL
  pure_quanta q_cap_diffbus *
  page167_i247
#CELL
  pure_quanta q_cap_diffbus *
  page167_i248
#CELL
  pure_quanta q_cap_diffbus *
  page167_i249
#CELL
  pure_quanta q_cap_diffbus *
  page167_i250
#CELL
  pure_quanta q_cap_diffbus *
  page167_i251
#ISCELL
  standard tap *
  page167_i252
#ISCELL
  standard tap *
  page167_i253
#ISCELL
  standard tap *
  page167_i254
#ISCELL
  standard tap *
  page167_i255
#ISCELL
  standard tap *
  page167_i256
#ISCELL
  standard tap *
  page167_i257
#ISCELL
  standard tap *
  page167_i258
#ISCELL
  standard tap *
  page167_i259
#ISCELL
  standard tap *
  page167_i260
#ISCELL
  standard tap *
  page167_i261
#ISCELL
  standard tap *
  page167_i262
#ISCELL
  standard tap *
  page167_i263
#ISCELL
  standard tap *
  page167_i264
#ISCELL
  standard tap *
  page167_i265
#ISCELL
  standard tap *
  page167_i266
#ISCELL
  standard tap *
  page167_i267
#ISCELL
  standard tap *
  page167_i268
#ISCELL
  standard tap *
  page167_i269
#ISCELL
  standard tap *
  page167_i270
#ISCELL
  standard tap *
  page167_i271
#ISCELL
  standard tap *
  page167_i272
#ISCELL
  standard tap *
  page167_i273
#CELL
  pure_quanta q_cap_diffbus *
  page167_i274
#CELL
  pure_quanta q_cap_diffbus *
  page167_i275
#CELL
  pure_quanta q_cap_diffbus *
  page167_i276
#CELL
  pure_quanta q_cap_diffbus *
  page167_i277
#CELL
  pure_quanta q_cap_diffbus *
  page167_i278
#CELL
  pure_quanta q_cap_diffbus *
  page167_i279
#CELL
  pure_quanta q_cap_diffbus *
  page167_i280
#CELL
  pure_quanta q_cap_diffbus *
  page167_i281
#CELL
  pure_quanta q_cap_diffbus *
  page167_i282
#CELL
  pure_quanta q_cap_diffbus *
  page167_i283
#ISCELL
  standard tap *
  page167_i284
#ISCELL
  standard tap *
  page167_i285
#ISCELL
  standard tap *
  page167_i286
#ISCELL
  standard tap *
  page167_i287
#ISCELL
  standard tap *
  page167_i288
#ISCELL
  standard tap *
  page167_i289
#ISCELL
  standard tap *
  page167_i290
#ISCELL
  standard tap *
  page167_i291
#ISCELL
  standard tap *
  page167_i292
#ISCELL
  standard tap *
  page167_i293
#CELL
  pure_quanta q_cap_diffbus *
  page167_i294
#CELL
  pure_quanta q_cap_diffbus *
  page167_i295
#CELL
  pure_quanta q_cap_diffbus *
  page167_i296
#CELL
  pure_quanta q_cap_diffbus *
  page167_i297
#CELL
  pure_quanta q_cap_diffbus *
  page167_i298
#CELL
  pure_quanta q_cap_diffbus *
  page167_i299
#ISCELL
  standard tap *
  page167_i300
#ISCELL
  standard tap *
  page167_i301
#ISCELL
  standard tap *
  page167_i302
#ISCELL
  standard tap *
  page167_i303
#ISCELL
  standard tap *
  page167_i304
#ISCELL
  standard tap *
  page167_i305
#ISCELL
  standard offpage *
  page167_i306
#ISCELL
  standard offpage *
  page167_i307
#ISCELL
  standard offpage *
  page167_i308
#ISCELL
  standard offpage *
  page167_i309
#ISCELL
  standard tap *
  page167_i310
#ISCELL
  standard tap *
  page167_i311
#CELL
  pure_quanta q_cap_diffbus *
  page167_i312
#ISCELL
  standard offpage *
  page167_i95
#ISCELL
  standard offpage *
  page167_i96
#ISCELL
  pure_quanta quanta_title_block_c *
  *
#ISCELL
  standard offpage *
  page168_i103
#ISCELL
  standard offpage *
  page168_i104
#ISCELL
  standard offpage *
  page168_i107
#ISCELL
  standard offpage *
  page168_i108
#ISCELL
  standard tap *
  page168_i109
#ISCELL
  standard tap *
  page168_i110
#ISCELL
  standard tap *
  page168_i111
#ISCELL
  standard tap *
  page168_i112
#ISCELL
  standard tap *
  page168_i113
#ISCELL
  standard tap *
  page168_i114
#ISCELL
  standard tap *
  page168_i115
#ISCELL
  standard tap *
  page168_i116
#ISCELL
  standard tap *
  page168_i117
#ISCELL
  standard tap *
  page168_i118
#ISCELL
  standard tap *
  page168_i119
#ISCELL
  standard tap *
  page168_i120
#ISCELL
  standard tap *
  page168_i121
#ISCELL
  standard tap *
  page168_i122
#ISCELL
  standard tap *
  page168_i123
#ISCELL
  standard tap *
  page168_i124
#CELL
  pure_quanta q_cap_diffbus *
  page168_i125
#CELL
  pure_quanta q_cap_diffbus *
  page168_i126
#CELL
  pure_quanta q_cap_diffbus *
  page168_i127
#CELL
  pure_quanta q_cap_diffbus *
  page168_i128
#CELL
  pure_quanta q_cap_diffbus *
  page168_i129
#CELL
  pure_quanta q_cap_diffbus *
  page168_i130
#CELL
  pure_quanta q_cap_diffbus *
  page168_i131
#CELL
  pure_quanta q_cap_diffbus *
  page168_i132
#CELL
  pure_quanta q_cap_diffbus *
  page168_i133
#CELL
  pure_quanta q_cap_diffbus *
  page168_i134
#CELL
  pure_quanta q_cap_diffbus *
  page168_i135
#CELL
  pure_quanta q_cap_diffbus *
  page168_i136
#CELL
  pure_quanta q_cap_diffbus *
  page168_i137
#CELL
  pure_quanta q_cap_diffbus *
  page168_i138
#CELL
  pure_quanta q_cap_diffbus *
  page168_i139
#CELL
  pure_quanta q_cap_diffbus *
  page168_i140
#ISCELL
  standard tap *
  page168_i141
#ISCELL
  standard tap *
  page168_i142
#ISCELL
  standard tap *
  page168_i143
#ISCELL
  standard tap *
  page168_i144
#ISCELL
  standard tap *
  page168_i145
#ISCELL
  standard tap *
  page168_i146
#ISCELL
  standard tap *
  page168_i147
#ISCELL
  standard tap *
  page168_i148
#ISCELL
  standard tap *
  page168_i149
#ISCELL
  standard tap *
  page168_i150
#ISCELL
  standard tap *
  page168_i151
#ISCELL
  standard tap *
  page168_i152
#ISCELL
  standard tap *
  page168_i153
#ISCELL
  standard tap *
  page168_i154
#ISCELL
  standard tap *
  page168_i155
#ISCELL
  standard tap *
  page168_i156
#CELL
  pure_quanta q_cap_diffbus *
  page168_i157
#CELL
  pure_quanta q_cap_diffbus *
  page168_i158
#CELL
  pure_quanta q_cap_diffbus *
  page168_i159
#CELL
  pure_quanta q_cap_diffbus *
  page168_i160
#CELL
  pure_quanta q_cap_diffbus *
  page168_i161
#CELL
  pure_quanta q_cap_diffbus *
  page168_i162
#CELL
  pure_quanta q_cap_diffbus *
  page168_i163
#CELL
  pure_quanta q_cap_diffbus *
  page168_i164
#CELL
  pure_quanta q_cap_diffbus *
  page168_i165
#CELL
  pure_quanta q_cap_diffbus *
  page168_i166
#CELL
  pure_quanta q_cap_diffbus *
  page168_i167
#CELL
  pure_quanta q_cap_diffbus *
  page168_i168
#CELL
  pure_quanta q_cap_diffbus *
  page168_i169
#CELL
  pure_quanta q_cap_diffbus *
  page168_i170
#CELL
  pure_quanta q_cap_diffbus *
  page168_i171
#CELL
  pure_quanta q_cap_diffbus *
  page168_i172
#ISCELL
  standard tap *
  page168_i173
#ISCELL
  standard tap *
  page168_i174
#ISCELL
  standard tap *
  page168_i175
#ISCELL
  standard tap *
  page168_i176
#ISCELL
  standard tap *
  page168_i177
#ISCELL
  standard tap *
  page168_i178
#ISCELL
  standard tap *
  page168_i179
#ISCELL
  standard tap *
  page168_i180
#ISCELL
  standard tap *
  page168_i181
#ISCELL
  standard tap *
  page168_i182
#ISCELL
  standard tap *
  page168_i183
#ISCELL
  standard tap *
  page168_i184
#ISCELL
  standard tap *
  page168_i185
#ISCELL
  standard tap *
  page168_i186
#ISCELL
  standard tap *
  page168_i187
#ISCELL
  standard tap *
  page168_i188
#ISCELL
  standard offpage *
  page168_i189
#ISCELL
  standard offpage *
  page168_i190
#ISCELL
  standard tap *
  page168_i191
#ISCELL
  standard tap *
  page168_i192
#ISCELL
  standard tap *
  page168_i193
#ISCELL
  standard tap *
  page168_i194
#ISCELL
  standard tap *
  page168_i195
#ISCELL
  standard tap *
  page168_i196
#ISCELL
  standard tap *
  page168_i197
#ISCELL
  standard tap *
  page168_i198
#ISCELL
  standard tap *
  page168_i199
#ISCELL
  standard tap *
  page168_i200
#ISCELL
  standard tap *
  page168_i201
#ISCELL
  standard tap *
  page168_i202
#ISCELL
  standard tap *
  page168_i203
#ISCELL
  standard tap *
  page168_i204
#ISCELL
  standard tap *
  page168_i205
#ISCELL
  standard tap *
  page168_i206
#ISCELL
  standard offpage *
  page168_i207
#ISCELL
  standard offpage *
  page168_i208
#ISCELL
  standard offpage *
  page168_i209
#ISCELL
  standard offpage *
  page168_i210
#ISCELL
  standard offpage *
  page168_i211
#ISCELL
  standard offpage *
  page168_i212
#ISCELL
  standard tap *
  page168_i213
#ISCELL
  standard tap *
  page168_i214
#ISCELL
  standard tap *
  page168_i215
#ISCELL
  standard tap *
  page168_i216
#ISCELL
  standard tap *
  page168_i217
#ISCELL
  standard tap *
  page168_i218
#ISCELL
  standard tap *
  page168_i219
#ISCELL
  standard tap *
  page168_i220
#ISCELL
  standard tap *
  page168_i221
#ISCELL
  standard tap *
  page168_i222
#ISCELL
  standard tap *
  page168_i223
#ISCELL
  standard tap *
  page168_i224
#ISCELL
  standard tap *
  page168_i225
#ISCELL
  standard tap *
  page168_i226
#ISCELL
  standard tap *
  page168_i227
#ISCELL
  standard tap *
  page168_i228
#CELL
  pure_quanta q_cap_diffbus *
  page168_i229
#CELL
  pure_quanta q_cap_diffbus *
  page168_i230
#CELL
  pure_quanta q_cap_diffbus *
  page168_i231
#CELL
  pure_quanta q_cap_diffbus *
  page168_i232
#CELL
  pure_quanta q_cap_diffbus *
  page168_i233
#CELL
  pure_quanta q_cap_diffbus *
  page168_i234
#CELL
  pure_quanta q_cap_diffbus *
  page168_i235
#CELL
  pure_quanta q_cap_diffbus *
  page168_i236
#CELL
  pure_quanta q_cap_diffbus *
  page168_i237
#CELL
  pure_quanta q_cap_diffbus *
  page168_i238
#ISCELL
  standard tap *
  page168_i239
#ISCELL
  standard tap *
  page168_i240
#ISCELL
  standard tap *
  page168_i241
#ISCELL
  standard tap *
  page168_i242
#ISCELL
  standard tap *
  page168_i243
#ISCELL
  standard tap *
  page168_i244
#ISCELL
  standard tap *
  page168_i245
#ISCELL
  standard tap *
  page168_i246
#ISCELL
  standard tap *
  page168_i247
#ISCELL
  standard tap *
  page168_i248
#CELL
  pure_quanta q_cap_diffbus *
  page168_i249
#CELL
  pure_quanta q_cap_diffbus *
  page168_i250
#CELL
  pure_quanta q_cap_diffbus *
  page168_i251
#CELL
  pure_quanta q_cap_diffbus *
  page168_i252
#CELL
  pure_quanta q_cap_diffbus *
  page168_i253
#CELL
  pure_quanta q_cap_diffbus *
  page168_i254
#ISCELL
  standard tap *
  page168_i255
#ISCELL
  standard tap *
  page168_i256
#ISCELL
  standard tap *
  page168_i257
#ISCELL
  standard tap *
  page168_i258
#ISCELL
  standard tap *
  page168_i259
#ISCELL
  standard tap *
  page168_i260
#ISCELL
  standard tap *
  page168_i261
#ISCELL
  standard tap *
  page168_i262
#ISCELL
  standard tap *
  page168_i263
#ISCELL
  standard tap *
  page168_i264
#ISCELL
  standard tap *
  page168_i265
#ISCELL
  standard tap *
  page168_i266
#ISCELL
  standard tap *
  page168_i267
#ISCELL
  standard tap *
  page168_i268
#ISCELL
  standard tap *
  page168_i269
#ISCELL
  standard tap *
  page168_i270
#ISCELL
  standard tap *
  page168_i271
#ISCELL
  standard tap *
  page168_i272
#ISCELL
  standard tap *
  page168_i273
#ISCELL
  standard tap *
  page168_i274
#ISCELL
  standard tap *
  page168_i275
#ISCELL
  standard tap *
  page168_i276
#CELL
  pure_quanta q_cap_diffbus *
  page168_i277
#CELL
  pure_quanta q_cap_diffbus *
  page168_i278
#CELL
  pure_quanta q_cap_diffbus *
  page168_i279
#CELL
  pure_quanta q_cap_diffbus *
  page168_i280
#CELL
  pure_quanta q_cap_diffbus *
  page168_i281
#CELL
  pure_quanta q_cap_diffbus *
  page168_i282
#CELL
  pure_quanta q_cap_diffbus *
  page168_i283
#CELL
  pure_quanta q_cap_diffbus *
  page168_i284
#CELL
  pure_quanta q_cap_diffbus *
  page168_i285
#CELL
  pure_quanta q_cap_diffbus *
  page168_i286
#ISCELL
  standard tap *
  page168_i287
#ISCELL
  standard tap *
  page168_i288
#ISCELL
  standard tap *
  page168_i289
#ISCELL
  standard tap *
  page168_i290
#ISCELL
  standard tap *
  page168_i291
#ISCELL
  standard tap *
  page168_i292
#ISCELL
  standard tap *
  page168_i293
#ISCELL
  standard tap *
  page168_i294
#ISCELL
  standard tap *
  page168_i295
#ISCELL
  standard tap *
  page168_i296
#CELL
  pure_quanta q_cap_diffbus *
  page168_i297
#CELL
  pure_quanta q_cap_diffbus *
  page168_i298
#CELL
  pure_quanta q_cap_diffbus *
  page168_i299
#CELL
  pure_quanta q_cap_diffbus *
  page168_i300
#CELL
  pure_quanta q_cap_diffbus *
  page168_i301
#CELL
  pure_quanta q_cap_diffbus *
  page168_i302
#ISCELL
  standard tap *
  page168_i303
#ISCELL
  standard tap *
  page168_i304
#ISCELL
  standard tap *
  page168_i305
#ISCELL
  standard tap *
  page168_i306
#ISCELL
  standard tap *
  page168_i307
#ISCELL
  standard tap *
  page168_i308
#ISCELL
  standard offpage *
  page168_i309
#ISCELL
  standard offpage *
  page168_i310
#ISCELL
  standard offpage *
  page168_i311
#ISCELL
  standard offpage *
  page168_i312
#ISCELL
  pure_quanta quanta_title_block_c *
  *
#ISCELL
  standard offpage *
  page169_i1
#ISCELL
  standard tap *
  page169_i10
#ISCELL
  standard tap *
  page169_i100
#ISCELL
  standard tap *
  page169_i101
#ISCELL
  standard tap *
  page169_i102
#ISCELL
  standard tap *
  page169_i103
#ISCELL
  standard tap *
  page169_i104
#ISCELL
  standard tap *
  page169_i105
#ISCELL
  standard tap *
  page169_i106
#ISCELL
  standard tap *
  page169_i107
#ISCELL
  standard tap *
  page169_i108
#ISCELL
  standard tap *
  page169_i109
#ISCELL
  standard tap *
  page169_i11
#ISCELL
  standard tap *
  page169_i110
#ISCELL
  standard tap *
  page169_i111
#ISCELL
  standard tap *
  page169_i112
#CELL
  pure_quanta q_cap_diffbus *
  page169_i113
#CELL
  pure_quanta q_cap_diffbus *
  page169_i114
#CELL
  pure_quanta q_cap_diffbus *
  page169_i115
#CELL
  pure_quanta q_cap_diffbus *
  page169_i116
#CELL
  pure_quanta q_cap_diffbus *
  page169_i117
#CELL
  pure_quanta q_cap_diffbus *
  page169_i118
#CELL
  pure_quanta q_cap_diffbus *
  page169_i119
#ISCELL
  standard tap *
  page169_i12
#CELL
  pure_quanta q_cap_diffbus *
  page169_i120
#CELL
  pure_quanta q_cap_diffbus *
  page169_i121
#CELL
  pure_quanta q_cap_diffbus *
  page169_i122
#CELL
  pure_quanta q_cap_diffbus *
  page169_i123
#CELL
  pure_quanta q_cap_diffbus *
  page169_i124
#CELL
  pure_quanta q_cap_diffbus *
  page169_i125
#CELL
  pure_quanta q_cap_diffbus *
  page169_i126
#CELL
  pure_quanta q_cap_diffbus *
  page169_i127
#CELL
  pure_quanta q_cap_diffbus *
  page169_i128
#ISCELL
  standard tap *
  page169_i129
#ISCELL
  standard tap *
  page169_i13
#ISCELL
  standard tap *
  page169_i130
#ISCELL
  standard tap *
  page169_i131
#ISCELL
  standard tap *
  page169_i132
#ISCELL
  standard tap *
  page169_i133
#ISCELL
  standard tap *
  page169_i134
#ISCELL
  standard tap *
  page169_i135
#ISCELL
  standard tap *
  page169_i136
#ISCELL
  standard tap *
  page169_i137
#ISCELL
  standard tap *
  page169_i138
#ISCELL
  standard tap *
  page169_i139
#ISCELL
  standard tap *
  page169_i14
#ISCELL
  standard tap *
  page169_i140
#ISCELL
  standard tap *
  page169_i141
#ISCELL
  standard tap *
  page169_i142
#ISCELL
  standard tap *
  page169_i143
#ISCELL
  standard tap *
  page169_i144
#ISCELL
  standard offpage *
  page169_i145
#ISCELL
  standard offpage *
  page169_i146
#ISCELL
  standard tap *
  page169_i15
#ISCELL
  standard tap *
  page169_i16
#ISCELL
  standard tap *
  page169_i17
#ISCELL
  standard tap *
  page169_i18
#ISCELL
  standard tap *
  page169_i19
#ISCELL
  standard offpage *
  page169_i2
#ISCELL
  standard tap *
  page169_i20
#CELL
  pure_quanta q_cap_diffbus *
  page169_i21
#CELL
  pure_quanta q_cap_diffbus *
  page169_i22
#CELL
  pure_quanta q_cap_diffbus *
  page169_i23
#CELL
  pure_quanta q_cap_diffbus *
  page169_i24
#CELL
  pure_quanta q_cap_diffbus *
  page169_i25
#CELL
  pure_quanta q_cap_diffbus *
  page169_i26
#CELL
  pure_quanta q_cap_diffbus *
  page169_i27
#CELL
  pure_quanta q_cap_diffbus *
  page169_i28
#CELL
  pure_quanta q_cap_diffbus *
  page169_i29
#CELL
  pure_quanta q_cap_diffbus *
  page169_i30
#CELL
  pure_quanta q_cap_diffbus *
  page169_i31
#CELL
  pure_quanta q_cap_diffbus *
  page169_i32
#CELL
  pure_quanta q_cap_diffbus *
  page169_i33
#CELL
  pure_quanta q_cap_diffbus *
  page169_i34
#CELL
  pure_quanta q_cap_diffbus *
  page169_i35
#CELL
  pure_quanta q_cap_diffbus *
  page169_i36
#ISCELL
  standard tap *
  page169_i5
#ISCELL
  standard tap *
  page169_i6
#ISCELL
  standard tap *
  page169_i7
#ISCELL
  standard tap *
  page169_i76
#ISCELL
  standard tap *
  page169_i77
#ISCELL
  standard tap *
  page169_i78
#ISCELL
  standard tap *
  page169_i79
#ISCELL
  standard tap *
  page169_i8
#ISCELL
  standard tap *
  page169_i80
#ISCELL
  standard tap *
  page169_i81
#ISCELL
  standard tap *
  page169_i82
#ISCELL
  standard tap *
  page169_i83
#ISCELL
  standard tap *
  page169_i85
#ISCELL
  standard tap *
  page169_i86
#ISCELL
  standard tap *
  page169_i87
#ISCELL
  standard tap *
  page169_i88
#ISCELL
  standard tap *
  page169_i89
#ISCELL
  standard tap *
  page169_i9
#ISCELL
  standard tap *
  page169_i90
#ISCELL
  standard tap *
  page169_i91
#ISCELL
  standard tap *
  page169_i92
#ISCELL
  standard offpage *
  page169_i93
#ISCELL
  standard offpage *
  page169_i94
#ISCELL
  standard tap *
  page169_i95
#ISCELL
  standard tap *
  page169_i96
#ISCELL
  standard offpage *
  page169_i97
#ISCELL
  standard offpage *
  page169_i98
#ISCELL
  standard tap *
  page169_i99
#ISCELL
  logical_power bom_note *
  *
#ISCELL
  logical_power cad_note *
  *
#ISCELL
  mstr_misc dns *
  *
#ISCELL
  pure_quanta quanta_title_block_c *
  *
#ISCELL
  logical_power universal_gnd *
  page171_i1
#CELL
  pure_quanta q_cap *
  page171_i10
#ISCELL
  standard offpage *
  page171_i100
#CELL
  pure_quanta q_res *
  page171_i103
#CELL
  pure_quanta q_res *
  page171_i104
#ISCELL
  standard offpage *
  page171_i107
#ISCELL
  standard offpage *
  page171_i108
#ISCELL
  standard offpage *
  page171_i109
#CELL
  pure_quanta q_crystal *
  page171_i11
#ISCELL
  standard offpage *
  page171_i110
#ISCELL
  standard offpage *
  page171_i111
#ISCELL
  standard offpage *
  page171_i112
#ISCELL
  standard offpage *
  page171_i114
#CELL
  pure_quanta q_res *
  page171_i116
#CELL
  pure_quanta q_res *
  page171_i117
#ISCELL
  standard offpage *
  page171_i118
#ISCELL
  standard offpage *
  page171_i119
#ISCELL
  standard offpage *
  page171_i120
#CELL
  pure_quanta q_res *
  page171_i121
#CELL
  pure_quanta q_res *
  page171_i122
#ISCELL
  standard offpage *
  page171_i14
#ISCELL
  standard offpage *
  page171_i15
#ISCELL
  logical_power universal_gnd *
  page171_i16
#CELL
  pure_quanta q_cap *
  page171_i17
#ISCELL
  standard offpage *
  page171_i18
#ISCELL
  standard offpage *
  page171_i19
#ISCELL
  logical_power universal_gnd *
  page171_i5
#ISCELL
  standard offpage *
  page171_i63
#ISCELL
  standard offpage *
  page171_i64
#ISCELL
  standard offpage *
  page171_i66
#ISCELL
  standard offpage *
  page171_i67
#ISCELL
  standard offpage *
  page171_i68
#CELL
  pure_quanta q_res *
  page171_i69
#ISCELL
  logical_power universal_gnd *
  page171_i7
#CELL
  pure_quanta q_res *
  page171_i74
#CELL
  pure_quanta q_xtal_4p_13bi_24gnd *
  page171_i75
#CELL
  pure_quanta q_cap *
  page171_i76
#CELL
  pure_quanta q_cap *
  page171_i77
#CELL
  pure_quanta emmitsburg_rev0p9 *
  page171_i78
#ISCELL
  standard offpage *
  page171_i83
#ISCELL
  standard offpage *
  page171_i84
#ISCELL
  standard offpage *
  page171_i85
#ISCELL
  standard offpage *
  page171_i86
#ISCELL
  standard offpage *
  page171_i87
#ISCELL
  standard offpage *
  page171_i88
#CELL
  pure_quanta q_cap *
  page171_i89
#ISCELL
  logical_power universal_gnd *
  page171_i9
#ISCELL
  logical_power universal_gnd *
  page171_i90
#ISCELL
  standard offpage *
  page171_i91
#CELL
  pure_quanta q_res *
  page171_i92
#ISCELL
  standard offpage *
  page171_i97
#ISCELL
  standard offpage *
  page171_i98
#ISCELL
  standard offpage *
  page171_i99
#ISCELL
  logical_power cad_note *
  *
#ISCELL
  logical_power design_note *
  *
#ISCELL
  pure_quanta quanta_title_block_c *
  *
#CELL
  pure_quanta q_res *
  page172_i10
#CELL
  pure_quanta emmitsburg_rev0p9 *
  page172_i11
#ISCELL
  standard offpage *
  page172_i12
#ISCELL
  standard offpage *
  page172_i13
#ISCELL
  standard offpage *
  page172_i20
#ISCELL
  standard offpage *
  page172_i21
#ISCELL
  standard offpage *
  page172_i24
#ISCELL
  standard offpage *
  page172_i25
#ISCELL
  standard offpage *
  page172_i32
#ISCELL
  standard offpage *
  page172_i33
#ISCELL
  standard offpage *
  page172_i34
#ISCELL
  standard offpage *
  page172_i35
#ISCELL
  logical_power universal_gnd *
  page172_i9
#ISCELL
  logical_power cad_note *
  *
#ISCELL
  pure_quanta quanta_title_block_c *
  *
#CELL
  pure_quanta q_res *
  page173_i1
#ISCELL
  standard offpage *
  page173_i10
#ISCELL
  standard offpage *
  page173_i100
#ISCELL
  standard offpage *
  page173_i101
#ISCELL
  standard offpage *
  page173_i102
#ISCELL
  standard offpage *
  page173_i103
#ISCELL
  standard offpage *
  page173_i104
#ISCELL
  standard offpage *
  page173_i105
#ISCELL
  standard offpage *
  page173_i106
#ISCELL
  standard offpage *
  page173_i107
#ISCELL
  standard offpage *
  page173_i108
#ISCELL
  standard offpage *
  page173_i109
#ISCELL
  standard offpage *
  page173_i11
#CELL
  pure_quanta emmitsburg_rev0p9 *
  page173_i110
#ISCELL
  standard offpage *
  page173_i12
#ISCELL
  standard offpage *
  page173_i13
#ISCELL
  standard offpage *
  page173_i14
#ISCELL
  standard offpage *
  page173_i15
#ISCELL
  standard offpage *
  page173_i16
#ISCELL
  standard offpage *
  page173_i17
#ISCELL
  standard offpage *
  page173_i18
#ISCELL
  standard offpage *
  page173_i19
#ISCELL
  standard offpage *
  page173_i2
#ISCELL
  standard offpage *
  page173_i20
#ISCELL
  standard offpage *
  page173_i21
#ISCELL
  standard offpage *
  page173_i22
#ISCELL
  standard offpage *
  page173_i23
#ISCELL
  standard offpage *
  page173_i24
#ISCELL
  standard offpage *
  page173_i25
#ISCELL
  standard tap *
  page173_i26
#ISCELL
  standard tap *
  page173_i27
#ISCELL
  standard tap *
  page173_i28
#ISCELL
  standard offpage *
  page173_i29
#ISCELL
  standard offpage *
  page173_i3
#ISCELL
  standard offpage *
  page173_i30
#ISCELL
  standard tap *
  page173_i31
#ISCELL
  standard tap *
  page173_i32
#ISCELL
  standard tap *
  page173_i33
#ISCELL
  standard tap *
  page173_i34
#ISCELL
  standard tap *
  page173_i35
#ISCELL
  standard tap *
  page173_i36
#ISCELL
  standard tap *
  page173_i37
#ISCELL
  standard tap *
  page173_i38
#ISCELL
  standard tap *
  page173_i39
#ISCELL
  standard offpage *
  page173_i4
#ISCELL
  standard tap *
  page173_i40
#ISCELL
  standard tap *
  page173_i41
#ISCELL
  standard tap *
  page173_i42
#ISCELL
  standard tap *
  page173_i43
#ISCELL
  standard tap *
  page173_i44
#ISCELL
  standard tap *
  page173_i45
#ISCELL
  standard tap *
  page173_i46
#ISCELL
  standard tap *
  page173_i47
#ISCELL
  standard tap *
  page173_i48
#ISCELL
  standard tap *
  page173_i49
#ISCELL
  standard offpage *
  page173_i5
#ISCELL
  standard tap *
  page173_i50
#ISCELL
  standard tap *
  page173_i51
#ISCELL
  standard tap *
  page173_i52
#ISCELL
  standard tap *
  page173_i53
#ISCELL
  standard tap *
  page173_i54
#ISCELL
  standard tap *
  page173_i55
#ISCELL
  standard tap *
  page173_i56
#ISCELL
  standard tap *
  page173_i57
#ISCELL
  standard tap *
  page173_i58
#ISCELL
  standard tap *
  page173_i59
#ISCELL
  standard offpage *
  page173_i6
#CELL
  pure_quanta q_cap_diffbus *
  page173_i60
#CELL
  pure_quanta q_cap_diffbus *
  page173_i61
#CELL
  pure_quanta q_cap_diffbus *
  page173_i62
#CELL
  pure_quanta q_cap_diffbus *
  page173_i63
#CELL
  pure_quanta q_cap_diffbus *
  page173_i64
#CELL
  pure_quanta q_cap_diffbus *
  page173_i65
#CELL
  pure_quanta q_cap_diffbus *
  page173_i66
#CELL
  pure_quanta q_cap_diffbus *
  page173_i67
#CELL
  pure_quanta q_cap_diffbus *
  page173_i68
#CELL
  pure_quanta q_cap_diffbus *
  page173_i69
#ISCELL
  standard offpage *
  page173_i7
#CELL
  pure_quanta q_cap_diffbus *
  page173_i70
#CELL
  pure_quanta q_cap_diffbus *
  page173_i71
#CELL
  pure_quanta q_cap_diffbus *
  page173_i72
#CELL
  pure_quanta q_cap_diffbus *
  page173_i73
#CELL
  pure_quanta q_cap_diffbus *
  page173_i74
#CELL
  pure_quanta q_cap_diffbus *
  page173_i75
#CELL
  pure_quanta q_cap_diffbus *
  page173_i76
#CELL
  pure_quanta q_cap_diffbus *
  page173_i77
#CELL
  pure_quanta q_cap *
  page173_i78
#CELL
  pure_quanta q_cap_diffbus *
  page173_i79
#ISCELL
  standard offpage *
  page173_i8
#CELL
  pure_quanta q_cap *
  page173_i80
#CELL
  pure_quanta q_cap_diffbus *
  page173_i81
#CELL
  pure_quanta q_cap_diffbus *
  page173_i82
#CELL
  pure_quanta q_cap_diffbus *
  page173_i83
#ISCELL
  standard offpage *
  page173_i84
#ISCELL
  standard offpage *
  page173_i85
#ISCELL
  standard offpage *
  page173_i86
#ISCELL
  standard offpage *
  page173_i87
#ISCELL
  standard offpage *
  page173_i88
#ISCELL
  standard offpage *
  page173_i89
#ISCELL
  standard offpage *
  page173_i9
#ISCELL
  standard offpage *
  page173_i90
#ISCELL
  standard offpage *
  page173_i91
#ISCELL
  standard offpage *
  page173_i92
#ISCELL
  standard offpage *
  page173_i93
#ISCELL
  standard offpage *
  page173_i94
#ISCELL
  standard offpage *
  page173_i95
#ISCELL
  standard offpage *
  page173_i96
#ISCELL
  standard offpage *
  page173_i97
#ISCELL
  standard offpage *
  page173_i98
#ISCELL
  standard offpage *
  page173_i99
#ISCELL
  mstr_misc dns *
  *
#ISCELL
  pure_quanta quanta_title_block_c *
  *
#ISCELL
  standard offpage *
  page174_i10
#ISCELL
  standard offpage *
  page174_i11
#ISCELL
  standard offpage *
  page174_i12
#ISCELL
  standard offpage *
  page174_i17
#ISCELL
  standard offpage *
  page174_i19
#ISCELL
  standard offpage *
  page174_i20
#ISCELL
  standard offpage *
  page174_i21
#ISCELL
  standard offpage *
  page174_i22
#ISCELL
  standard offpage *
  page174_i23
#ISCELL
  standard offpage *
  page174_i24
#ISCELL
  standard offpage *
  page174_i25
#ISCELL
  standard offpage *
  page174_i26
#ISCELL
  standard offpage *
  page174_i27
#ISCELL
  standard offpage *
  page174_i28
#ISCELL
  standard offpage *
  page174_i29
#ISCELL
  standard offpage *
  page174_i3
#ISCELL
  standard offpage *
  page174_i31
#ISCELL
  standard offpage *
  page174_i32
#ISCELL
  standard offpage *
  page174_i33
#ISCELL
  standard offpage *
  page174_i34
#ISCELL
  standard offpage *
  page174_i35
#CELL
  pure_quanta emmitsburg_rev0p9 *
  page174_i36
#CELL
  pure_quanta q_res *
  page174_i37
#CELL
  pure_quanta q_res *
  page174_i38
#ISCELL
  logical_power universal_power *
  page174_i39
#ISCELL
  logical_power universal_gnd *
  page174_i40
#CELL
  pure_quanta q_res *
  page174_i41
#ISCELL
  logical_power universal_gnd *
  page174_i42
#CELL
  pure_quanta q_res *
  page174_i48
#ISCELL
  logical_power universal_power *
  page174_i49
#ISCELL
  logical_power universal_power *
  page174_i5
#CELL
  pure_quanta q_res *
  page174_i50
#ISCELL
  logical_power universal_gnd *
  page174_i51
#ISCELL
  standard offpage *
  page174_i53
#ISCELL
  standard offpage *
  page174_i54
#ISCELL
  standard offpage *
  page174_i55
#ISCELL
  standard offpage *
  page174_i56
#ISCELL
  standard offpage *
  page174_i57
#CELL
  pure_quanta q_res *
  page174_i58
#ISCELL
  standard offpage *
  page174_i59
#CELL
  pure_quanta q_res *
  page174_i60
#ISCELL
  standard offpage *
  page174_i61
#ISCELL
  standard offpage *
  page174_i62
#CELL
  pure_quanta q_res *
  page174_i63
#ISCELL
  standard offpage *
  page174_i64
#ISCELL
  standard offpage *
  page174_i65
#CELL
  pure_quanta q_res *
  page174_i66
#ISCELL
  standard offpage *
  page174_i73
#CELL
  pure_quanta q_res *
  page174_i74
#CELL
  pure_quanta q_res *
  page174_i75
#ISCELL
  logical_power universal_power *
  page174_i76
#CELL
  pure_quanta q_res *
  page174_i77
#ISCELL
  logical_power universal_power *
  page174_i78
#ISCELL
  standard offpage *
  page174_i8
#ISCELL
  logical_power universal_power *
  page174_i80
#ISCELL
  standard offpage *
  page174_i81
#CELL
  pure_quanta q_res *
  page174_i82
#ISCELL
  standard offpage *
  page174_i9
#ISCELL
  standard offpage *
  page174_i90
#ISCELL
  standard offpage *
  page174_i91
#ISCELL
  standard offpage *
  page174_i92
#ISCELL
  standard offpage *
  page174_i93
#CELL
  pure_quanta q_res *
  page174_i94
#ISCELL
  logical_power universal_gnd *
  page174_i95
#CELL
  pure_quanta q_res *
  page174_i96
#ISCELL
  logical_power universal_power *
  page174_i97
#CELL
  pure_quanta q_res *
  page174_i98
#CELL
  pure_quanta q_res *
  page174_i99
#ISCELL
  logical_power design_note *
  *
#ISCELL
  mstr_misc dns *
  *
#ISCELL
  pure_quanta quanta_title_block_c *
  *
#ISCELL
  standard offpage *
  page175_i101
#CELL
  pure_quanta q_res *
  page175_i102
#CELL
  pure_quanta q_res *
  page175_i109
#ISCELL
  standard offpage *
  page175_i110
#ISCELL
  logical_power universal_power *
  page175_i111
#CELL
  pure_quanta q_res *
  page175_i112
#ISCELL
  standard offpage *
  page175_i113
#ISCELL
  standard offpage *
  page175_i118
#ISCELL
  standard offpage *
  page175_i119
#CELL
  pure_quanta q_res *
  page175_i120
#CELL
  pure_quanta q_res *
  page175_i121
#CELL
  pure_quanta q_res *
  page175_i125
#ISCELL
  logical_power universal_gnd *
  page175_i126
#ISCELL
  standard offpage *
  page175_i131
#ISCELL
  standard offpage *
  page175_i132
#ISCELL
  standard offpage *
  page175_i134
#ISCELL
  standard offpage *
  page175_i135
#ISCELL
  standard offpage *
  page175_i136
#CELL
  pure_quanta q_res *
  page175_i137
#CELL
  pure_quanta q_res *
  page175_i138
#ISCELL
  standard offpage *
  page175_i139
#ISCELL
  standard offpage *
  page175_i140
#CELL
  pure_quanta q_res *
  page175_i141
#CELL
  pure_quanta q_res *
  page175_i142
#ISCELL
  standard offpage *
  page175_i143
#CELL
  pure_quanta q_res *
  page175_i144
#ISCELL
  standard offpage *
  page175_i145
#ISCELL
  standard offpage *
  page175_i147
#CELL
  pure_quanta q_res *
  page175_i148
#ISCELL
  standard offpage *
  page175_i15
#ISCELL
  standard offpage *
  page175_i150
#CELL
  pure_quanta q_res *
  page175_i151
#ISCELL
  standard offpage *
  page175_i16
#ISCELL
  standard offpage *
  page175_i17
#ISCELL
  standard offpage *
  page175_i175
#ISCELL
  standard offpage *
  page175_i177
#CELL
  pure_quanta q_res *
  page175_i178
#ISCELL
  standard offpage *
  page175_i18
#CELL
  pure_quanta q_res *
  page175_i180
#CELL
  pure_quanta q_res *
  page175_i181
#ISCELL
  standard offpage *
  page175_i182
#ISCELL
  standard offpage *
  page175_i183
#CELL
  pure_quanta q_res *
  page175_i188
#ISCELL
  standard offpage *
  page175_i189
#ISCELL
  standard offpage *
  page175_i19
#CELL
  pure_quanta q_res *
  page175_i193
#ISCELL
  standard offpage *
  page175_i194
#ISCELL
  standard offpage *
  page175_i195
#ISCELL
  standard offpage *
  page175_i20
#ISCELL
  standard offpage *
  page175_i209
#ISCELL
  standard offpage *
  page175_i21
#ISCELL
  standard offpage *
  page175_i210
#ISCELL
  standard offpage *
  page175_i212
#CELL
  pure_quanta q_res *
  page175_i213
#ISCELL
  standard offpage *
  page175_i22
#CELL
  pure_quanta q_res *
  page175_i222
#ISCELL
  standard offpage *
  page175_i223
#ISCELL
  logical_power universal_gnd *
  page175_i224
#CELL
  pure_quanta q_res *
  page175_i225
#ISCELL
  standard offpage *
  page175_i227
#ISCELL
  standard offpage *
  page175_i228
#ISCELL
  standard offpage *
  page175_i229
#ISCELL
  standard offpage *
  page175_i23
#ISCELL
  standard offpage *
  page175_i230
#CELL
  pure_quanta q_res *
  page175_i234
#ISCELL
  standard offpage *
  page175_i235
#CELL
  pure_quanta q_res *
  page175_i236
#ISCELL
  standard offpage *
  page175_i237
#ISCELL
  standard offpage *
  page175_i238
#CELL
  pure_quanta q_res *
  page175_i239
#ISCELL
  standard offpage *
  page175_i24
#ISCELL
  standard offpage *
  page175_i240
#CELL
  pure_quanta q_res *
  page175_i241
#ISCELL
  standard offpage *
  page175_i246
#ISCELL
  standard offpage *
  page175_i247
#ISCELL
  standard offpage *
  page175_i248
#ISCELL
  standard offpage *
  page175_i249
#ISCELL
  standard offpage *
  page175_i25
#ISCELL
  standard offpage *
  page175_i250
#ISCELL
  standard offpage *
  page175_i252
#CELL
  pure_quanta q_res *
  page175_i253
#CELL
  pure_quanta conn3_210hp1030br1 *
  page175_i256
#ISCELL
  logical_power universal_gnd *
  page175_i257
#ISCELL
  standard offpage *
  page175_i258
#ISCELL
  standard offpage *
  page175_i259
#ISCELL
  standard offpage *
  page175_i26
#ISCELL
  logical_power universal_gnd *
  page175_i260
#ISCELL
  standard offpage *
  page175_i261
#ISCELL
  standard offpage *
  page175_i262
#CELL
  pure_quanta conn3_210hp1030br1 *
  page175_i263
#ISCELL
  standard offpage *
  page175_i268
#ISCELL
  standard offpage *
  page175_i269
#ISCELL
  standard offpage *
  page175_i27
#ISCELL
  standard offpage *
  page175_i271
#CELL
  pure_quanta q_res *
  page175_i272
#ISCELL
  standard offpage *
  page175_i273
#CELL
  pure_quanta q_res *
  page175_i274
#CELL
  pure_quanta q_res *
  page175_i275
#ISCELL
  standard offpage *
  page175_i276
#ISCELL
  standard offpage *
  page175_i277
#ISCELL
  standard offpage *
  page175_i278
#ISCELL
  standard offpage *
  page175_i279
#ISCELL
  standard offpage *
  page175_i28
#ISCELL
  standard offpage *
  page175_i280
#ISCELL
  standard offpage *
  page175_i281
#ISCELL
  standard offpage *
  page175_i282
#CELL
  pure_quanta q_res *
  page175_i284
#CELL
  pure_quanta q_res *
  page175_i285
#CELL
  pure_quanta q_res *
  page175_i286
#CELL
  pure_quanta q_res *
  page175_i287
#CELL
  pure_quanta q_res *
  page175_i288
#ISCELL
  logical_power universal_gnd *
  page175_i289
#ISCELL
  standard offpage *
  page175_i29
#ISCELL
  standard offpage *
  page175_i290
#ISCELL
  standard offpage *
  page175_i291
#ISCELL
  standard offpage *
  page175_i292
#ISCELL
  standard offpage *
  page175_i293
#ISCELL
  standard offpage *
  page175_i294
#ISCELL
  standard offpage *
  page175_i295
#ISCELL
  standard offpage *
  page175_i296
#ISCELL
  standard offpage *
  page175_i297
#CELL
  pure_quanta q_res *
  page175_i298
#CELL
  pure_quanta q_res *
  page175_i299
#ISCELL
  standard offpage *
  page175_i30
#CELL
  pure_quanta q_res *
  page175_i300
#ISCELL
  standard offpage *
  page175_i302
#ISCELL
  standard offpage *
  page175_i303
#ISCELL
  standard offpage *
  page175_i304
#CELL
  pure_quanta q_res *
  page175_i305
#ISCELL
  standard offpage *
  page175_i306
#ISCELL
  standard offpage *
  page175_i307
#CELL
  pure_quanta q_res *
  page175_i308
#ISCELL
  standard offpage *
  page175_i309
#ISCELL
  standard offpage *
  page175_i31
#ISCELL
  standard offpage *
  page175_i310
#ISCELL
  standard offpage *
  page175_i311
#ISCELL
  standard offpage *
  page175_i312
#CELL
  pure_quanta q_res *
  page175_i314
#CELL
  pure_quanta q_res *
  page175_i315
#ISCELL
  standard offpage *
  page175_i317
#ISCELL
  standard offpage *
  page175_i32
#ISCELL
  standard offpage *
  page175_i33
#ISCELL
  standard offpage *
  page175_i36
#ISCELL
  standard offpage *
  page175_i37
#ISCELL
  standard offpage *
  page175_i38
#ISCELL
  standard offpage *
  page175_i39
#ISCELL
  standard offpage *
  page175_i40
#ISCELL
  standard offpage *
  page175_i41
#ISCELL
  standard offpage *
  page175_i42
#ISCELL
  standard offpage *
  page175_i43
#ISCELL
  standard offpage *
  page175_i44
#ISCELL
  standard offpage *
  page175_i45
#ISCELL
  standard offpage *
  page175_i46
#ISCELL
  standard offpage *
  page175_i49
#ISCELL
  standard offpage *
  page175_i50
#ISCELL
  standard offpage *
  page175_i51
#ISCELL
  standard offpage *
  page175_i53
#ISCELL
  standard offpage *
  page175_i56
#ISCELL
  standard offpage *
  page175_i57
#ISCELL
  standard offpage *
  page175_i58
#ISCELL
  standard offpage *
  page175_i60
#ISCELL
  standard offpage *
  page175_i62
#ISCELL
  standard offpage *
  page175_i67
#ISCELL
  standard offpage *
  page175_i68
#ISCELL
  standard offpage *
  page175_i70
#ISCELL
  standard offpage *
  page175_i71
#ISCELL
  standard offpage *
  page175_i72
#ISCELL
  standard offpage *
  page175_i73
#ISCELL
  standard offpage *
  page175_i74
#ISCELL
  standard offpage *
  page175_i75
#ISCELL
  standard offpage *
  page175_i76
#ISCELL
  standard offpage *
  page175_i77
#ISCELL
  standard offpage *
  page175_i78
#ISCELL
  standard offpage *
  page175_i79
#ISCELL
  standard offpage *
  page175_i80
#ISCELL
  standard offpage *
  page175_i81
#ISCELL
  standard offpage *
  page175_i83
#ISCELL
  standard offpage *
  page175_i85
#ISCELL
  standard offpage *
  page175_i86
#ISCELL
  standard offpage *
  page175_i87
#ISCELL
  standard offpage *
  page175_i88
#ISCELL
  standard offpage *
  page175_i89
#ISCELL
  standard offpage *
  page175_i90
#ISCELL
  standard offpage *
  page175_i91
#ISCELL
  standard offpage *
  page175_i92
#CELL
  pure_quanta emmitsburg_rev0p9 *
  page175_i93
#ISCELL
  standard offpage *
  page175_i99
#ISCELL
  logical_power design_note *
  *
#ISCELL
  mstr_misc dns *
  *
#ISCELL
  pure_quanta quanta_title_block_c *
  *
#ISCELL
  standard offpage *
  page176_i10
#ISCELL
  standard offpage *
  page176_i11
#ISCELL
  standard offpage *
  page176_i118
#ISCELL
  standard offpage *
  page176_i119
#ISCELL
  standard offpage *
  page176_i155
#ISCELL
  standard offpage *
  page176_i156
#ISCELL
  standard offpage *
  page176_i157
#ISCELL
  standard offpage *
  page176_i16
#ISCELL
  logical_power universal_gnd *
  page176_i161
#ISCELL
  logical_power universal_gnd *
  page176_i163
#ISCELL
  logical_power universal_power *
  page176_i168
#ISCELL
  standard offpage *
  page176_i17
#ISCELL
  standard offpage *
  page176_i171
#ISCELL
  standard offpage *
  page176_i172
#CELL
  pure_quanta q_res *
  page176_i173
#CELL
  pure_quanta q_res *
  page176_i174
#CELL
  pure_quanta q_res *
  page176_i175
#CELL
  pure_quanta q_res *
  page176_i176
#ISCELL
  standard offpage *
  page176_i177
#ISCELL
  standard offpage *
  page176_i179
#ISCELL
  standard offpage *
  page176_i180
#ISCELL
  standard offpage *
  page176_i181
#CELL
  pure_quanta q_res *
  page176_i183
#CELL
  pure_quanta q_res *
  page176_i184
#CELL
  pure_quanta q_res *
  page176_i185
#CELL
  pure_quanta q_res *
  page176_i186
#ISCELL
  standard offpage *
  page176_i188
#ISCELL
  standard offpage *
  page176_i189
#ISCELL
  standard offpage *
  page176_i190
#ISCELL
  standard offpage *
  page176_i191
#CELL
  pure_quanta q_res *
  page176_i195
#CELL
  pure_quanta q_res *
  page176_i196
#CELL
  pure_quanta q_res *
  page176_i197
#ISCELL
  standard offpage *
  page176_i198
#ISCELL
  standard offpage *
  page176_i199
#ISCELL
  standard offpage *
  page176_i2
#ISCELL
  standard offpage *
  page176_i20
#ISCELL
  standard offpage *
  page176_i200
#CELL
  pure_quanta q_res *
  page176_i201
#CELL
  pure_quanta q_res *
  page176_i202
#CELL
  pure_quanta q_res *
  page176_i203
#CELL
  pure_quanta q_res *
  page176_i204
#CELL
  pure_quanta q_res *
  page176_i205
#CELL
  pure_quanta q_res *
  page176_i206
#CELL
  pure_quanta q_res *
  page176_i207
#ISCELL
  logical_power universal_gnd *
  page176_i208
#CELL
  pure_quanta q_res *
  page176_i209
#ISCELL
  standard offpage *
  page176_i21
#ISCELL
  standard offpage *
  page176_i210
#ISCELL
  standard offpage *
  page176_i211
#ISCELL
  standard offpage *
  page176_i212
#ISCELL
  standard offpage *
  page176_i213
#ISCELL
  standard offpage *
  page176_i214
#ISCELL
  standard offpage *
  page176_i215
#ISCELL
  standard offpage *
  page176_i216
#ISCELL
  standard offpage *
  page176_i217
#CELL
  pure_quanta emmitsburg_rev0p9 *
  page176_i22
#ISCELL
  standard offpage *
  page176_i225
#ISCELL
  standard offpage *
  page176_i226
#ISCELL
  standard offpage *
  page176_i227
#ISCELL
  standard offpage *
  page176_i228
#ISCELL
  standard offpage *
  page176_i229
#ISCELL
  standard offpage *
  page176_i23
#ISCELL
  standard offpage *
  page176_i230
#ISCELL
  standard offpage *
  page176_i231
#ISCELL
  standard offpage *
  page176_i232
#ISCELL
  standard offpage *
  page176_i233
#ISCELL
  standard offpage *
  page176_i234
#ISCELL
  standard offpage *
  page176_i235
#ISCELL
  standard offpage *
  page176_i237
#ISCELL
  standard offpage *
  page176_i238
#CELL
  pure_quanta q_res *
  page176_i239
#ISCELL
  standard offpage *
  page176_i24
#CELL
  pure_quanta q_res *
  page176_i240
#ISCELL
  standard offpage *
  page176_i243
#ISCELL
  standard offpage *
  page176_i244
#ISCELL
  standard offpage *
  page176_i245
#CELL
  pure_quanta q_res *
  page176_i246
#ISCELL
  logical_power universal_power *
  page176_i247
#ISCELL
  standard offpage *
  page176_i248
#ISCELL
  standard offpage *
  page176_i25
#ISCELL
  standard offpage *
  page176_i26
#ISCELL
  standard offpage *
  page176_i31
#ISCELL
  standard offpage *
  page176_i32
#ISCELL
  standard offpage *
  page176_i34
#ISCELL
  standard offpage *
  page176_i39
#ISCELL
  standard offpage *
  page176_i40
#ISCELL
  standard offpage *
  page176_i41
#ISCELL
  standard offpage *
  page176_i42
#ISCELL
  standard offpage *
  page176_i43
#ISCELL
  standard offpage *
  page176_i44
#ISCELL
  standard offpage *
  page176_i46
#ISCELL
  standard offpage *
  page176_i47
#ISCELL
  standard offpage *
  page176_i48
#ISCELL
  standard offpage *
  page176_i53
#ISCELL
  standard offpage *
  page176_i75
#ISCELL
  standard offpage *
  page176_i76
#ISCELL
  standard offpage *
  page176_i94
#ISCELL
  standard offpage *
  page176_i95
#ISCELL
  mstr_misc dns *
  *
#ISCELL
  pure_quanta quanta_title_block_c *
  *
#CELL
  pure_quanta q_res *
  page177_i100
#CELL
  pure_quanta q_res *
  page177_i102
#CELL
  pure_quanta q_res *
  page177_i106
#ISCELL
  standard offpage *
  page177_i108
#ISCELL
  standard offpage *
  page177_i110
#ISCELL
  standard offpage *
  page177_i111
#ISCELL
  standard offpage *
  page177_i112
#ISCELL
  standard offpage *
  page177_i113
#ISCELL
  standard offpage *
  page177_i114
#ISCELL
  standard offpage *
  page177_i115
#ISCELL
  logical_power universal_power *
  page177_i116
#ISCELL
  standard offpage *
  page177_i117
#CELL
  pure_quanta q_res *
  page177_i118
#CELL
  pure_quanta q_res *
  page177_i119
#ISCELL
  standard offpage *
  page177_i12
#CELL
  pure_quanta q_res *
  page177_i120
#CELL
  pure_quanta q_res *
  page177_i121
#ISCELL
  standard offpage *
  page177_i122
#CELL
  pure_quanta mosfet_nch_gds_esd_protected *
  page177_i123
#CELL
  pure_quanta mosfet_nch_gds_esd_protected *
  page177_i124
#CELL
  pure_quanta q_res *
  page177_i125
#ISCELL
  logical_power universal_gnd *
  page177_i126
#CELL
  pure_quanta q_res *
  page177_i127
#ISCELL
  logical_power universal_gnd *
  page177_i128
#ISCELL
  standard offpage *
  page177_i13
#ISCELL
  standard offpage *
  page177_i15
#ISCELL
  standard offpage *
  page177_i16
#ISCELL
  standard offpage *
  page177_i18
#ISCELL
  standard offpage *
  page177_i19
#ISCELL
  standard offpage *
  page177_i2
#ISCELL
  standard offpage *
  page177_i21
#ISCELL
  standard offpage *
  page177_i22
#ISCELL
  standard offpage *
  page177_i23
#CELL
  pure_quanta q_res *
  page177_i24
#ISCELL
  logical_power universal_power *
  page177_i25
#CELL
  pure_quanta emmitsburg_rev0p9 *
  page177_i27
#ISCELL
  standard offpage *
  page177_i3
#ISCELL
  standard offpage *
  page177_i33
#ISCELL
  standard offpage *
  page177_i34
#ISCELL
  standard offpage *
  page177_i35
#ISCELL
  standard offpage *
  page177_i39
#ISCELL
  logical_power universal_power *
  page177_i53
#ISCELL
  logical_power universal_power *
  page177_i56
#ISCELL
  standard offpage *
  page177_i57
#ISCELL
  logical_power universal_power *
  page177_i59
#CELL
  pure_quanta q_res *
  page177_i62
#CELL
  pure_quanta conn2_aaabat029y19 *
  page177_i63
#CELL
  pure_quanta bas70057f *
  page177_i64
#CELL
  pure_quanta q_cap *
  page177_i65
#ISCELL
  logical_power universal_gnd *
  page177_i66
#ISCELL
  logical_power universal_gnd *
  page177_i67
#CELL
  pure_quanta q_cap *
  page177_i68
#ISCELL
  logical_power universal_gnd *
  page177_i69
#CELL
  pure_quanta q_res *
  page177_i70
#ISCELL
  standard offpage *
  page177_i71
#ISCELL
  standard offpage *
  page177_i73
#ISCELL
  standard offpage *
  page177_i74
#ISCELL
  standard offpage *
  page177_i75
#ISCELL
  standard offpage *
  page177_i76
#ISCELL
  standard offpage *
  page177_i78
#ISCELL
  standard offpage *
  page177_i79
#CELL
  pure_quanta q_res *
  page177_i80
#ISCELL
  standard offpage *
  page177_i82
#ISCELL
  logical_power universal_gnd *
  page177_i83
#ISCELL
  standard offpage *
  page177_i84
#CELL
  pure_quanta q_res *
  page177_i85
#ISCELL
  standard offpage *
  page177_i87
#ISCELL
  logical_power universal_gnd *
  page177_i88
#CELL
  pure_quanta q_res *
  page177_i89
#ISCELL
  standard offpage *
  page177_i90
#ISCELL
  standard offpage *
  page177_i92
#ISCELL
  standard offpage *
  page177_i93
#ISCELL
  standard offpage *
  page177_i95
#ISCELL
  standard offpage *
  page177_i96
#ISCELL
  standard offpage *
  page177_i97
#ISCELL
  standard offpage *
  page177_i98
#ISCELL
  standard offpage *
  page177_i99
#ISCELL
  pure_quanta quanta_title_block_c *
  *
#ISCELL
  logical_power universal_power *
  page178_i10
#CELL
  pure_quanta emmitsburg_rev0p9 *
  page178_i11
#ISCELL
  logical_power universal_power *
  page178_i17
#ISCELL
  logical_power universal_gnd *
  page178_i18
#ISCELL
  logical_power universal_power *
  page178_i2
#ISCELL
  logical_power universal_power *
  page178_i5
#ISCELL
  logical_power universal_power *
  page178_i6
#ISCELL
  logical_power universal_power *
  page178_i7
#ISCELL
  logical_power universal_power *
  page178_i8
#ISCELL
  logical_power universal_power *
  page178_i9
#ISCELL
  pure_quanta quanta_title_block_c *
  *
#CELL
  pure_quanta q_res *
  page179_i2
#ISCELL
  logical_power universal_gnd *
  page179_i3
#CELL
  pure_quanta emmitsburg_rev0p9 *
  page179_i4
#ISCELL
  pure_quanta quanta_title_block_c *
  *
#ISCELL
  logical_power universal_gnd *
  page180_i10
#ISCELL
  logical_power universal_gnd *
  page180_i2
#ISCELL
  logical_power universal_gnd *
  page180_i5
#CELL
  pure_quanta emmitsburg_rev0p9 *
  page180_i7
#ISCELL
  logical_power universal_gnd *
  page180_i8
#CELL
  pure_quanta emmitsburg_rev0p9 *
  page180_i9
#ISCELL
  mstr_misc dns *
  *
#ISCELL
  pure_quanta quanta_title_block_c *
  *
#ISCELL
  logical_power universal_power *
  page181_i103
#CELL
  pure_quanta q_cap *
  page181_i104
#ISCELL
  logical_power universal_gnd *
  page181_i106
#ISCELL
  logical_power universal_power *
  page181_i108
#ISCELL
  logical_power universal_power *
  page181_i11
#CELL
  pure_quanta q_cap *
  page181_i110
#CELL
  pure_quanta q_cap *
  page181_i111
#ISCELL
  logical_power universal_gnd *
  page181_i113
#ISCELL
  logical_power universal_gnd *
  page181_i114
#ISCELL
  logical_power universal_power *
  page181_i115
#ISCELL
  logical_power universal_gnd *
  page181_i117
#ISCELL
  logical_power universal_power *
  page181_i118
#CELL
  pure_quanta q_cap *
  page181_i119
#CELL
  pure_quanta q_cap *
  page181_i12
#ISCELL
  logical_power universal_gnd *
  page181_i122
#CELL
  pure_quanta q_cap *
  page181_i123
#ISCELL
  logical_power universal_power *
  page181_i124
#CELL
  pure_quanta q_cap *
  page181_i125
#ISCELL
  logical_power universal_gnd *
  page181_i126
#CELL
  pure_quanta q_cap *
  page181_i127
#ISCELL
  logical_power universal_power *
  page181_i128
#CELL
  pure_quanta q_res *
  page181_i129
#CELL
  pure_quanta q_cap *
  page181_i13
#ISCELL
  logical_power universal_power *
  page181_i130
#CELL
  pure_quanta q_cap *
  page181_i131
#ISCELL
  logical_power universal_gnd *
  page181_i132
#CELL
  pure_quanta q_cap *
  page181_i133
#ISCELL
  logical_power universal_gnd *
  page181_i134
#CELL
  pure_quanta q_cap *
  page181_i136
#CELL
  pure_quanta q_cap *
  page181_i137
#ISCELL
  logical_power universal_power *
  page181_i138
#ISCELL
  logical_power universal_power *
  page181_i139
#ISCELL
  logical_power universal_gnd *
  page181_i14
#CELL
  pure_quanta q_cap *
  page181_i140
#ISCELL
  logical_power universal_gnd *
  page181_i141
#CELL
  pure_quanta q_cap *
  page181_i142
#ISCELL
  logical_power universal_gnd *
  page181_i143
#CELL
  pure_quanta q_res *
  page181_i144
#CELL
  pure_quanta q_inductor *
  page181_i145
#CELL
  pure_quanta q_cap *
  page181_i146
#CELL
  pure_quanta q_cap *
  page181_i147
#ISCELL
  logical_power universal_power *
  page181_i148
#ISCELL
  logical_power universal_power *
  page181_i149
#ISCELL
  logical_power universal_power *
  page181_i150
#CELL
  pure_quanta q_cap *
  page181_i151
#CELL
  pure_quanta q_cap *
  page181_i152
#CELL
  pure_quanta q_cap *
  page181_i153
#CELL
  pure_quanta q_cap *
  page181_i154
#CELL
  pure_quanta q_cap *
  page181_i155
#CELL
  pure_quanta q_cap *
  page181_i156
#CELL
  pure_quanta q_cap *
  page181_i157
#CELL
  pure_quanta q_cap *
  page181_i158
#CELL
  pure_quanta q_cap *
  page181_i159
#CELL
  pure_quanta q_cap *
  page181_i162
#CELL
  pure_quanta q_cap *
  page181_i163
#CELL
  pure_quanta q_inductor *
  page181_i164
#CELL
  pure_quanta q_res *
  page181_i165
#ISCELL
  logical_power universal_gnd *
  page181_i18
#ISCELL
  logical_power universal_power *
  page181_i20
#CELL
  pure_quanta q_cap *
  page181_i25
#ISCELL
  logical_power universal_power *
  page181_i26
#CELL
  pure_quanta q_cap *
  page181_i27
#ISCELL
  logical_power universal_gnd *
  page181_i28
#CELL
  pure_quanta q_cap *
  page181_i29
#CELL
  pure_quanta q_cap *
  page181_i30
#ISCELL
  logical_power universal_power *
  page181_i31
#CELL
  pure_quanta q_cap *
  page181_i32
#ISCELL
  logical_power universal_gnd *
  page181_i33
#ISCELL
  logical_power universal_power *
  page181_i4
#CELL
  pure_quanta q_cap *
  page181_i40
#ISCELL
  logical_power universal_power *
  page181_i41
#CELL
  pure_quanta q_cap *
  page181_i42
#CELL
  pure_quanta q_cap *
  page181_i43
#ISCELL
  logical_power universal_gnd *
  page181_i44
#CELL
  pure_quanta q_cap *
  page181_i45
#CELL
  pure_quanta q_cap *
  page181_i48
#CELL
  pure_quanta q_cap *
  page181_i49
#ISCELL
  logical_power universal_gnd *
  page181_i5
#ISCELL
  logical_power universal_gnd *
  page181_i50
#CELL
  pure_quanta q_cap *
  page181_i51
#CELL
  pure_quanta q_cap *
  page181_i58
#CELL
  pure_quanta q_cap *
  page181_i59
#CELL
  pure_quanta q_cap *
  page181_i6
#CELL
  pure_quanta q_cap *
  page181_i60
#CELL
  pure_quanta q_cap *
  page181_i61
#CELL
  pure_quanta q_cap *
  page181_i63
#ISCELL
  logical_power universal_gnd *
  page181_i64
#ISCELL
  logical_power universal_gnd *
  page181_i68
#CELL
  pure_quanta q_cap *
  page181_i7
#CELL
  pure_quanta q_cap *
  page181_i78
#CELL
  pure_quanta q_cap *
  page181_i8
#CELL
  pure_quanta q_cap *
  page181_i87
#ISCELL
  logical_power universal_gnd *
  page181_i88
#CELL
  pure_quanta q_cap *
  page181_i89
#ISCELL
  logical_power universal_power *
  page181_i90
#CELL
  pure_quanta q_cap *
  page181_i91
#ISCELL
  logical_power universal_gnd *
  page181_i92
#ISCELL
  logical_power universal_gnd *
  page181_i93
#ISCELL
  logical_power universal_power *
  page181_i94
#ISCELL
  logical_power universal_power *
  page181_i95
#ISCELL
  logical_power universal_power *
  page181_i99
#ISCELL
  logical_power bom_note *
  *
#ISCELL
  logical_power design_note *
  *
#ISCELL
  mstr_misc dns *
  *
#ISCELL
  pure_quanta quanta_title_block_c *
  *
#CELL
  pure_quanta q_cap *
  page182_i100
#CELL
  pure_quanta q_res *
  page182_i105
#ISCELL
  logical_power universal_gnd *
  page182_i106
#ISCELL
  standard offpage *
  page182_i107
#ISCELL
  standard offpage *
  page182_i108
#ISCELL
  standard offpage *
  page182_i120
#ISCELL
  standard offpage *
  page182_i123
#ISCELL
  standard offpage *
  page182_i124
#ISCELL
  standard offpage *
  page182_i125
#ISCELL
  standard tap *
  page182_i136
#ISCELL
  standard tap *
  page182_i137
#ISCELL
  standard tap *
  page182_i146
#ISCELL
  standard tap *
  page182_i147
#ISCELL
  standard tap *
  page182_i150
#ISCELL
  standard tap *
  page182_i151
#ISCELL
  standard offpage *
  page182_i154
#ISCELL
  standard offpage *
  page182_i155
#ISCELL
  standard offpage *
  page182_i158
#ISCELL
  standard offpage *
  page182_i159
#ISCELL
  standard offpage *
  page182_i160
#ISCELL
  standard offpage *
  page182_i161
#CELL
  pure_quanta q_res *
  page182_i162
#ISCELL
  standard offpage *
  page182_i163
#CELL
  pure_quanta q_res *
  page182_i164
#ISCELL
  logical_power universal_gnd *
  page182_i165
#CELL
  pure_quanta q_res *
  page182_i167
#ISCELL
  logical_power universal_gnd *
  page182_i172
#CELL
  pure_quanta q_res *
  page182_i173
#ISCELL
  logical_power universal_power *
  page182_i174
#ISCELL
  standard offpage *
  page182_i175
#CELL
  pure_quanta q_res *
  page182_i176
#ISCELL
  logical_power universal_power *
  page182_i177
#CELL
  pure_quanta sconn75k_apci0155p004a *
  page182_i178
#ISCELL
  standard offpage *
  page182_i231
#ISCELL
  standard tap *
  page182_i233
#ISCELL
  standard tap *
  page182_i234
#ISCELL
  standard tap *
  page182_i235
#ISCELL
  standard tap *
  page182_i236
#ISCELL
  standard tap *
  page182_i237
#ISCELL
  standard tap *
  page182_i238
#ISCELL
  standard offpage *
  page182_i244
#ISCELL
  standard offpage *
  page182_i245
#CELL
  pure_quanta q_res *
  page182_i247
#ISCELL
  standard offpage *
  page182_i248
#ISCELL
  logical_power universal_power *
  page182_i249
#ISCELL
  standard offpage *
  page182_i250
#ISCELL
  standard offpage *
  page182_i296
#CELL
  pure_quanta q_res *
  page182_i299
#ISCELL
  logical_power universal_power *
  page182_i300
#ISCELL
  logical_power universal_gnd *
  page182_i301
#ISCELL
  standard offpage *
  page182_i302
#CELL
  pure_quanta q_res *
  page182_i303
#ISCELL
  logical_power universal_gnd *
  page182_i304
#ISCELL
  logical_power universal_power *
  page182_i305
#CELL
  pure_quanta q_res *
  page182_i306
#ISCELL
  logical_power universal_power *
  page182_i307
#CELL
  pure_quanta q_cap *
  page182_i308
#ISCELL
  logical_power universal_gnd *
  page182_i309
#ISCELL
  logical_power universal_gnd *
  page182_i310
#ISCELL
  standard offpage *
  page182_i311
#CELL
  pure_quanta q_res *
  page182_i312
#ISCELL
  logical_power universal_gnd *
  page182_i313
#CELL
  pure_quanta 74lvc1g126se7 *
  page182_i315
#CELL
  pure_quanta q_res *
  page182_i317
#ISCELL
  standard offpage *
  page182_i318
#CELL
  pure_quanta q_res *
  page182_i320
#ISCELL
  standard offpage *
  page182_i322
#ISCELL
  logical_power universal_power *
  page182_i323
#CELL
  pure_quanta q_res *
  page182_i324
#ISCELL
  logical_power universal_power *
  page182_i325
#CELL
  pure_quanta q_cap *
  page182_i326
#CELL
  pure_quanta sn74lvc2g07dckr *
  page182_i327
#ISCELL
  logical_power universal_gnd *
  page182_i328
#ISCELL
  standard offpage *
  page182_i329
#ISCELL
  standard offpage *
  page182_i336
#CELL
  pure_quanta q_res *
  page182_i337
#ISCELL
  logical_power universal_power *
  page182_i338
#ISCELL
  standard offpage *
  page182_i340
#ISCELL
  logical_power universal_power *
  page182_i341
#CELL
  pure_quanta mosfet_nch_dual *
  page182_i342
#CELL
  pure_quanta mosfet_nch_dual *
  page182_i343
#CELL
  pure_quanta q_res *
  page182_i344
#CELL
  pure_quanta q_cap *
  page182_i88
#ISCELL
  logical_power universal_power *
  page182_i89
#CELL
  pure_quanta q_cap *
  page182_i90
#CELL
  pure_quanta q_cap *
  page182_i96
#CELL
  pure_quanta q_cap *
  page182_i97
#CELL
  pure_quanta q_cap *
  page182_i98
#ISCELL
  logical_power universal_gnd *
  page182_i99
#ISCELL
  logical_power cad_note *
  *
#ISCELL
  logical_power design_note *
  *
#ISCELL
  mstr_misc dns *
  *
#ISCELL
  pure_quanta quanta_title_block_c *
  *
#ISCELL
  standard offpage *
  page297_i156
#CELL
  pure_quanta q_res *
  page297_i157
#ISCELL
  standard offpage *
  page297_i158
#CELL
  pure_quanta q_res *
  page297_i159
#ISCELL
  logical_power universal_power *
  page297_i160
#CELL
  pure_quanta 74lvc1g126se7 *
  page297_i163
#ISCELL
  logical_power universal_gnd *
  page297_i164
#CELL
  pure_quanta q_res *
  page297_i165
#ISCELL
  logical_power universal_gnd *
  page297_i166
#ISCELL
  standard offpage *
  page297_i167
#ISCELL
  logical_power universal_power *
  page297_i168
#CELL
  pure_quanta q_res *
  page297_i169
#CELL
  pure_quanta q_cap *
  page297_i170
#ISCELL
  logical_power universal_gnd *
  page297_i171
#ISCELL
  logical_power universal_power *
  page297_i172
#CELL
  pure_quanta q_cap *
  page297_i237
#ISCELL
  logical_power universal_power *
  page297_i238
#ISCELL
  standard offpage *
  page297_i240
#ISCELL
  standard offpage *
  page297_i241
#ISCELL
  logical_power universal_power *
  page297_i242
#ISCELL
  standard offpage *
  page297_i244
#CELL
  pure_quanta q_cap *
  page297_i245
#ISCELL
  logical_power universal_power *
  page297_i246
#CELL
  pure_quanta q_cap *
  page297_i247
#ISCELL
  logical_power universal_gnd *
  page297_i248
#ISCELL
  logical_power universal_gnd *
  page297_i250
#ISCELL
  standard offpage *
  page297_i251
#CELL
  pure_quanta q_cap *
  page297_i252
#ISCELL
  logical_power universal_gnd *
  page297_i253
#ISCELL
  standard offpage *
  page297_i254
#ISCELL
  standard offpage *
  page297_i255
#ISCELL
  standard offpage *
  page297_i256
#ISCELL
  standard offpage *
  page297_i257
#CELL
  pure_quanta q_cap *
  page297_i258
#ISCELL
  logical_power universal_power *
  page297_i259
#CELL
  pure_quanta q_cap *
  page297_i260
#ISCELL
  logical_power universal_power *
  page297_i261
#ISCELL
  logical_power universal_power *
  page297_i262
#ISCELL
  logical_power universal_power *
  page297_i263
#CELL
  pure_quanta q_res *
  page297_i264
#ISCELL
  standard tap *
  page297_i267
#ISCELL
  standard tap *
  page297_i268
#ISCELL
  standard tap *
  page297_i269
#ISCELL
  standard tap *
  page297_i270
#ISCELL
  standard tap *
  page297_i271
#ISCELL
  standard tap *
  page297_i272
#ISCELL
  logical_power universal_gnd *
  page297_i273
#ISCELL
  logical_power universal_gnd *
  page297_i275
#ISCELL
  standard tap *
  page297_i278
#ISCELL
  standard tap *
  page297_i280
#ISCELL
  standard tap *
  page297_i281
#ISCELL
  standard tap *
  page297_i283
#ISCELL
  standard offpage *
  page297_i285
#ISCELL
  standard offpage *
  page297_i286
#ISCELL
  standard offpage *
  page297_i287
#ISCELL
  standard offpage *
  page297_i288
#ISCELL
  standard offpage *
  page297_i289
#ISCELL
  logical_power universal_power *
  page297_i290
#CELL
  pure_quanta q_res *
  page297_i291
#ISCELL
  standard offpage *
  page297_i292
#CELL
  pure_quanta q_res *
  page297_i293
#ISCELL
  logical_power universal_gnd *
  page297_i294
#ISCELL
  logical_power universal_power *
  page297_i295
#CELL
  pure_quanta q_res *
  page297_i296
#ISCELL
  standard offpage *
  page297_i297
#ISCELL
  standard offpage *
  page297_i298
#CELL
  pure_quanta q_res *
  page297_i299
#ISCELL
  logical_power universal_power *
  page297_i300
#CELL
  pure_quanta q_res *
  page297_i301
#CELL
  pure_quanta q_res *
  page297_i302
#ISCELL
  logical_power universal_gnd *
  page297_i303
#CELL
  pure_quanta q_cap *
  page297_i304
#CELL
  pure_quanta 74lvc2g07dw7 *
  page297_i305
#ISCELL
  logical_power universal_gnd *
  page297_i306
#CELL
  pure_quanta q_res *
  page297_i307
#ISCELL
  standard offpage *
  page297_i308
#CELL
  pure_quanta q_res *
  page297_i309
#ISCELL
  standard offpage *
  page297_i310
#CELL
  pure_quanta q_res *
  page297_i311
#CELL
  pure_quanta q_res *
  page297_i312
#CELL
  pure_quanta q_res *
  page297_i313
#CELL
  pure_quanta mosfet_nch_gds_esd_protected *
  page297_i316
#ISCELL
  logical_power universal_gnd *
  page297_i317
#CELL
  pure_quanta sconn56_123276793 *
  page297_i318
#ISCELL
  standard tap *
  page297_i319
#ISCELL
  standard tap *
  page297_i320
#ISCELL
  standard tap *
  page297_i321
#ISCELL
  standard tap *
  page297_i322
#ISCELL
  standard tap *
  page297_i324
#ISCELL
  standard tap *
  page297_i325
#ISCELL
  logical_power universal_gnd *
  page297_i326
#CELL
  pure_quanta q_cap *
  page297_i327
#ISCELL
  logical_power universal_power *
  page297_i328
#CELL
  pure_quanta apx80929sag7 *
  page297_i329
#ISCELL
  logical_power universal_gnd *
  page297_i330
#CELL
  pure_quanta q_res *
  page297_i331
#ISCELL
  standard offpage *
  page297_i332
#ISCELL
  logical_power cad_note *
  *
#ISCELL
  mstr_misc dns *
  *
#ISCELL
  pure_quanta quanta_title_block_c *
  *
#CELL
  pure_quanta q_res *
  page324_i1
#CELL
  pure_quanta mosfet_nch_dual *
  page324_i10
#ISCELL
  logical_power gnd *
  page324_i11
#ISCELL
  logical_power gnd *
  page324_i12
#CELL
  pure_quanta q_res *
  page324_i13
#CELL
  pure_quanta q_res *
  page324_i14
#CELL
  pure_quanta q_res *
  page324_i15
#ISCELL
  logical_power gnd *
  page324_i16
#CELL
  pure_quanta q_cap *
  page324_i17
#CELL
  pure_quanta q_res *
  page324_i18
#ISCELL
  logical_power universal_power *
  page324_i19
#ISCELL
  logical_power gnd *
  page324_i2
#ISCELL
  standard offpage *
  page324_i20
#CELL
  pure_quanta q_res *
  page324_i21
#CELL
  pure_quanta q_res *
  page324_i22
#ISCELL
  logical_power universal_power *
  page324_i23
#CELL
  pure_quanta mosfet_nch_dual *
  page324_i24
#ISCELL
  logical_power gnd *
  page324_i25
#CELL
  pure_quanta q_res *
  page324_i26
#ISCELL
  logical_power gnd *
  page324_i27
#CELL
  pure_quanta q_res *
  page324_i28
#ISCELL
  logical_power gnd *
  page324_i29
#CELL
  pure_quanta mosfet_nch_dual *
  page324_i3
#ISCELL
  logical_power universal_power *
  page324_i30
#CELL
  pure_quanta q_cap *
  page324_i31
#CELL
  pure_quanta q_res *
  page324_i32
#ISCELL
  logical_power gnd *
  page324_i33
#CELL
  pure_quanta q_res *
  page324_i34
#CELL
  pure_quanta max15090bewit *
  page324_i35
#ISCELL
  logical_power gnd *
  page324_i36
#CELL
  pure_quanta q_cap *
  page324_i37
#CELL
  pure_quanta q_cap *
  page324_i38
#CELL
  pure_quanta q_res *
  page324_i39
#CELL
  pure_quanta mosfet_nch_dual *
  page324_i4
#ISCELL
  logical_power gnd *
  page324_i40
#CELL
  pure_quanta q_res *
  page324_i41
#CELL
  pure_quanta q_cap *
  page324_i42
#CELL
  pure_quanta q_res *
  page324_i43
#CELL
  pure_quanta q_res *
  page324_i44
#CELL
  pure_quanta q_cap *
  page324_i45
#CELL
  pure_quanta schottky_ac *
  page324_i46
#ISCELL
  logical_power gnd *
  page324_i47
#CELL
  pure_quanta q_res *
  page324_i48
#ISCELL
  logical_power vccaux15 *
  page324_i49
#ISCELL
  logical_power gnd *
  page324_i5
#CELL
  pure_quanta q_res *
  page324_i50
#ISCELL
  logical_power gnd *
  page324_i51
#CELL
  pure_quanta q_cap *
  page324_i52
#CELL
  pure_quanta q_cap *
  page324_i53
#ISCELL
  logical_power universal_power *
  page324_i54
#ISCELL
  logical_power universal_power *
  page324_i55
#ISCELL
  logical_power gnd *
  page324_i56
#CELL
  pure_quanta q_cap *
  page324_i57
#ISCELL
  logical_power gnd *
  page324_i58
#CELL
  pure_quanta q_res *
  page324_i59
#CELL
  pure_quanta q_res *
  page324_i6
#CELL
  pure_quanta q_cap *
  page324_i60
#CELL
  pure_quanta q_res *
  page324_i61
#CELL
  pure_quanta max15090bewit *
  page324_i62
#ISCELL
  logical_power gnd *
  page324_i63
#CELL
  pure_quanta q_res *
  page324_i64
#CELL
  pure_quanta q_res *
  page324_i65
#CELL
  pure_quanta q_cap *
  page324_i66
#CELL
  pure_quanta q_res *
  page324_i67
#CELL
  pure_quanta q_res *
  page324_i68
#CELL
  pure_quanta q_cap *
  page324_i69
#ISCELL
  logical_power universal_power *
  page324_i7
#CELL
  pure_quanta q_res *
  page324_i70
#CELL
  pure_quanta schottky_ac *
  page324_i71
#ISCELL
  logical_power gnd *
  page324_i72
#CELL
  pure_quanta q_res *
  page324_i73
#ISCELL
  logical_power vccaux15 *
  page324_i74
#CELL
  pure_quanta q_cap *
  page324_i75
#CELL
  pure_quanta q_res *
  page324_i76
#ISCELL
  logical_power gnd *
  page324_i77
#CELL
  pure_quanta q_cap *
  page324_i78
#CELL
  pure_quanta q_cap *
  page324_i79
#ISCELL
  logical_power gnd *
  page324_i8
#ISCELL
  logical_power universal_power *
  page324_i80
#ISCELL
  standard offpage *
  page324_i81
#ISCELL
  standard offpage *
  page324_i82
#ISCELL
  standard offpage *
  page324_i83
#CELL
  pure_quanta diode_tvs *
  page324_i84
#CELL
  pure_quanta q_res *
  page324_i85
#CELL
  pure_quanta q_res *
  page324_i9
#ISCELL
  logical_power cad_note *
  *
#ISCELL
  mstr_misc dns *
  *
#ISCELL
  pure_quanta quanta_title_block_c *
  *
#ISCELL
  standard offpage *
  page323_i1
#ISCELL
  logical_power universal_power *
  page323_i10
#ISCELL
  logical_power universal_gnd *
  page323_i2
#ISCELL
  logical_power universal_gnd *
  page323_i28
#ISCELL
  logical_power universal_gnd *
  page323_i29
#CELL
  pure_quanta q_cap *
  page323_i3
#CELL
  pure_quanta q_cap *
  page323_i30
#CELL
  pure_quanta mp5016gqhlz *
  page323_i31
#CELL
  pure_quanta q_cap *
  page323_i32
#ISCELL
  logical_power universal_gnd *
  page323_i33
#CELL
  pure_quanta q_cap *
  page323_i34
#ISCELL
  logical_power universal_power *
  page323_i35
#ISCELL
  logical_power gnd *
  page323_i36
#CELL
  pure_quanta q_cap *
  page323_i37
#ISCELL
  standard offpage *
  page323_i38
#ISCELL
  logical_power gnd *
  page323_i39
#CELL
  pure_quanta q_res *
  page323_i4
#CELL
  pure_quanta q_res *
  page323_i40
#ISCELL
  logical_power gnd *
  page323_i41
#CELL
  pure_quanta q_cap *
  page323_i42
#CELL
  pure_quanta q_res *
  page323_i43
#ISCELL
  logical_power gnd *
  page323_i44
#CELL
  pure_quanta q_res *
  page323_i45
#ISCELL
  logical_power gnd *
  page323_i46
#CELL
  pure_quanta q_cap *
  page323_i47
#ISCELL
  logical_power gnd *
  page323_i48
#CELL
  pure_quanta rs31312r *
  page323_i49
#CELL
  pure_quanta q_res *
  page323_i5
#ISCELL
  logical_power gnd *
  page323_i50
#CELL
  pure_quanta q_cap *
  page323_i51
#ISCELL
  logical_power universal_power *
  page323_i52
#CELL
  pure_quanta q_res *
  page323_i53
#CELL
  pure_quanta q_res *
  page323_i54
#CELL
  pure_quanta q_res *
  page323_i55
#CELL
  pure_quanta q_cap *
  page323_i56
#ISCELL
  logical_power gnd *
  page323_i57
#CELL
  pure_quanta q_res *
  page323_i58
#ISCELL
  standard offpage *
  page323_i59
#CELL
  pure_quanta q_res *
  page323_i6
#ISCELL
  standard offpage *
  page323_i60
#ISCELL
  logical_power vccaux15 *
  page323_i61
#CELL
  pure_quanta q_res *
  page323_i62
#CELL
  pure_quanta q_res *
  page323_i63
#CELL
  pure_quanta q_res *
  page323_i64
#ISCELL
  logical_power vccaux15 *
  page323_i65
#CELL
  pure_quanta q_res *
  page323_i66
#CELL
  pure_quanta q_res *
  page323_i67
#ISCELL
  logical_power gnd *
  page323_i68
#CELL
  pure_quanta q_cap *
  page323_i69
#ISCELL
  logical_power universal_gnd *
  page323_i7
#CELL
  pure_quanta q_res *
  page323_i70
#ISCELL
  logical_power universal_power *
  page323_i71
#ISCELL
  logical_power gnd *
  page323_i72
#CELL
  pure_quanta q_cap *
  page323_i73
#ISCELL
  standard offpage *
  page323_i74
#ISCELL
  standard offpage *
  page323_i75
#ISCELL
  standard offpage *
  page323_i76
#ISCELL
  logical_power universal_power *
  page323_i77
#ISCELL
  logical_power universal_gnd *
  page323_i8
#CELL
  pure_quanta q_cap *
  page323_i9
#ISCELL
  mstr_misc dns *
  *
#ISCELL
  pure_quanta quanta_title_block_c *
  *
#CELL
  pure_quanta pca9306dp1 *
  page183_i27
#CELL
  pure_quanta q_cap *
  page183_i28
#ISCELL
  logical_power universal_power *
  page183_i29
#ISCELL
  logical_power universal_power *
  page183_i3
#ISCELL
  logical_power universal_gnd *
  page183_i30
#ISCELL
  logical_power universal_gnd *
  page183_i38
#CELL
  pure_quanta q_res *
  page183_i43
#CELL
  pure_quanta q_res *
  page183_i45
#ISCELL
  logical_power universal_power *
  page183_i47
#CELL
  pure_quanta q_res *
  page183_i5
#ISCELL
  logical_power universal_power *
  page183_i51
#CELL
  pure_quanta q_cap *
  page183_i52
#ISCELL
  logical_power universal_gnd *
  page183_i53
#ISCELL
  standard offpage *
  page183_i54
#ISCELL
  standard offpage *
  page183_i55
#CELL
  pure_quanta q_res *
  page183_i65
#CELL
  pure_quanta q_res *
  page183_i66
#ISCELL
  standard offpage *
  page183_i67
#ISCELL
  standard offpage *
  page183_i68
#ISCELL
  standard offpage *
  page183_i7
#CELL
  pure_quanta q_res *
  page183_i70
#ISCELL
  standard offpage *
  page183_i71
#CELL
  pure_quanta q_res *
  page183_i72
#ISCELL
  standard offpage *
  page183_i73
#ISCELL
  standard offpage *
  page183_i74
#CELL
  pure_quanta q_res *
  page183_i76
#CELL
  pure_quanta q_res *
  page183_i77
#CELL
  pure_quanta q_res *
  page183_i78
#CELL
  pure_quanta q_res *
  page183_i80
#CELL
  pure_quanta q_cap *
  page183_i82
#ISCELL
  logical_power universal_gnd *
  page183_i84
#ISCELL
  logical_power universal_power *
  page183_i87
#CELL
  pure_quanta q_cap *
  page183_i89
#ISCELL
  logical_power universal_gnd *
  page183_i90
#ISCELL
  standard offpage *
  page183_i91
#ISCELL
  standard offpage *
  page183_i92
#CELL
  pure_quanta pca9617adp *
  page183_i93
#ISCELL
  standard offpage *
  page183_i94
#ISCELL
  logical_power universal_gnd *
  page183_i95
#CELL
  pure_quanta q_res *
  page183_i96
#ISCELL
  logical_power universal_power *
  page183_i97
#ISCELL
  logical_power universal_power *
  page183_i98
#CELL
  pure_quanta q_res *
  page183_i99
#ISCELL
  logical_power design_note *
  *
#ISCELL
  mstr_misc dns *
  *
#ISCELL
  pure_quanta quanta_title_block_c *
  *
#CELL
  pure_quanta q_res *
  page184_i1
#ISCELL
  logical_power universal_gnd *
  page184_i10
#CELL
  pure_quanta q_res *
  page184_i11
#CELL
  pure_quanta q_res *
  page184_i12
#CELL
  pure_quanta q_res *
  page184_i13
#ISCELL
  logical_power universal_power *
  page184_i14
#ISCELL
  logical_power universal_gnd *
  page184_i15
#CELL
  pure_quanta q_res *
  page184_i16
#ISCELL
  logical_power universal_gnd *
  page184_i17
#CELL
  pure_quanta q_res *
  page184_i18
#ISCELL
  logical_power universal_gnd *
  page184_i19
#ISCELL
  logical_power universal_gnd *
  page184_i2
#CELL
  pure_quanta q_res *
  page184_i20
#ISCELL
  standard offpage *
  page184_i21
#CELL
  pure_quanta q_res *
  page184_i22
#CELL
  pure_quanta q_res *
  page184_i23
#CELL
  pure_quanta q_res *
  page184_i24
#ISCELL
  logical_power universal_gnd *
  page184_i25
#CELL
  pure_quanta q_res *
  page184_i26
#ISCELL
  logical_power universal_gnd *
  page184_i27
#CELL
  pure_quanta q_res *
  page184_i28
#ISCELL
  logical_power universal_gnd *
  page184_i29
#ISCELL
  logical_power universal_gnd *
  page184_i3
#CELL
  pure_quanta q_res *
  page184_i30
#ISCELL
  standard offpage *
  page184_i31
#ISCELL
  standard offpage *
  page184_i32
#ISCELL
  standard offpage *
  page184_i33
#ISCELL
  standard offpage *
  page184_i34
#CELL
  pure_quanta q_res *
  page184_i4
#CELL
  pure_quanta q_res *
  page184_i48
#CELL
  pure_quanta q_res *
  page184_i49
#CELL
  pure_quanta q_res *
  page184_i5
#CELL
  pure_quanta q_res *
  page184_i50
#ISCELL
  standard offpage *
  page184_i51
#ISCELL
  standard offpage *
  page184_i52
#ISCELL
  standard offpage *
  page184_i53
#ISCELL
  standard offpage *
  page184_i54
#ISCELL
  standard offpage *
  page184_i55
#ISCELL
  logical_power universal_gnd *
  page184_i56
#ISCELL
  logical_power universal_gnd *
  page184_i57
#CELL
  pure_quanta q_res *
  page184_i58
#CELL
  pure_quanta q_res *
  page184_i59
#CELL
  pure_quanta q_res *
  page184_i6
#ISCELL
  logical_power universal_gnd *
  page184_i60
#CELL
  pure_quanta q_res *
  page184_i61
#CELL
  pure_quanta q_res *
  page184_i62
#CELL
  pure_quanta q_res *
  page184_i63
#ISCELL
  logical_power universal_power *
  page184_i64
#ISCELL
  logical_power universal_gnd *
  page184_i65
#ISCELL
  logical_power universal_gnd *
  page184_i66
#CELL
  pure_quanta q_res *
  page184_i67
#ISCELL
  logical_power universal_gnd *
  page184_i68
#CELL
  pure_quanta q_res *
  page184_i69
#ISCELL
  logical_power universal_power *
  page184_i7
#CELL
  pure_quanta q_res *
  page184_i70
#CELL
  pure_quanta q_res *
  page184_i71
#CELL
  pure_quanta q_res *
  page184_i72
#ISCELL
  logical_power universal_power *
  page184_i73
#CELL
  pure_quanta q_res *
  page184_i74
#CELL
  pure_quanta q_res *
  page184_i75
#ISCELL
  standard offpage *
  page184_i76
#ISCELL
  standard offpage *
  page184_i77
#ISCELL
  standard offpage *
  page184_i78
#ISCELL
  standard offpage *
  page184_i79
#ISCELL
  logical_power universal_gnd *
  page184_i8
#ISCELL
  standard offpage *
  page184_i80
#ISCELL
  standard offpage *
  page184_i81
#CELL
  pure_quanta q_res *
  page184_i9
#ISCELL
  logical_power cad_note *
  *
#ISCELL
  mstr_misc dns *
  *
#ISCELL
  pure_quanta quanta_title_block_c *
  *
#ISCELL
  logical_power universal_gnd *
  page194_i1
#ISCELL
  logical_power universal_power *
  page194_i10
#ISCELL
  standard offpage *
  page194_i11
#ISCELL
  standard offpage *
  page194_i12
#CELL
  pure_quanta q_res *
  page194_i13
#ISCELL
  logical_power universal_gnd *
  page194_i14
#CELL
  pure_quanta q_cap *
  page194_i15
#CELL
  pure_quanta q_res *
  page194_i16
#CELL
  pure_quanta q_res *
  page194_i17
#CELL
  pure_quanta q_res *
  page194_i18
#CELL
  pure_quanta q_res *
  page194_i19
#CELL
  pure_quanta q_cap *
  page194_i2
#CELL
  pure_quanta tusb211irwbr *
  page194_i20
#ISCELL
  logical_power universal_power *
  page194_i21
#CELL
  pure_quanta q_res *
  page194_i22
#CELL
  pure_quanta q_res *
  page194_i23
#CELL
  pure_quanta q_res *
  page194_i24
#CELL
  pure_quanta q_res *
  page194_i25
#CELL
  pure_quanta q_res *
  page194_i26
#CELL
  pure_quanta q_res *
  page194_i27
#ISCELL
  standard offpage *
  page194_i28
#ISCELL
  standard offpage *
  page194_i29
#ISCELL
  logical_power universal_gnd *
  page194_i3
#ISCELL
  standard offpage *
  page194_i30
#ISCELL
  standard offpage *
  page194_i31
#ISCELL
  standard offpage *
  page194_i32
#ISCELL
  standard offpage *
  page194_i33
#ISCELL
  standard offpage *
  page194_i34
#ISCELL
  logical_power universal_gnd *
  page194_i35
#ISCELL
  logical_power universal_gnd *
  page194_i36
#CELL
  pure_quanta q_res *
  page194_i37
#CELL
  pure_quanta q_res *
  page194_i38
#ISCELL
  standard offpage *
  page194_i39
#CELL
  pure_quanta q_res *
  page194_i4
#CELL
  pure_quanta gl852gohy60 *
  page194_i40
#CELL
  pure_quanta q_res *
  page194_i41
#ISCELL
  logical_power universal_gnd *
  page194_i42
#CELL
  pure_quanta q_cap *
  page194_i43
#ISCELL
  logical_power universal_power *
  page194_i44
#CELL
  pure_quanta q_cap *
  page194_i45
#CELL
  pure_quanta q_cap *
  page194_i46
#CELL
  pure_quanta q_cap *
  page194_i47
#ISCELL
  logical_power universal_power *
  page194_i48
#CELL
  pure_quanta q_cap *
  page194_i49
#ISCELL
  standard offpage *
  page194_i5
#CELL
  pure_quanta q_res *
  page194_i50
#CELL
  pure_quanta q_cap *
  page194_i51
#CELL
  pure_quanta q_cap *
  page194_i52
#CELL
  pure_quanta q_cap *
  page194_i53
#ISCELL
  logical_power universal_gnd *
  page194_i54
#CELL
  pure_quanta q_cap *
  page194_i55
#CELL
  pure_quanta q_cap *
  page194_i56
#ISCELL
  logical_power universal_gnd *
  page194_i57
#CELL
  pure_quanta q_cap *
  page194_i58
#ISCELL
  logical_power universal_gnd *
  page194_i59
#ISCELL
  standard offpage *
  page194_i6
#CELL
  pure_quanta q_res *
  page194_i60
#CELL
  pure_quanta q_res *
  page194_i61
#ISCELL
  logical_power universal_power *
  page194_i62
#ISCELL
  logical_power universal_gnd *
  page194_i63
#ISCELL
  standard offpage *
  page194_i64
#ISCELL
  standard offpage *
  page194_i65
#ISCELL
  standard offpage *
  page194_i66
#ISCELL
  standard offpage *
  page194_i67
#ISCELL
  logical_power universal_gnd *
  page194_i7
#CELL
  pure_quanta q_res *
  page194_i72
#CELL
  pure_quanta q_res *
  page194_i73
#ISCELL
  standard offpage *
  page194_i74
#CELL
  pure_quanta q_res *
  page194_i75
#ISCELL
  logical_power universal_gnd *
  page194_i76
#CELL
  pure_quanta q_res *
  page194_i77
#CELL
  pure_quanta q_res *
  page194_i78
#ISCELL
  standard offpage *
  page194_i79
#CELL
  pure_quanta q_res *
  page194_i8
#ISCELL
  logical_power universal_gnd *
  page194_i80
#CELL
  pure_quanta q_cap *
  page194_i81
#ISCELL
  logical_power universal_gnd *
  page194_i82
#CELL
  pure_quanta q_xtal_4p_13bi_24gnd *
  page194_i83
#ISCELL
  logical_power universal_gnd *
  page194_i84
#CELL
  pure_quanta q_cap *
  page194_i85
#ISCELL
  logical_power universal_gnd *
  page194_i86
#ISCELL
  standard offpage *
  page194_i87
#CELL
  pure_quanta q_res *
  page194_i88
#ISCELL
  logical_power universal_gnd *
  page194_i89
#CELL
  pure_quanta q_res *
  page194_i9
#CELL
  pure_quanta q_res *
  page194_i90
#ISCELL
  logical_power universal_gnd *
  page194_i91
#ISCELL
  logical_power design_note *
  *
#ISCELL
  mstr_misc dns *
  *
#ISCELL
  pure_quanta quanta_title_block_c *
  *
#ISCELL
  standard offpage *
  page185_i18
#ISCELL
  standard offpage *
  page185_i19
#ISCELL
  standard offpage *
  page185_i20
#ISCELL
  logical_power universal_gnd *
  page185_i22
#CELL
  pure_quanta q_res *
  page185_i24
#CELL
  pure_quanta q_res *
  page185_i26
#ISCELL
  logical_power universal_power *
  page185_i27
#ISCELL
  logical_power universal_gnd *
  page185_i28
#CELL
  pure_quanta q_res *
  page185_i30
#ISCELL
  logical_power universal_power *
  page185_i31
#CELL
  pure_quanta q_res *
  page185_i32
#ISCELL
  logical_power universal_gnd *
  page185_i34
#CELL
  pure_quanta nc7sb3157 *
  page185_i35
#CELL
  pure_quanta q_cap *
  page185_i36
#ISCELL
  logical_power universal_power *
  page185_i37
#ISCELL
  logical_power universal_gnd *
  page185_i38
#CELL
  pure_quanta q_res *
  page185_i39
#ISCELL
  logical_power universal_power *
  page185_i40
#CELL
  pure_quanta q_res *
  page185_i41
#CELL
  pure_quanta q_res *
  page185_i42
#ISCELL
  logical_power universal_gnd *
  page185_i43
#ISCELL
  standard offpage *
  page185_i44
#CELL
  pure_quanta q_res *
  page185_i45
#ISCELL
  standard offpage *
  page185_i46
#CELL
  pure_quanta q_res *
  page185_i47
#CELL
  pure_quanta q_res *
  page185_i49
#CELL
  pure_quanta q_res *
  page185_i50
#CELL
  pure_quanta q_res *
  page185_i51
#ISCELL
  logical_power design_note *
  *
#ISCELL
  mstr_misc dns *
  *
#ISCELL
  pure_quanta quanta_title_block_c *
  *
#ISCELL
  logical_power universal_power *
  page186_i10
#CELL
  pure_quanta q_res *
  page186_i11
#ISCELL
  standard offpage *
  page186_i14
#ISCELL
  logical_power universal_power *
  page186_i15
#CELL
  pure_quanta q_res *
  page186_i16
#ISCELL
  standard offpage *
  page186_i41
#ISCELL
  logical_power universal_power *
  page186_i44
#CELL
  pure_quanta q_res *
  page186_i45
#CELL
  pure_quanta q_res *
  page186_i46
#ISCELL
  logical_power universal_gnd *
  page186_i47
#ISCELL
  logical_power universal_power *
  page186_i58
#ISCELL
  standard offpage *
  page186_i59
#CELL
  pure_quanta q_res *
  page186_i60
#CELL
  pure_quanta q_res *
  page186_i61
#ISCELL
  logical_power universal_gnd *
  page186_i62
#ISCELL
  standard offpage *
  page186_i64
#ISCELL
  logical_power universal_power *
  page186_i65
#CELL
  pure_quanta q_res *
  page186_i68
#ISCELL
  standard offpage *
  page186_i72
#ISCELL
  logical_power universal_power *
  page186_i73
#ISCELL
  logical_power universal_gnd *
  page186_i74
#CELL
  pure_quanta q_res *
  page186_i76
#CELL
  pure_quanta q_res *
  page186_i77
#CELL
  pure_quanta q_res *
  page186_i78
#ISCELL
  standard offpage *
  page186_i79
#ISCELL
  standard offpage *
  page186_i8
#ISCELL
  logical_power universal_power *
  page186_i80
#CELL
  pure_quanta q_res *
  page186_i81
#ISCELL
  logical_power universal_gnd *
  page186_i82
#ISCELL
  standard offpage *
  page186_i84
#ISCELL
  logical_power universal_power *
  page186_i85
#ISCELL
  logical_power universal_gnd *
  page186_i87
#CELL
  pure_quanta q_res *
  page186_i88
#CELL
  pure_quanta q_res *
  page186_i89
#CELL
  pure_quanta q_res *
  page186_i90
#ISCELL
  logical_power universal_gnd *
  page186_i91
#CELL
  pure_quanta q_res *
  page186_i92
#ISCELL
  logical_power universal_gnd *
  page186_i93
#ISCELL
  mstr_misc dns *
  *
#ISCELL
  pure_quanta quanta_title_block_c *
  *
#ISCELL
  logical_power universal_gnd *
  page187_i11
#ISCELL
  logical_power universal_power *
  page187_i12
#CELL
  pure_quanta q_res *
  page187_i13
#CELL
  pure_quanta q_res *
  page187_i14
#ISCELL
  logical_power universal_gnd *
  page187_i15
#ISCELL
  standard offpage *
  page187_i16
#ISCELL
  logical_power universal_power *
  page187_i17
#CELL
  pure_quanta q_res *
  page187_i18
#ISCELL
  standard offpage *
  page187_i19
#ISCELL
  logical_power universal_power *
  page187_i20
#CELL
  pure_quanta q_res *
  page187_i21
#ISCELL
  standard offpage *
  page187_i22
#CELL
  pure_quanta q_res *
  page187_i23
#ISCELL
  logical_power universal_gnd *
  page187_i24
#ISCELL
  logical_power universal_power *
  page187_i25
#ISCELL
  standard offpage *
  page187_i27
#ISCELL
  logical_power universal_power *
  page187_i30
#ISCELL
  standard offpage *
  page187_i32
#ISCELL
  standard offpage *
  page187_i33
#ISCELL
  logical_power universal_gnd *
  page187_i35
#CELL
  pure_quanta q_res *
  page187_i36
#ISCELL
  logical_power universal_gnd *
  page187_i37
#ISCELL
  logical_power universal_power *
  page187_i38
#CELL
  pure_quanta q_res *
  page187_i39
#ISCELL
  standard offpage *
  page187_i4
#CELL
  pure_quanta q_res *
  page187_i40
#ISCELL
  logical_power universal_gnd *
  page187_i41
#ISCELL
  logical_power universal_power *
  page187_i42
#CELL
  pure_quanta q_res *
  page187_i43
#CELL
  pure_quanta q_res *
  page187_i44
#ISCELL
  logical_power universal_gnd *
  page187_i45
#ISCELL
  standard offpage *
  page187_i46
#ISCELL
  logical_power universal_power *
  page187_i47
#CELL
  pure_quanta q_res *
  page187_i48
#ISCELL
  standard offpage *
  page187_i5
#CELL
  pure_quanta q_res *
  page187_i51
#CELL
  pure_quanta q_res *
  page187_i53
#CELL
  pure_quanta q_res *
  page187_i54
#CELL
  pure_quanta q_res *
  page187_i55
#CELL
  pure_quanta q_res *
  page187_i56
#ISCELL
  logical_power universal_power *
  page187_i8
#ISCELL
  mstr_misc dns *
  *
#ISCELL
  pure_quanta quanta_title_block_c *
  *
#ISCELL
  logical_power universal_gnd *
  page188_i20
#CELL
  pure_quanta q_res *
  page188_i21
#CELL
  pure_quanta q_res *
  page188_i22
#ISCELL
  logical_power universal_power *
  page188_i23
#ISCELL
  standard offpage *
  page188_i25
#ISCELL
  standard offpage *
  page188_i26
#ISCELL
  logical_power universal_gnd *
  page188_i30
#CELL
  pure_quanta q_res *
  page188_i31
#ISCELL
  standard offpage *
  page188_i33
#CELL
  pure_quanta q_res *
  page188_i36
#ISCELL
  logical_power universal_gnd *
  page188_i37
#ISCELL
  standard offpage *
  page188_i38
#ISCELL
  logical_power universal_power *
  page188_i39
#ISCELL
  logical_power universal_gnd *
  page188_i42
#CELL
  pure_quanta q_res *
  page188_i43
#CELL
  pure_quanta q_res *
  page188_i44
#ISCELL
  standard offpage *
  page188_i45
#ISCELL
  logical_power universal_power *
  page188_i46
#CELL
  pure_quanta q_res *
  page188_i47
#ISCELL
  logical_power universal_gnd *
  page188_i49
#CELL
  pure_quanta q_res *
  page188_i50
#ISCELL
  standard offpage *
  page188_i51
#ISCELL
  logical_power universal_power *
  page188_i52
#CELL
  pure_quanta q_res *
  page188_i57
#ISCELL
  standard offpage *
  page188_i59
#ISCELL
  logical_power universal_power *
  page188_i60
#ISCELL
  logical_power universal_gnd *
  page188_i62
#CELL
  pure_quanta q_res *
  page188_i63
#CELL
  pure_quanta q_res *
  page188_i64
#ISCELL
  standard offpage *
  page188_i66
#ISCELL
  logical_power universal_power *
  page188_i67
#ISCELL
  logical_power universal_gnd *
  page188_i69
#CELL
  pure_quanta q_res *
  page188_i70
#CELL
  pure_quanta q_res *
  page188_i71
#ISCELL
  standard offpage *
  page188_i72
#ISCELL
  logical_power universal_power *
  page188_i73
#ISCELL
  logical_power universal_gnd *
  page188_i75
#CELL
  pure_quanta q_res *
  page188_i76
#CELL
  pure_quanta q_res *
  page188_i77
#ISCELL
  logical_power design_note *
  *
#ISCELL
  pure_quanta quanta_title_block_c *
  *
#CELL
  pure_quanta q_res *
  page189_i100
#ISCELL
  standard offpage *
  page189_i101
#ISCELL
  standard offpage *
  page189_i102
#ISCELL
  standard offpage *
  page189_i103
#ISCELL
  standard offpage *
  page189_i104
#ISCELL
  logical_power universal_gnd *
  page189_i105
#CELL
  pure_quanta q_res *
  page189_i106
#CELL
  pure_quanta q_res *
  page189_i107
#ISCELL
  logical_power universal_gnd *
  page189_i108
#CELL
  pure_quanta q_res *
  page189_i109
#ISCELL
  logical_power universal_gnd *
  page189_i110
#ISCELL
  standard offpage *
  page189_i111
#ISCELL
  logical_power universal_power *
  page189_i112
#CELL
  pure_quanta q_res *
  page189_i113
#CELL
  pure_quanta q_res *
  page189_i114
#CELL
  pure_quanta sw_pushbutton4p_24 *
  page189_i122
#CELL
  pure_quanta q_res *
  page189_i123
#ISCELL
  logical_power universal_gnd *
  page189_i124
#ISCELL
  standard offpage *
  page189_i125
#ISCELL
  logical_power universal_power *
  page189_i126
#CELL
  pure_quanta q_res *
  page189_i127
#CELL
  pure_quanta q_cap *
  page189_i128
#ISCELL
  logical_power universal_gnd *
  page189_i129
#ISCELL
  standard offpage *
  page189_i130
#ISCELL
  standard offpage *
  page189_i131
#CELL
  pure_quanta q_res *
  page189_i132
#CELL
  pure_quanta q_res *
  page189_i133
#CELL
  pure_quanta conn14_210hp207gbr1 *
  page189_i134
#CELL
  pure_quanta q_res *
  page189_i86
#CELL
  pure_quanta q_res *
  page189_i87
#CELL
  pure_quanta q_res *
  page189_i88
#CELL
  pure_quanta q_res *
  page189_i89
#ISCELL
  logical_power universal_power *
  page189_i90
#ISCELL
  logical_power universal_power *
  page189_i92
#CELL
  pure_quanta q_res *
  page189_i93
#ISCELL
  logical_power universal_gnd *
  page189_i98
#ISCELL
  logical_power universal_power *
  page189_i99
#ISCELL
  logical_power design_note *
  *
#ISCELL
  mstr_misc dns *
  *
#ISCELL
  pure_quanta quanta_title_block_c *
  *
#ISCELL
  standard offpage *
  page190_i10
#CELL
  pure_quanta q_res *
  page190_i100
#CELL
  pure_quanta q_res *
  page190_i101
#CELL
  pure_quanta q_res *
  page190_i102
#ISCELL
  standard offpage *
  page190_i103
#CELL
  pure_quanta q_res *
  page190_i105
#ISCELL
  standard offpage *
  page190_i11
#ISCELL
  standard offpage *
  page190_i12
#ISCELL
  standard offpage *
  page190_i14
#ISCELL
  standard offpage *
  page190_i15
#ISCELL
  standard offpage *
  page190_i18
#ISCELL
  logical_power universal_gnd *
  page190_i20
#ISCELL
  logical_power universal_gnd *
  page190_i21
#ISCELL
  logical_power universal_power *
  page190_i24
#ISCELL
  standard offpage *
  page190_i32
#CELL
  pure_quanta q_res *
  page190_i33
#CELL
  pure_quanta nc7sb3157 *
  page190_i34
#CELL
  pure_quanta q_cap *
  page190_i36
#CELL
  pure_quanta q_cap *
  page190_i37
#CELL
  pure_quanta q_res *
  page190_i38
#CELL
  pure_quanta nc7sb3157 *
  page190_i39
#ISCELL
  logical_power universal_gnd *
  page190_i40
#ISCELL
  standard offpage *
  page190_i41
#CELL
  pure_quanta q_cap *
  page190_i43
#ISCELL
  logical_power universal_power *
  page190_i44
#CELL
  pure_quanta q_cap *
  page190_i45
#ISCELL
  logical_power universal_gnd *
  page190_i46
#ISCELL
  standard offpage *
  page190_i48
#ISCELL
  standard offpage *
  page190_i5
#ISCELL
  standard offpage *
  page190_i50
#ISCELL
  standard offpage *
  page190_i51
#ISCELL
  standard offpage *
  page190_i53
#CELL
  pure_quanta q_res *
  page190_i54
#ISCELL
  standard offpage *
  page190_i6
#ISCELL
  standard offpage *
  page190_i7
#CELL
  pure_quanta q_res *
  page190_i70
#ISCELL
  logical_power universal_power *
  page190_i71
#ISCELL
  standard offpage *
  page190_i79
#ISCELL
  standard offpage *
  page190_i8
#ISCELL
  standard offpage *
  page190_i81
#ISCELL
  standard offpage *
  page190_i82
#ISCELL
  logical_power universal_gnd *
  page190_i83
#CELL
  pure_quanta q_cap *
  page190_i84
#ISCELL
  logical_power universal_gnd *
  page190_i85
#ISCELL
  logical_power universal_power *
  page190_i86
#CELL
  pure_quanta q_res *
  page190_i87
#ISCELL
  logical_power universal_power *
  page190_i88
#CELL
  pure_quanta q_res *
  page190_i89
#ISCELL
  standard offpage *
  page190_i9
#ISCELL
  logical_power universal_gnd *
  page190_i90
#CELL
  pure_quanta q_res *
  page190_i91
#ISCELL
  standard offpage *
  page190_i92
#ISCELL
  logical_power universal_power *
  page190_i93
#CELL
  pure_quanta q_res *
  page190_i94
#CELL
  pure_quanta 74lvc1g07se7 *
  page190_i95
#CELL
  pure_quanta q_res *
  page190_i96
#CELL
  pure_quanta q_res *
  page190_i97
#CELL
  pure_quanta q_res *
  page190_i98
#CELL
  pure_quanta q_res *
  page190_i99
#ISCELL
  pure_quanta quanta_title_block_c *
  *
#ISCELL
  standard offpage *
  page191_i1
#ISCELL
  standard offpage *
  page191_i10
#CELL
  pure_quanta q_res *
  page191_i14
#CELL
  pure_quanta q_res *
  page191_i2
#ISCELL
  standard offpage *
  page191_i22
#ISCELL
  standard offpage *
  page191_i28
#CELL
  pure_quanta q_res *
  page191_i29
#ISCELL
  standard offpage *
  page191_i30
#ISCELL
  logical_power universal_power *
  page191_i34
#CELL
  pure_quanta q_res *
  page191_i35
#ISCELL
  logical_power universal_power *
  page191_i37
#CELL
  pure_quanta q_res *
  page191_i38
#ISCELL
  standard offpage *
  page191_i6
#ISCELL
  mstr_misc dns *
  *
#ISCELL
  pure_quanta quanta_title_block_c *
  *
#CELL
  pure_quanta q_res *
  page192_i1
#CELL
  pure_quanta q_res *
  page192_i11
#ISCELL
  logical_power universal_power *
  page192_i12
#ISCELL
  standard offpage *
  page192_i13
#ISCELL
  standard offpage *
  page192_i14
#ISCELL
  standard offpage *
  page192_i16
#CELL
  pure_quanta q_res *
  page192_i17
#CELL
  pure_quanta q_res *
  page192_i18
#ISCELL
  logical_power universal_power *
  page192_i2
#CELL
  pure_quanta q_res *
  page192_i23
#CELL
  pure_quanta q_res *
  page192_i24
#ISCELL
  logical_power universal_power *
  page192_i25
#CELL
  pure_quanta q_res *
  page192_i26
#ISCELL
  standard offpage *
  page192_i28
#ISCELL
  standard offpage *
  page192_i29
#ISCELL
  standard offpage *
  page192_i3
#ISCELL
  standard offpage *
  page192_i30
#ISCELL
  standard offpage *
  page192_i33
#ISCELL
  standard offpage *
  page192_i34
#ISCELL
  logical_power universal_power *
  page192_i39
#CELL
  pure_quanta q_res *
  page192_i4
#CELL
  pure_quanta q_res *
  page192_i41
#CELL
  pure_quanta q_res *
  page192_i42
#ISCELL
  standard offpage *
  page192_i44
#ISCELL
  standard offpage *
  page192_i45
#ISCELL
  logical_power universal_power *
  page192_i49
#ISCELL
  standard offpage *
  page192_i5
#CELL
  pure_quanta q_res *
  page192_i50
#CELL
  pure_quanta q_res *
  page192_i51
#ISCELL
  standard offpage *
  page192_i53
#ISCELL
  standard offpage *
  page192_i54
#ISCELL
  logical_power universal_power *
  page192_i58
#CELL
  pure_quanta q_res *
  page192_i59
#CELL
  pure_quanta q_res *
  page192_i6
#CELL
  pure_quanta q_res *
  page192_i60
#ISCELL
  standard offpage *
  page192_i61
#CELL
  pure_quanta q_res *
  page192_i62
#ISCELL
  standard offpage *
  page192_i64
#ISCELL
  logical_power universal_power *
  page192_i65
#CELL
  pure_quanta q_res *
  page192_i66
#ISCELL
  logical_power universal_power *
  page192_i67
#ISCELL
  standard offpage *
  page192_i68
#CELL
  pure_quanta q_res *
  page192_i69
#ISCELL
  standard offpage *
  page192_i7
#ISCELL
  standard offpage *
  page192_i71
#CELL
  pure_quanta q_res *
  page192_i72
#ISCELL
  standard offpage *
  page192_i74
#CELL
  pure_quanta q_res *
  page192_i75
#CELL
  pure_quanta q_res *
  page192_i8
#ISCELL
  standard offpage *
  page192_i9
#ISCELL
  pure_quanta quanta_title_block_c *
  *
#ISCELL
  standard offpage *
  page193_i1
#CELL
  pure_quanta q_res *
  page193_i10
#ISCELL
  standard offpage *
  page193_i12
#CELL
  pure_quanta q_res *
  page193_i13
#ISCELL
  standard offpage *
  page193_i14
#ISCELL
  standard offpage *
  page193_i18
#ISCELL
  standard offpage *
  page193_i19
#ISCELL
  standard offpage *
  page193_i2
#CELL
  pure_quanta q_res *
  page193_i20
#CELL
  pure_quanta q_res *
  page193_i21
#ISCELL
  standard offpage *
  page193_i22
#ISCELL
  standard offpage *
  page193_i23
#ISCELL
  standard offpage *
  page193_i25
#ISCELL
  standard offpage *
  page193_i26
#CELL
  pure_quanta q_res *
  page193_i27
#CELL
  pure_quanta q_res *
  page193_i28
#ISCELL
  standard offpage *
  page193_i29
#CELL
  pure_quanta q_res *
  page193_i3
#ISCELL
  standard offpage *
  page193_i30
#CELL
  pure_quanta q_res *
  page193_i32
#ISCELL
  standard offpage *
  page193_i36
#ISCELL
  standard offpage *
  page193_i37
#ISCELL
  standard offpage *
  page193_i38
#ISCELL
  standard offpage *
  page193_i39
#ISCELL
  standard offpage *
  page193_i4
#CELL
  pure_quanta q_res *
  page193_i40
#ISCELL
  standard offpage *
  page193_i41
#CELL
  pure_quanta q_res *
  page193_i5
#ISCELL
  standard offpage *
  page193_i6
#ISCELL
  logical_power design_note *
  *
#ISCELL
  mstr_misc dns *
  *
#ISCELL
  pure_quanta quanta_title_block_c *
  *
#CELL
  pure_quanta 9qxl2001bnhgi8 *
  page195_i119
#ISCELL
  standard offpage *
  page195_i120
#ISCELL
  standard offpage *
  page195_i121
#ISCELL
  standard offpage *
  page195_i122
#ISCELL
  standard offpage *
  page195_i123
#ISCELL
  standard offpage *
  page195_i126
#ISCELL
  standard offpage *
  page195_i127
#ISCELL
  standard offpage *
  page195_i128
#ISCELL
  standard offpage *
  page195_i129
#ISCELL
  standard offpage *
  page195_i150
#ISCELL
  standard offpage *
  page195_i151
#ISCELL
  standard offpage *
  page195_i154
#CELL
  pure_quanta q_res *
  page195_i156
#ISCELL
  standard offpage *
  page195_i157
#ISCELL
  logical_power universal_power *
  page195_i158
#ISCELL
  logical_power universal_power *
  page195_i159
#ISCELL
  logical_power universal_power *
  page195_i160
#ISCELL
  logical_power universal_power *
  page195_i161
#CELL
  pure_quanta q_res *
  page195_i162
#CELL
  pure_quanta q_res *
  page195_i163
#CELL
  pure_quanta q_cap *
  page195_i164
#CELL
  pure_quanta q_cap *
  page195_i165
#ISCELL
  logical_power universal_power *
  page195_i166
#CELL
  pure_quanta q_cap *
  page195_i167
#CELL
  pure_quanta q_cap *
  page195_i168
#ISCELL
  logical_power universal_power *
  page195_i169
#CELL
  pure_quanta q_inductor *
  page195_i170
#CELL
  pure_quanta q_cap *
  page195_i171
#CELL
  pure_quanta q_cap *
  page195_i172
#CELL
  pure_quanta q_cap *
  page195_i173
#CELL
  pure_quanta q_cap *
  page195_i174
#ISCELL
  logical_power universal_power *
  page195_i175
#ISCELL
  logical_power universal_power *
  page195_i176
#CELL
  pure_quanta q_inductor *
  page195_i177
#CELL
  pure_quanta q_res *
  page195_i178
#CELL
  pure_quanta q_res *
  page195_i179
#ISCELL
  logical_power universal_power *
  page195_i183
#CELL
  pure_quanta q_res *
  page195_i185
#CELL
  pure_quanta q_res *
  page195_i187
#ISCELL
  standard offpage *
  page195_i188
#ISCELL
  standard offpage *
  page195_i189
#ISCELL
  standard offpage *
  page195_i190
#ISCELL
  standard offpage *
  page195_i191
#ISCELL
  standard offpage *
  page195_i192
#CELL
  pure_quanta q_res *
  page195_i194
#ISCELL
  logical_power universal_power *
  page195_i195
#CELL
  pure_quanta q_res *
  page195_i197
#CELL
  pure_quanta q_res *
  page195_i199
#ISCELL
  standard offpage *
  page195_i200
#CELL
  pure_quanta q_res *
  page195_i304
#ISCELL
  standard offpage *
  page195_i381
#ISCELL
  standard offpage *
  page195_i382
#ISCELL
  standard offpage *
  page195_i383
#ISCELL
  standard offpage *
  page195_i384
#ISCELL
  standard offpage *
  page195_i385
#ISCELL
  standard offpage *
  page195_i386
#ISCELL
  standard offpage *
  page195_i387
#ISCELL
  standard offpage *
  page195_i388
#ISCELL
  standard offpage *
  page195_i409
#ISCELL
  standard offpage *
  page195_i410
#CELL
  pure_quanta q_cap *
  page195_i419
#ISCELL
  logical_power universal_gnd *
  page195_i432
#ISCELL
  logical_power universal_gnd *
  page195_i433
#ISCELL
  logical_power universal_gnd *
  page195_i434
#ISCELL
  logical_power universal_gnd *
  page195_i435
#ISCELL
  logical_power universal_gnd *
  page195_i436
#ISCELL
  logical_power universal_gnd *
  page195_i437
#ISCELL
  logical_power universal_gnd *
  page195_i438
#ISCELL
  logical_power universal_gnd *
  page195_i439
#CELL
  pure_quanta q_res *
  page195_i487
#ISCELL
  standard offpage *
  page195_i488
#ISCELL
  standard offpage *
  page195_i502
#ISCELL
  standard offpage *
  page195_i503
#ISCELL
  standard offpage *
  page195_i504
#ISCELL
  standard offpage *
  page195_i505
#ISCELL
  standard offpage *
  page195_i506
#ISCELL
  standard offpage *
  page195_i507
#ISCELL
  standard offpage *
  page195_i508
#ISCELL
  standard offpage *
  page195_i509
#ISCELL
  standard offpage *
  page195_i519
#ISCELL
  standard offpage *
  page195_i520
#ISCELL
  standard offpage *
  page195_i523
#ISCELL
  standard offpage *
  page195_i524
#ISCELL
  standard offpage *
  page195_i525
#ISCELL
  standard offpage *
  page195_i528
#ISCELL
  standard offpage *
  page195_i529
#ISCELL
  standard offpage *
  page195_i530
#ISCELL
  standard offpage *
  page195_i531
#ISCELL
  standard offpage *
  page195_i532
#CELL
  pure_quanta q_res *
  page195_i534
#CELL
  pure_quanta q_res *
  page195_i535
#CELL
  pure_quanta q_res *
  page195_i536
#CELL
  pure_quanta q_res *
  page195_i537
#ISCELL
  standard offpage *
  page195_i538
#CELL
  pure_quanta q_res *
  page195_i539
#CELL
  pure_quanta q_res *
  page195_i540
#ISCELL
  logical_power universal_power *
  page195_i541
#ISCELL
  pure_quanta quanta_title_block_c *
  *
#ISCELL
  standard offpage *
  page196_i1
#CELL
  pure_quanta q_res *
  page196_i10
#CELL
  pure_quanta q_res *
  page196_i11
#CELL
  pure_quanta q_res *
  page196_i12
#CELL
  pure_quanta q_res *
  page196_i13
#CELL
  pure_quanta q_res *
  page196_i14
#CELL
  pure_quanta q_res *
  page196_i15
#CELL
  pure_quanta q_res *
  page196_i16
#CELL
  pure_quanta q_res *
  page196_i17
#CELL
  pure_quanta q_res *
  page196_i18
#ISCELL
  standard offpage *
  page196_i19
#ISCELL
  standard offpage *
  page196_i2
#ISCELL
  standard offpage *
  page196_i20
#ISCELL
  standard offpage *
  page196_i21
#ISCELL
  standard offpage *
  page196_i22
#ISCELL
  standard offpage *
  page196_i23
#CELL
  pure_quanta q_res *
  page196_i24
#CELL
  pure_quanta q_res *
  page196_i25
#CELL
  pure_quanta q_res *
  page196_i26
#CELL
  pure_quanta q_res *
  page196_i27
#CELL
  pure_quanta q_res *
  page196_i28
#ISCELL
  standard offpage *
  page196_i29
#ISCELL
  standard offpage *
  page196_i3
#ISCELL
  standard offpage *
  page196_i30
#ISCELL
  standard offpage *
  page196_i31
#ISCELL
  standard offpage *
  page196_i32
#ISCELL
  standard offpage *
  page196_i33
#ISCELL
  standard offpage *
  page196_i34
#ISCELL
  standard offpage *
  page196_i35
#ISCELL
  standard offpage *
  page196_i36
#ISCELL
  standard offpage *
  page196_i37
#ISCELL
  standard offpage *
  page196_i38
#ISCELL
  standard offpage *
  page196_i39
#ISCELL
  standard offpage *
  page196_i4
#ISCELL
  standard offpage *
  page196_i40
#ISCELL
  standard offpage *
  page196_i41
#ISCELL
  standard offpage *
  page196_i42
#ISCELL
  standard offpage *
  page196_i5
#ISCELL
  standard offpage *
  page196_i6
#ISCELL
  standard offpage *
  page196_i7
#ISCELL
  standard offpage *
  page196_i8
#ISCELL
  standard offpage *
  page196_i9
#ISCELL
  logical_power design_note *
  *
#ISCELL
  mstr_misc dns *
  *
#ISCELL
  pure_quanta quanta_title_block_c *
  *
#ISCELL
  standard offpage *
  page197_i100
#ISCELL
  standard offpage *
  page197_i112
#ISCELL
  standard offpage *
  page197_i113
#ISCELL
  standard offpage *
  page197_i115
#ISCELL
  standard offpage *
  page197_i116
#ISCELL
  standard offpage *
  page197_i119
#ISCELL
  standard offpage *
  page197_i120
#ISCELL
  logical_power universal_power *
  page197_i157
#ISCELL
  logical_power universal_power *
  page197_i158
#ISCELL
  logical_power universal_power *
  page197_i159
#ISCELL
  logical_power universal_power *
  page197_i160
#ISCELL
  logical_power universal_power *
  page197_i161
#ISCELL
  logical_power universal_power *
  page197_i162
#ISCELL
  standard offpage *
  page197_i163
#ISCELL
  standard offpage *
  page197_i164
#ISCELL
  standard offpage *
  page197_i165
#ISCELL
  standard offpage *
  page197_i167
#ISCELL
  standard offpage *
  page197_i168
#ISCELL
  standard offpage *
  page197_i170
#ISCELL
  standard offpage *
  page197_i171
#ISCELL
  standard offpage *
  page197_i172
#CELL
  pure_quanta 9sq440nqqi8 *
  page197_i180
#ISCELL
  standard offpage *
  page197_i182
#ISCELL
  standard offpage *
  page197_i206
#ISCELL
  standard offpage *
  page197_i207
#ISCELL
  standard offpage *
  page197_i242
#CELL
  pure_quanta q_res *
  page197_i252
#ISCELL
  standard offpage *
  page197_i253
#ISCELL
  standard offpage *
  page197_i254
#ISCELL
  standard offpage *
  page197_i255
#ISCELL
  standard offpage *
  page197_i256
#ISCELL
  standard offpage *
  page197_i257
#ISCELL
  standard offpage *
  page197_i258
#ISCELL
  standard offpage *
  page197_i259
#ISCELL
  standard offpage *
  page197_i260
#ISCELL
  standard offpage *
  page197_i261
#ISCELL
  standard offpage *
  page197_i262
#ISCELL
  standard offpage *
  page197_i263
#ISCELL
  standard offpage *
  page197_i264
#CELL
  pure_quanta q_res *
  page197_i265
#CELL
  pure_quanta q_res *
  page197_i267
#CELL
  pure_quanta q_res *
  page197_i268
#CELL
  pure_quanta q_res *
  page197_i269
#CELL
  pure_quanta q_res *
  page197_i270
#CELL
  pure_quanta q_res *
  page197_i271
#CELL
  pure_quanta q_res *
  page197_i272
#CELL
  pure_quanta q_res *
  page197_i273
#CELL
  pure_quanta q_res *
  page197_i274
#CELL
  pure_quanta q_res *
  page197_i275
#CELL
  pure_quanta q_res *
  page197_i276
#CELL
  pure_quanta q_res *
  page197_i277
#CELL
  pure_quanta q_res *
  page197_i278
#ISCELL
  logical_power universal_power *
  page197_i279
#CELL
  pure_quanta q_res *
  page197_i280
#CELL
  pure_quanta q_res *
  page197_i281
#CELL
  pure_quanta q_res *
  page197_i282
#CELL
  pure_quanta q_res *
  page197_i283
#ISCELL
  logical_power universal_gnd *
  page197_i285
#CELL
  pure_quanta q_cap *
  page197_i286
#CELL
  pure_quanta 9sq440nqqi8 *
  page197_i288
#ISCELL
  logical_power universal_gnd *
  page197_i294
#ISCELL
  logical_power universal_gnd *
  page197_i295
#ISCELL
  logical_power universal_gnd *
  page197_i301
#ISCELL
  logical_power universal_gnd *
  page197_i302
#CELL
  pure_quanta q_res *
  page197_i303
#ISCELL
  logical_power universal_power *
  page197_i304
#ISCELL
  standard offpage *
  page197_i330
#CELL
  pure_quanta q_res *
  page197_i378
#CELL
  pure_quanta q_res *
  page197_i379
#CELL
  pure_quanta q_res *
  page197_i380
#CELL
  pure_quanta q_res *
  page197_i381
#CELL
  pure_quanta q_res *
  page197_i382
#CELL
  pure_quanta q_res *
  page197_i383
#ISCELL
  logical_power universal_power *
  page197_i385
#CELL
  pure_quanta q_xtal_4p_13bi_24gnd *
  page197_i391
#CELL
  pure_quanta q_res *
  page197_i392
#CELL
  pure_quanta q_cap *
  page197_i393
#CELL
  pure_quanta q_cap *
  page197_i394
#ISCELL
  standard offpage *
  page197_i99
#ISCELL
  mstr_misc dns *
  *
#ISCELL
  pure_quanta quanta_title_block_c *
  *
#ISCELL
  standard offpage *
  page198_i1
#CELL
  pure_quanta q_res *
  page198_i10
#CELL
  pure_quanta q_res *
  page198_i11
#CELL
  pure_quanta q_res *
  page198_i12
#ISCELL
  standard offpage *
  page198_i13
#ISCELL
  standard offpage *
  page198_i14
#ISCELL
  standard offpage *
  page198_i15
#ISCELL
  standard offpage *
  page198_i16
#ISCELL
  standard offpage *
  page198_i17
#ISCELL
  standard offpage *
  page198_i18
#CELL
  pure_quanta q_res *
  page198_i19
#ISCELL
  standard offpage *
  page198_i2
#CELL
  pure_quanta q_res *
  page198_i20
#CELL
  pure_quanta q_res *
  page198_i21
#CELL
  pure_quanta q_res *
  page198_i22
#CELL
  pure_quanta q_res *
  page198_i23
#CELL
  pure_quanta q_res *
  page198_i24
#ISCELL
  standard offpage *
  page198_i25
#ISCELL
  standard offpage *
  page198_i26
#CELL
  pure_quanta q_res *
  page198_i27
#CELL
  pure_quanta q_res *
  page198_i28
#CELL
  pure_quanta q_res *
  page198_i29
#ISCELL
  standard offpage *
  page198_i3
#CELL
  pure_quanta q_res *
  page198_i30
#ISCELL
  standard offpage *
  page198_i31
#ISCELL
  standard offpage *
  page198_i32
#ISCELL
  standard offpage *
  page198_i33
#ISCELL
  standard offpage *
  page198_i34
#ISCELL
  standard offpage *
  page198_i35
#ISCELL
  standard offpage *
  page198_i36
#ISCELL
  standard offpage *
  page198_i37
#ISCELL
  standard offpage *
  page198_i38
#ISCELL
  standard offpage *
  page198_i39
#ISCELL
  standard offpage *
  page198_i4
#ISCELL
  standard offpage *
  page198_i40
#ISCELL
  standard offpage *
  page198_i41
#ISCELL
  standard offpage *
  page198_i42
#CELL
  pure_quanta q_res *
  page198_i43
#CELL
  pure_quanta q_res *
  page198_i44
#CELL
  pure_quanta q_res *
  page198_i45
#CELL
  pure_quanta q_res *
  page198_i46
#CELL
  pure_quanta q_res *
  page198_i47
#CELL
  pure_quanta q_res *
  page198_i48
#ISCELL
  standard offpage *
  page198_i49
#ISCELL
  standard offpage *
  page198_i5
#ISCELL
  standard offpage *
  page198_i50
#ISCELL
  standard offpage *
  page198_i51
#ISCELL
  standard offpage *
  page198_i52
#ISCELL
  standard offpage *
  page198_i53
#ISCELL
  standard offpage *
  page198_i54
#ISCELL
  standard offpage *
  page198_i55
#ISCELL
  standard offpage *
  page198_i56
#CELL
  pure_quanta q_res *
  page198_i57
#CELL
  pure_quanta q_res *
  page198_i58
#ISCELL
  standard offpage *
  page198_i59
#ISCELL
  standard offpage *
  page198_i6
#ISCELL
  standard offpage *
  page198_i60
#CELL
  pure_quanta q_res *
  page198_i7
#CELL
  pure_quanta q_res *
  page198_i8
#CELL
  pure_quanta q_res *
  page198_i9
#ISCELL
  logical_power cad_note *
  *
#ISCELL
  pure_quanta quanta_title_block_c *
  *
#CELL
  pure_quanta q_cap *
  page199_i19
#CELL
  pure_quanta q_inductor *
  page199_i20
#ISCELL
  logical_power universal_power *
  page199_i21
#ISCELL
  logical_power universal_power *
  page199_i3
#ISCELL
  logical_power universal_power *
  page199_i31
#ISCELL
  logical_power universal_power *
  page199_i35
#CELL
  pure_quanta q_res *
  page199_i36
#CELL
  pure_quanta q_inductor *
  page199_i41
#ISCELL
  logical_power universal_power *
  page199_i42
#CELL
  pure_quanta q_cap *
  page199_i43
#CELL
  pure_quanta q_cap *
  page199_i44
#CELL
  pure_quanta q_cap *
  page199_i48
#ISCELL
  logical_power universal_power *
  page199_i51
#CELL
  pure_quanta q_cap *
  page199_i53
#CELL
  pure_quanta q_res *
  page199_i55
#ISCELL
  logical_power universal_power *
  page199_i56
#CELL
  pure_quanta q_cap *
  page199_i58
#CELL
  pure_quanta q_cap *
  page199_i59
#CELL
  pure_quanta q_cap *
  page199_i6
#CELL
  pure_quanta q_inductor *
  page199_i60
#ISCELL
  logical_power universal_power *
  page199_i61
#ISCELL
  logical_power universal_gnd *
  page199_i69
#CELL
  pure_quanta q_res *
  page199_i7
#ISCELL
  logical_power universal_gnd *
  page199_i70
#ISCELL
  logical_power universal_gnd *
  page199_i71
#ISCELL
  logical_power universal_gnd *
  page199_i72
#ISCELL
  logical_power universal_gnd *
  page199_i73
#ISCELL
  logical_power universal_gnd *
  page199_i74
#CELL
  pure_quanta q_cap *
  page199_i76
#CELL
  pure_quanta q_cap *
  page199_i77
#CELL
  pure_quanta q_cap *
  page199_i78
#CELL
  pure_quanta q_cap *
  page199_i79
#ISCELL
  logical_power universal_power *
  page199_i8
#CELL
  pure_quanta q_cap *
  page199_i80
#CELL
  pure_quanta q_cap *
  page199_i81
#CELL
  pure_quanta q_cap *
  page199_i82
#CELL
  pure_quanta q_cap *
  page199_i85
#CELL
  pure_quanta q_cap *
  page199_i86
#CELL
  pure_quanta q_cap *
  page199_i87
#CELL
  pure_quanta q_cap *
  page199_i88
#CELL
  pure_quanta q_cap *
  page199_i89
#ISCELL
  mstr_misc dns *
  *
#ISCELL
  pure_quanta quanta_title_block_c *
  *
#CELL
  pure_quanta 9zxl0451ekilft *
  page200_i1
#CELL
  pure_quanta q_cap *
  page200_i10
#CELL
  pure_quanta q_res *
  page200_i11
#ISCELL
  logical_power universal_gnd *
  page200_i12
#CELL
  pure_quanta q_cap *
  page200_i17
#ISCELL
  logical_power universal_gnd *
  page200_i21
#ISCELL
  logical_power universal_gnd *
  page200_i22
#ISCELL
  logical_power universal_power *
  page200_i23
#ISCELL
  logical_power universal_power *
  page200_i24
#ISCELL
  logical_power universal_power *
  page200_i25
#ISCELL
  logical_power universal_power *
  page200_i26
#ISCELL
  logical_power universal_power *
  page200_i27
#ISCELL
  logical_power universal_power *
  page200_i28
#ISCELL
  logical_power universal_power *
  page200_i29
#CELL
  pure_quanta q_res *
  page200_i30
#CELL
  pure_quanta q_res *
  page200_i31
#ISCELL
  logical_power universal_power *
  page200_i32
#ISCELL
  logical_power universal_gnd *
  page200_i33
#ISCELL
  standard offpage *
  page200_i34
#ISCELL
  standard offpage *
  page200_i35
#ISCELL
  standard offpage *
  page200_i36
#ISCELL
  standard offpage *
  page200_i37
#ISCELL
  standard offpage *
  page200_i38
#CELL
  pure_quanta q_res *
  page200_i39
#CELL
  pure_quanta q_res *
  page200_i4
#ISCELL
  standard offpage *
  page200_i40
#ISCELL
  standard offpage *
  page200_i41
#ISCELL
  standard offpage *
  page200_i42
#ISCELL
  standard offpage *
  page200_i43
#ISCELL
  standard offpage *
  page200_i44
#ISCELL
  standard offpage *
  page200_i45
#CELL
  pure_quanta q_res *
  page200_i48
#CELL
  pure_quanta q_res *
  page200_i49
#CELL
  pure_quanta q_cap *
  page200_i5
#ISCELL
  logical_power universal_power *
  page200_i50
#ISCELL
  logical_power universal_gnd *
  page200_i51
#ISCELL
  standard offpage *
  page200_i52
#ISCELL
  standard offpage *
  page200_i53
#CELL
  pure_quanta q_cap *
  page200_i54
#CELL
  pure_quanta q_cap *
  page200_i55
#CELL
  pure_quanta q_cap *
  page200_i56
#CELL
  pure_quanta q_cap *
  page200_i57
#CELL
  pure_quanta q_cap *
  page200_i58
#CELL
  pure_quanta q_cap *
  page200_i59
#ISCELL
  standard offpage *
  page200_i62
#ISCELL
  standard offpage *
  page200_i63
#ISCELL
  standard offpage *
  page200_i66
#CELL
  pure_quanta q_res *
  page200_i69
#ISCELL
  logical_power universal_power *
  page200_i7
#ISCELL
  logical_power universal_power *
  page200_i70
#CELL
  pure_quanta q_cap *
  page200_i71
#ISCELL
  standard offpage *
  page200_i72
#ISCELL
  standard offpage *
  page200_i73
#CELL
  pure_quanta q_res *
  page200_i74
#CELL
  pure_quanta q_res *
  page200_i75
#CELL
  pure_quanta q_res *
  page200_i76
#CELL
  pure_quanta q_res *
  page200_i77
#CELL
  pure_quanta q_res *
  page200_i78
#CELL
  pure_quanta q_res *
  page200_i79
#ISCELL
  logical_power universal_gnd *
  page200_i8
#ISCELL
  logical_power universal_power *
  page200_i80
#CELL
  pure_quanta q_inductor *
  page200_i81
#CELL
  pure_quanta q_inductor *
  page200_i82
#ISCELL
  logical_power design_note *
  *
#ISCELL
  mstr_misc dns *
  *
#ISCELL
  pure_quanta quanta_title_block_c *
  *
#CELL
  pure_quanta q_res *
  page201_i102
#CELL
  pure_quanta q_cap *
  page201_i103
#CELL
  pure_quanta q_cap *
  page201_i104
#CELL
  pure_quanta q_cap *
  page201_i105
#CELL
  pure_quanta q_cap *
  page201_i106
#ISCELL
  logical_power universal_gnd *
  page201_i107
#ISCELL
  logical_power universal_power *
  page201_i108
#ISCELL
  logical_power universal_power *
  page201_i109
#ISCELL
  logical_power universal_power *
  page201_i110
#ISCELL
  logical_power universal_power *
  page201_i111
#ISCELL
  logical_power universal_gnd *
  page201_i113
#ISCELL
  logical_power universal_gnd *
  page201_i115
#ISCELL
  logical_power universal_gnd *
  page201_i116
#ISCELL
  logical_power universal_gnd *
  page201_i117
#ISCELL
  standard offpage *
  page201_i125
#ISCELL
  standard offpage *
  page201_i126
#CELL
  pure_quanta q_res *
  page201_i127
#CELL
  pure_quanta q_res *
  page201_i128
#ISCELL
  standard offpage *
  page201_i129
#ISCELL
  logical_power universal_power *
  page201_i130
#ISCELL
  logical_power universal_gnd *
  page201_i133
#CELL
  pure_quanta q_res *
  page201_i134
#CELL
  pure_quanta q_res *
  page201_i135
#ISCELL
  standard offpage *
  page201_i139
#ISCELL
  standard offpage *
  page201_i140
#ISCELL
  logical_power universal_power *
  page201_i141
#CELL
  pure_quanta q_res *
  page201_i142
#CELL
  pure_quanta q_res *
  page201_i146
#CELL
  pure_quanta q_res *
  page201_i147
#ISCELL
  standard offpage *
  page201_i150
#ISCELL
  standard offpage *
  page201_i151
#ISCELL
  standard offpage *
  page201_i152
#ISCELL
  standard offpage *
  page201_i153
#ISCELL
  standard offpage *
  page201_i154
#CELL
  pure_quanta q_inductor *
  page201_i155
#ISCELL
  logical_power universal_power *
  page201_i156
#CELL
  pure_quanta q_res *
  page201_i157
#CELL
  pure_quanta 74lvc1g32gw *
  page201_i158
#CELL
  pure_quanta q_xtal_4p_13bi_24gnd *
  page201_i159
#CELL
  pure_quanta q_cap *
  page201_i16
#CELL
  pure_quanta q_res *
  page201_i160
#CELL
  pure_quanta q_res *
  page201_i161
#ISCELL
  logical_power universal_gnd *
  page201_i162
#CELL
  pure_quanta q_res *
  page201_i163
#ISCELL
  logical_power universal_power *
  page201_i164
#CELL
  pure_quanta q_cap *
  page201_i165
#CELL
  pure_quanta q_cap *
  page201_i166
#CELL
  pure_quanta 9fgl0251dkilft *
  page201_i167
#CELL
  pure_quanta q_cap *
  page201_i18
#CELL
  pure_quanta q_cap *
  page201_i19
#ISCELL
  logical_power universal_power *
  page201_i20
#ISCELL
  logical_power universal_gnd *
  page201_i21
#ISCELL
  logical_power universal_gnd *
  page201_i22
#ISCELL
  standard offpage *
  page201_i32
#ISCELL
  logical_power universal_power *
  page201_i33
#ISCELL
  logical_power universal_gnd *
  page201_i35
#CELL
  pure_quanta q_res *
  page201_i69
#ISCELL
  standard offpage *
  page201_i70
#ISCELL
  standard offpage *
  page201_i71
#ISCELL
  standard offpage *
  page201_i72
#ISCELL
  standard offpage *
  page201_i73
#CELL
  pure_quanta q_res *
  page201_i74
#CELL
  pure_quanta q_res *
  page201_i75
#CELL
  pure_quanta q_res *
  page201_i76
#ISCELL
  logical_power universal_power *
  page201_i79
#CELL
  pure_quanta q_cap *
  page201_i80
#ISCELL
  logical_power universal_gnd *
  page201_i81
#ISCELL
  logical_power universal_gnd *
  page201_i82
#CELL
  pure_quanta q_res *
  page201_i84
#CELL
  pure_quanta q_res *
  page201_i85
#ISCELL
  standard offpage *
  page201_i87
#ISCELL
  standard offpage *
  page201_i88
#ISCELL
  mstr_misc dns *
  *
#ISCELL
  pure_quanta quanta_title_block_c *
  *
#ISCELL
  standard offpage *
  page314_i1
#ISCELL
  standard offpage *
  page314_i10
#ISCELL
  standard offpage *
  page314_i100
#ISCELL
  standard offpage *
  page314_i101
#ISCELL
  standard offpage *
  page314_i102
#ISCELL
  standard offpage *
  page314_i103
#ISCELL
  standard offpage *
  page314_i104
#ISCELL
  standard offpage *
  page314_i105
#CELL
  pure_quanta q_res *
  page314_i106
#CELL
  pure_quanta q_res *
  page314_i107
#CELL
  pure_quanta q_res *
  page314_i108
#CELL
  pure_quanta q_res *
  page314_i109
#ISCELL
  standard offpage *
  page314_i11
#CELL
  pure_quanta q_res *
  page314_i110
#CELL
  pure_quanta q_res *
  page314_i111
#CELL
  pure_quanta q_res *
  page314_i112
#CELL
  pure_quanta q_res *
  page314_i113
#CELL
  pure_quanta q_res *
  page314_i114
#CELL
  pure_quanta q_res *
  page314_i115
#ISCELL
  standard offpage *
  page314_i116
#ISCELL
  standard offpage *
  page314_i117
#ISCELL
  standard offpage *
  page314_i118
#ISCELL
  standard offpage *
  page314_i119
#ISCELL
  standard offpage *
  page314_i12
#ISCELL
  standard offpage *
  page314_i120
#ISCELL
  standard offpage *
  page314_i121
#ISCELL
  standard offpage *
  page314_i122
#ISCELL
  standard offpage *
  page314_i123
#ISCELL
  standard offpage *
  page314_i124
#ISCELL
  standard offpage *
  page314_i125
#ISCELL
  standard offpage *
  page314_i126
#ISCELL
  standard offpage *
  page314_i127
#ISCELL
  standard offpage *
  page314_i128
#ISCELL
  standard offpage *
  page314_i129
#ISCELL
  standard offpage *
  page314_i13
#ISCELL
  standard offpage *
  page314_i130
#ISCELL
  standard offpage *
  page314_i131
#ISCELL
  standard offpage *
  page314_i132
#ISCELL
  standard offpage *
  page314_i133
#CELL
  pure_quanta q_res *
  page314_i134
#CELL
  pure_quanta q_res *
  page314_i135
#CELL
  pure_quanta q_res *
  page314_i136
#CELL
  pure_quanta q_res *
  page314_i137
#CELL
  pure_quanta q_res *
  page314_i138
#CELL
  pure_quanta q_res *
  page314_i139
#CELL
  pure_quanta q_res *
  page314_i14
#CELL
  pure_quanta q_res *
  page314_i140
#CELL
  pure_quanta q_res *
  page314_i141
#ISCELL
  standard offpage *
  page314_i142
#ISCELL
  standard offpage *
  page314_i143
#ISCELL
  standard offpage *
  page314_i144
#ISCELL
  standard offpage *
  page314_i145
#ISCELL
  standard offpage *
  page314_i146
#ISCELL
  standard offpage *
  page314_i147
#ISCELL
  standard offpage *
  page314_i148
#ISCELL
  standard offpage *
  page314_i149
#CELL
  pure_quanta q_res *
  page314_i15
#ISCELL
  standard offpage *
  page314_i150
#ISCELL
  standard offpage *
  page314_i151
#ISCELL
  standard offpage *
  page314_i152
#ISCELL
  standard offpage *
  page314_i153
#ISCELL
  standard offpage *
  page314_i154
#ISCELL
  standard offpage *
  page314_i155
#ISCELL
  standard offpage *
  page314_i156
#ISCELL
  standard offpage *
  page314_i157
#ISCELL
  standard offpage *
  page314_i158
#ISCELL
  standard offpage *
  page314_i159
#CELL
  pure_quanta q_res *
  page314_i16
#ISCELL
  standard offpage *
  page314_i160
#ISCELL
  standard offpage *
  page314_i161
#ISCELL
  standard offpage *
  page314_i162
#ISCELL
  standard offpage *
  page314_i163
#ISCELL
  standard offpage *
  page314_i164
#ISCELL
  standard offpage *
  page314_i165
#ISCELL
  standard offpage *
  page314_i166
#ISCELL
  standard offpage *
  page314_i167
#ISCELL
  standard offpage *
  page314_i168
#ISCELL
  standard offpage *
  page314_i169
#CELL
  pure_quanta q_res *
  page314_i17
#ISCELL
  standard offpage *
  page314_i170
#ISCELL
  standard offpage *
  page314_i171
#ISCELL
  standard offpage *
  page314_i172
#ISCELL
  standard offpage *
  page314_i173
#ISCELL
  standard offpage *
  page314_i174
#ISCELL
  standard offpage *
  page314_i175
#ISCELL
  standard offpage *
  page314_i176
#ISCELL
  standard offpage *
  page314_i177
#CELL
  pure_quanta q_res *
  page314_i178
#CELL
  pure_quanta q_res *
  page314_i179
#CELL
  pure_quanta q_res *
  page314_i18
#ISCELL
  logical_power universal_power *
  page314_i180
#ISCELL
  standard offpage *
  page314_i181
#ISCELL
  standard offpage *
  page314_i182
#ISCELL
  standard offpage *
  page314_i183
#ISCELL
  standard offpage *
  page314_i184
#ISCELL
  standard offpage *
  page314_i185
#ISCELL
  standard offpage *
  page314_i186
#ISCELL
  standard offpage *
  page314_i187
#CELL
  pure_quanta lcmxo3lf9400c5bg484c *
  page314_i188
#ISCELL
  standard offpage *
  page314_i189
#CELL
  pure_quanta q_res *
  page314_i19
#ISCELL
  standard offpage *
  page314_i190
#ISCELL
  standard offpage *
  page314_i193
#ISCELL
  standard offpage *
  page314_i194
#ISCELL
  standard offpage *
  page314_i195
#ISCELL
  standard offpage *
  page314_i196
#CELL
  pure_quanta q_res *
  page314_i197
#CELL
  pure_quanta q_res *
  page314_i198
#ISCELL
  standard offpage *
  page314_i2
#CELL
  pure_quanta q_res *
  page314_i20
#CELL
  pure_quanta q_res *
  page314_i21
#CELL
  pure_quanta q_res *
  page314_i22
#CELL
  pure_quanta q_res *
  page314_i23
#CELL
  pure_quanta q_res *
  page314_i24
#CELL
  pure_quanta q_res *
  page314_i25
#CELL
  pure_quanta q_res *
  page314_i26
#ISCELL
  standard offpage *
  page314_i27
#ISCELL
  standard offpage *
  page314_i28
#ISCELL
  standard offpage *
  page314_i29
#ISCELL
  standard offpage *
  page314_i3
#ISCELL
  standard offpage *
  page314_i30
#ISCELL
  standard offpage *
  page314_i31
#ISCELL
  standard offpage *
  page314_i32
#ISCELL
  standard offpage *
  page314_i33
#ISCELL
  standard offpage *
  page314_i34
#ISCELL
  standard offpage *
  page314_i35
#ISCELL
  standard offpage *
  page314_i36
#ISCELL
  standard offpage *
  page314_i37
#ISCELL
  standard offpage *
  page314_i38
#ISCELL
  standard offpage *
  page314_i39
#ISCELL
  standard offpage *
  page314_i4
#ISCELL
  standard offpage *
  page314_i40
#CELL
  pure_quanta q_res *
  page314_i41
#ISCELL
  logical_power universal_power *
  page314_i42
#CELL
  pure_quanta mosfet_nch_dual *
  page314_i43
#ISCELL
  logical_power universal_gnd *
  page314_i44
#CELL
  pure_quanta q_res *
  page314_i45
#ISCELL
  logical_power universal_power *
  page314_i46
#CELL
  pure_quanta q_res *
  page314_i47
#ISCELL
  logical_power universal_power *
  page314_i48
#CELL
  pure_quanta mosfet_nch_dual *
  page314_i49
#ISCELL
  standard offpage *
  page314_i5
#ISCELL
  logical_power universal_gnd *
  page314_i50
#CELL
  pure_quanta q_res *
  page314_i51
#ISCELL
  logical_power universal_power *
  page314_i52
#ISCELL
  standard offpage *
  page314_i53
#ISCELL
  standard offpage *
  page314_i54
#ISCELL
  standard offpage *
  page314_i55
#ISCELL
  standard offpage *
  page314_i56
#ISCELL
  standard offpage *
  page314_i57
#ISCELL
  standard offpage *
  page314_i58
#ISCELL
  standard offpage *
  page314_i59
#ISCELL
  standard offpage *
  page314_i6
#ISCELL
  standard offpage *
  page314_i60
#ISCELL
  standard offpage *
  page314_i61
#ISCELL
  standard offpage *
  page314_i62
#ISCELL
  standard offpage *
  page314_i63
#ISCELL
  standard offpage *
  page314_i64
#ISCELL
  standard offpage *
  page314_i65
#ISCELL
  standard offpage *
  page314_i66
#ISCELL
  standard offpage *
  page314_i67
#ISCELL
  standard offpage *
  page314_i68
#ISCELL
  standard offpage *
  page314_i69
#ISCELL
  standard offpage *
  page314_i7
#ISCELL
  standard offpage *
  page314_i70
#ISCELL
  standard offpage *
  page314_i71
#ISCELL
  standard offpage *
  page314_i72
#ISCELL
  standard offpage *
  page314_i73
#ISCELL
  standard offpage *
  page314_i74
#ISCELL
  standard offpage *
  page314_i75
#ISCELL
  standard offpage *
  page314_i76
#ISCELL
  standard offpage *
  page314_i77
#ISCELL
  standard offpage *
  page314_i78
#ISCELL
  standard offpage *
  page314_i79
#ISCELL
  standard offpage *
  page314_i8
#ISCELL
  standard offpage *
  page314_i80
#ISCELL
  standard offpage *
  page314_i81
#ISCELL
  standard offpage *
  page314_i82
#ISCELL
  standard offpage *
  page314_i83
#ISCELL
  standard offpage *
  page314_i84
#ISCELL
  standard offpage *
  page314_i85
#ISCELL
  standard offpage *
  page314_i86
#ISCELL
  standard offpage *
  page314_i87
#ISCELL
  standard offpage *
  page314_i88
#ISCELL
  standard offpage *
  page314_i89
#ISCELL
  standard offpage *
  page314_i9
#ISCELL
  standard offpage *
  page314_i90
#ISCELL
  standard offpage *
  page314_i91
#ISCELL
  standard offpage *
  page314_i92
#ISCELL
  standard offpage *
  page314_i93
#ISCELL
  standard offpage *
  page314_i94
#ISCELL
  standard offpage *
  page314_i95
#ISCELL
  standard offpage *
  page314_i96
#ISCELL
  standard offpage *
  page314_i97
#ISCELL
  standard offpage *
  page314_i98
#ISCELL
  standard offpage *
  page314_i99
#ISCELL
  logical_power cad_note *
  *
#ISCELL
  mstr_misc dns *
  *
#ISCELL
  pure_quanta quanta_title_block_c *
  *
#CELL
  pure_quanta lcmxo3lf9400c5bg484c *
  page313_i1
#ISCELL
  standard offpage *
  page313_i10
#ISCELL
  standard offpage *
  page313_i100
#ISCELL
  standard offpage *
  page313_i104
#ISCELL
  standard offpage *
  page313_i105
#ISCELL
  standard offpage *
  page313_i11
#CELL
  pure_quanta q_res *
  page313_i115
#ISCELL
  standard offpage *
  page313_i12
#ISCELL
  logical_power universal_gnd *
  page313_i123
#ISCELL
  logical_power universal_power *
  page313_i124
#ISCELL
  logical_power universal_gnd *
  page313_i125
#CELL
  pure_quanta q_cap *
  page313_i126
#CELL
  pure_quanta q_osc4p *
  page313_i127
#ISCELL
  logical_power universal_power *
  page313_i128
#CELL
  pure_quanta q_res *
  page313_i129
#ISCELL
  standard offpage *
  page313_i13
#ISCELL
  standard offpage *
  page313_i130
#ISCELL
  standard offpage *
  page313_i131
#ISCELL
  standard offpage *
  page313_i133
#ISCELL
  standard offpage *
  page313_i134
#ISCELL
  standard offpage *
  page313_i135
#ISCELL
  standard offpage *
  page313_i14
#ISCELL
  standard offpage *
  page313_i144
#ISCELL
  standard offpage *
  page313_i145
#ISCELL
  standard offpage *
  page313_i146
#CELL
  pure_quanta q_res *
  page313_i147
#ISCELL
  standard offpage *
  page313_i148
#ISCELL
  standard offpage *
  page313_i149
#ISCELL
  standard offpage *
  page313_i15
#ISCELL
  standard offpage *
  page313_i150
#ISCELL
  standard offpage *
  page313_i155
#ISCELL
  standard offpage *
  page313_i156
#ISCELL
  standard offpage *
  page313_i157
#ISCELL
  standard offpage *
  page313_i158
#CELL
  pure_quanta q_res *
  page313_i159
#ISCELL
  standard offpage *
  page313_i16
#CELL
  pure_quanta q_res *
  page313_i160
#ISCELL
  standard offpage *
  page313_i161
#ISCELL
  standard offpage *
  page313_i162
#ISCELL
  standard offpage *
  page313_i163
#ISCELL
  standard offpage *
  page313_i164
#ISCELL
  standard offpage *
  page313_i165
#CELL
  pure_quanta q_res *
  page313_i166
#CELL
  pure_quanta q_res *
  page313_i167
#ISCELL
  standard offpage *
  page313_i168
#ISCELL
  standard offpage *
  page313_i169
#ISCELL
  standard offpage *
  page313_i17
#ISCELL
  standard offpage *
  page313_i170
#ISCELL
  standard offpage *
  page313_i171
#ISCELL
  standard offpage *
  page313_i172
#ISCELL
  standard offpage *
  page313_i173
#ISCELL
  standard offpage *
  page313_i174
#CELL
  pure_quanta q_res *
  page313_i175
#CELL
  pure_quanta q_res *
  page313_i176
#ISCELL
  standard offpage *
  page313_i177
#ISCELL
  standard offpage *
  page313_i178
#ISCELL
  standard offpage *
  page313_i179
#ISCELL
  standard offpage *
  page313_i18
#CELL
  pure_quanta q_res *
  page313_i180
#ISCELL
  standard offpage *
  page313_i181
#ISCELL
  standard offpage *
  page313_i182
#CELL
  pure_quanta q_res *
  page313_i183
#ISCELL
  standard offpage *
  page313_i184
#ISCELL
  standard offpage *
  page313_i185
#ISCELL
  standard offpage *
  page313_i186
#ISCELL
  standard offpage *
  page313_i188
#ISCELL
  standard offpage *
  page313_i189
#ISCELL
  standard offpage *
  page313_i19
#CELL
  pure_quanta q_res *
  page313_i190
#ISCELL
  standard offpage *
  page313_i193
#CELL
  pure_quanta q_res *
  page313_i194
#ISCELL
  standard offpage *
  page313_i195
#ISCELL
  standard offpage *
  page313_i196
#ISCELL
  standard offpage *
  page313_i199
#ISCELL
  standard offpage *
  page313_i20
#CELL
  pure_quanta q_res *
  page313_i200
#ISCELL
  standard offpage *
  page313_i201
#ISCELL
  standard offpage *
  page313_i202
#ISCELL
  standard offpage *
  page313_i205
#CELL
  pure_quanta q_res *
  page313_i206
#ISCELL
  standard offpage *
  page313_i207
#ISCELL
  standard offpage *
  page313_i208
#ISCELL
  standard offpage *
  page313_i21
#ISCELL
  standard offpage *
  page313_i210
#CELL
  pure_quanta q_res *
  page313_i211
#ISCELL
  standard offpage *
  page313_i212
#ISCELL
  standard offpage *
  page313_i213
#ISCELL
  standard offpage *
  page313_i214
#ISCELL
  standard offpage *
  page313_i215
#ISCELL
  standard offpage *
  page313_i216
#ISCELL
  standard offpage *
  page313_i22
#ISCELL
  standard offpage *
  page313_i23
#ISCELL
  standard offpage *
  page313_i24
#ISCELL
  standard offpage *
  page313_i25
#ISCELL
  standard offpage *
  page313_i26
#ISCELL
  standard offpage *
  page313_i27
#ISCELL
  standard offpage *
  page313_i28
#ISCELL
  standard offpage *
  page313_i29
#ISCELL
  standard offpage *
  page313_i3
#ISCELL
  standard offpage *
  page313_i30
#ISCELL
  standard offpage *
  page313_i31
#ISCELL
  standard offpage *
  page313_i32
#ISCELL
  standard offpage *
  page313_i33
#ISCELL
  standard offpage *
  page313_i34
#ISCELL
  standard offpage *
  page313_i35
#ISCELL
  standard offpage *
  page313_i36
#ISCELL
  standard offpage *
  page313_i37
#ISCELL
  standard offpage *
  page313_i38
#ISCELL
  standard offpage *
  page313_i39
#ISCELL
  standard offpage *
  page313_i4
#ISCELL
  standard offpage *
  page313_i40
#ISCELL
  standard offpage *
  page313_i41
#ISCELL
  standard offpage *
  page313_i42
#ISCELL
  standard offpage *
  page313_i43
#ISCELL
  standard offpage *
  page313_i44
#ISCELL
  standard offpage *
  page313_i45
#ISCELL
  standard offpage *
  page313_i46
#ISCELL
  standard offpage *
  page313_i47
#ISCELL
  standard offpage *
  page313_i48
#ISCELL
  standard offpage *
  page313_i49
#ISCELL
  standard offpage *
  page313_i5
#ISCELL
  standard offpage *
  page313_i50
#ISCELL
  standard offpage *
  page313_i51
#ISCELL
  standard offpage *
  page313_i52
#ISCELL
  standard offpage *
  page313_i53
#ISCELL
  standard offpage *
  page313_i54
#ISCELL
  standard offpage *
  page313_i55
#ISCELL
  standard offpage *
  page313_i56
#ISCELL
  standard offpage *
  page313_i57
#ISCELL
  standard offpage *
  page313_i58
#ISCELL
  standard offpage *
  page313_i59
#ISCELL
  standard offpage *
  page313_i6
#ISCELL
  standard offpage *
  page313_i60
#ISCELL
  standard offpage *
  page313_i61
#ISCELL
  standard offpage *
  page313_i62
#ISCELL
  standard offpage *
  page313_i63
#ISCELL
  standard offpage *
  page313_i64
#ISCELL
  standard offpage *
  page313_i65
#ISCELL
  standard offpage *
  page313_i7
#ISCELL
  standard offpage *
  page313_i76
#ISCELL
  standard offpage *
  page313_i77
#ISCELL
  standard offpage *
  page313_i78
#ISCELL
  standard offpage *
  page313_i79
#ISCELL
  standard offpage *
  page313_i8
#CELL
  pure_quanta q_res *
  page313_i83
#CELL
  pure_quanta q_res *
  page313_i84
#CELL
  pure_quanta q_res *
  page313_i85
#CELL
  pure_quanta q_res *
  page313_i86
#ISCELL
  standard offpage *
  page313_i87
#ISCELL
  standard offpage *
  page313_i88
#ISCELL
  standard offpage *
  page313_i9
#ISCELL
  standard offpage *
  page313_i99
#ISCELL
  mstr_misc dns *
  *
#ISCELL
  pure_quanta quanta_title_block_c *
  *
#CELL
  pure_quanta lcmxo3lf9400c5bg484c *
  page312_i1
#ISCELL
  standard offpage *
  page312_i10
#ISCELL
  standard offpage *
  page312_i100
#ISCELL
  standard offpage *
  page312_i101
#ISCELL
  standard offpage *
  page312_i102
#CELL
  pure_quanta q_res *
  page312_i103
#CELL
  pure_quanta q_res *
  page312_i104
#ISCELL
  standard offpage *
  page312_i105
#ISCELL
  standard offpage *
  page312_i106
#ISCELL
  standard offpage *
  page312_i107
#ISCELL
  standard offpage *
  page312_i108
#ISCELL
  standard offpage *
  page312_i109
#ISCELL
  standard offpage *
  page312_i11
#ISCELL
  standard offpage *
  page312_i110
#ISCELL
  standard offpage *
  page312_i111
#ISCELL
  standard offpage *
  page312_i112
#ISCELL
  standard offpage *
  page312_i113
#CELL
  pure_quanta q_res *
  page312_i114
#ISCELL
  standard offpage *
  page312_i115
#ISCELL
  standard offpage *
  page312_i116
#ISCELL
  standard offpage *
  page312_i117
#ISCELL
  standard offpage *
  page312_i118
#ISCELL
  standard offpage *
  page312_i119
#ISCELL
  standard offpage *
  page312_i12
#CELL
  pure_quanta q_res *
  page312_i120
#CELL
  pure_quanta q_res *
  page312_i121
#CELL
  pure_quanta q_res *
  page312_i122
#ISCELL
  standard offpage *
  page312_i123
#ISCELL
  standard offpage *
  page312_i124
#ISCELL
  standard offpage *
  page312_i125
#ISCELL
  standard offpage *
  page312_i126
#ISCELL
  standard offpage *
  page312_i127
#ISCELL
  standard offpage *
  page312_i128
#ISCELL
  standard offpage *
  page312_i129
#ISCELL
  standard offpage *
  page312_i13
#ISCELL
  standard offpage *
  page312_i132
#ISCELL
  standard offpage *
  page312_i133
#CELL
  pure_quanta q_res *
  page312_i134
#CELL
  pure_quanta q_res *
  page312_i135
#ISCELL
  standard offpage *
  page312_i136
#ISCELL
  standard offpage *
  page312_i137
#ISCELL
  standard offpage *
  page312_i138
#ISCELL
  standard offpage *
  page312_i14
#ISCELL
  standard offpage *
  page312_i140
#ISCELL
  standard offpage *
  page312_i142
#CELL
  pure_quanta q_res *
  page312_i143
#ISCELL
  standard offpage *
  page312_i144
#CELL
  pure_quanta q_res *
  page312_i145
#ISCELL
  standard offpage *
  page312_i146
#ISCELL
  standard offpage *
  page312_i148
#ISCELL
  standard offpage *
  page312_i15
#CELL
  pure_quanta q_res *
  page312_i150
#ISCELL
  standard offpage *
  page312_i152
#ISCELL
  standard offpage *
  page312_i153
#ISCELL
  standard offpage *
  page312_i154
#ISCELL
  standard offpage *
  page312_i156
#ISCELL
  standard offpage *
  page312_i157
#CELL
  pure_quanta q_res *
  page312_i158
#ISCELL
  standard offpage *
  page312_i159
#ISCELL
  standard offpage *
  page312_i160
#ISCELL
  standard offpage *
  page312_i161
#ISCELL
  standard offpage *
  page312_i162
#ISCELL
  standard offpage *
  page312_i163
#CELL
  pure_quanta q_res *
  page312_i164
#CELL
  pure_quanta q_res *
  page312_i165
#ISCELL
  standard offpage *
  page312_i166
#ISCELL
  standard offpage *
  page312_i167
#ISCELL
  standard offpage *
  page312_i168
#CELL
  pure_quanta q_res *
  page312_i169
#ISCELL
  standard offpage *
  page312_i17
#CELL
  pure_quanta q_res *
  page312_i170
#ISCELL
  standard offpage *
  page312_i171
#ISCELL
  standard offpage *
  page312_i172
#ISCELL
  standard offpage *
  page312_i173
#ISCELL
  standard offpage *
  page312_i174
#ISCELL
  standard offpage *
  page312_i175
#CELL
  pure_quanta q_res *
  page312_i176
#CELL
  pure_quanta q_res *
  page312_i177
#CELL
  pure_quanta q_res *
  page312_i178
#ISCELL
  standard offpage *
  page312_i179
#ISCELL
  standard offpage *
  page312_i18
#ISCELL
  standard offpage *
  page312_i180
#ISCELL
  standard offpage *
  page312_i181
#ISCELL
  standard offpage *
  page312_i182
#CELL
  pure_quanta q_res *
  page312_i183
#CELL
  pure_quanta q_res *
  page312_i184
#ISCELL
  standard offpage *
  page312_i185
#ISCELL
  standard offpage *
  page312_i186
#CELL
  pure_quanta conn3_210hp1030br1 *
  page312_i187
#ISCELL
  logical_power universal_power *
  page312_i188
#ISCELL
  logical_power universal_gnd *
  page312_i189
#ISCELL
  standard offpage *
  page312_i19
#CELL
  pure_quanta q_res *
  page312_i190
#CELL
  pure_quanta q_res *
  page312_i191
#ISCELL
  standard offpage *
  page312_i192
#ISCELL
  standard offpage *
  page312_i193
#ISCELL
  standard offpage *
  page312_i194
#ISCELL
  logical_power universal_power *
  page312_i2
#ISCELL
  standard offpage *
  page312_i20
#ISCELL
  standard offpage *
  page312_i21
#ISCELL
  standard offpage *
  page312_i212
#CELL
  pure_quanta q_res *
  page312_i213
#ISCELL
  standard offpage *
  page312_i214
#ISCELL
  standard offpage *
  page312_i215
#ISCELL
  standard offpage *
  page312_i216
#CELL
  pure_quanta q_res *
  page312_i217
#ISCELL
  standard offpage *
  page312_i23
#ISCELL
  standard offpage *
  page312_i24
#ISCELL
  standard offpage *
  page312_i25
#ISCELL
  standard offpage *
  page312_i26
#ISCELL
  standard offpage *
  page312_i27
#ISCELL
  standard offpage *
  page312_i28
#ISCELL
  standard offpage *
  page312_i29
#CELL
  pure_quanta q_res *
  page312_i3
#ISCELL
  standard offpage *
  page312_i30
#ISCELL
  standard offpage *
  page312_i31
#ISCELL
  standard offpage *
  page312_i32
#ISCELL
  standard offpage *
  page312_i34
#ISCELL
  standard offpage *
  page312_i36
#ISCELL
  standard offpage *
  page312_i37
#CELL
  pure_quanta q_res *
  page312_i38
#CELL
  pure_quanta q_cap *
  page312_i39
#ISCELL
  logical_power universal_power *
  page312_i4
#ISCELL
  logical_power universal_gnd *
  page312_i40
#ISCELL
  standard offpage *
  page312_i41
#ISCELL
  standard offpage *
  page312_i42
#ISCELL
  standard offpage *
  page312_i43
#ISCELL
  standard offpage *
  page312_i44
#ISCELL
  standard offpage *
  page312_i45
#ISCELL
  standard offpage *
  page312_i46
#ISCELL
  standard offpage *
  page312_i47
#ISCELL
  standard offpage *
  page312_i48
#CELL
  pure_quanta q_res *
  page312_i5
#ISCELL
  standard offpage *
  page312_i50
#ISCELL
  standard offpage *
  page312_i51
#ISCELL
  standard offpage *
  page312_i52
#ISCELL
  standard offpage *
  page312_i53
#ISCELL
  standard offpage *
  page312_i54
#ISCELL
  standard offpage *
  page312_i55
#ISCELL
  standard offpage *
  page312_i56
#ISCELL
  standard offpage *
  page312_i57
#ISCELL
  standard offpage *
  page312_i58
#ISCELL
  standard offpage *
  page312_i59
#ISCELL
  standard offpage *
  page312_i6
#ISCELL
  standard offpage *
  page312_i60
#ISCELL
  standard offpage *
  page312_i61
#ISCELL
  standard offpage *
  page312_i62
#ISCELL
  standard offpage *
  page312_i63
#ISCELL
  standard offpage *
  page312_i64
#ISCELL
  standard offpage *
  page312_i65
#ISCELL
  standard offpage *
  page312_i66
#ISCELL
  standard offpage *
  page312_i67
#ISCELL
  standard offpage *
  page312_i68
#ISCELL
  standard offpage *
  page312_i69
#ISCELL
  standard offpage *
  page312_i7
#ISCELL
  standard offpage *
  page312_i70
#ISCELL
  standard offpage *
  page312_i71
#ISCELL
  standard offpage *
  page312_i72
#ISCELL
  standard offpage *
  page312_i73
#ISCELL
  standard offpage *
  page312_i74
#ISCELL
  standard offpage *
  page312_i75
#ISCELL
  standard offpage *
  page312_i76
#ISCELL
  standard offpage *
  page312_i77
#ISCELL
  standard offpage *
  page312_i78
#ISCELL
  standard offpage *
  page312_i79
#ISCELL
  standard offpage *
  page312_i8
#CELL
  pure_quanta q_res *
  page312_i80
#ISCELL
  standard offpage *
  page312_i81
#ISCELL
  standard offpage *
  page312_i82
#ISCELL
  standard offpage *
  page312_i84
#ISCELL
  standard offpage *
  page312_i85
#CELL
  pure_quanta q_res *
  page312_i86
#ISCELL
  logical_power universal_power *
  page312_i87
#ISCELL
  standard offpage *
  page312_i88
#CELL
  pure_quanta q_res *
  page312_i89
#ISCELL
  standard offpage *
  page312_i9
#ISCELL
  standard offpage *
  page312_i90
#ISCELL
  standard offpage *
  page312_i91
#ISCELL
  standard offpage *
  page312_i92
#CELL
  pure_quanta q_res *
  page312_i93
#ISCELL
  standard offpage *
  page312_i94
#ISCELL
  standard offpage *
  page312_i95
#ISCELL
  standard offpage *
  page312_i96
#CELL
  pure_quanta q_res *
  page312_i97
#CELL
  pure_quanta q_res *
  page312_i98
#ISCELL
  standard offpage *
  page312_i99
#ISCELL
  logical_power design_note *
  *
#ISCELL
  pure_quanta quanta_title_block_c *
  *
#ISCELL
  standard offpage *
  page311_i1
#ISCELL
  standard offpage *
  page311_i10
#ISCELL
  standard offpage *
  page311_i14
#ISCELL
  standard offpage *
  page311_i15
#ISCELL
  standard offpage *
  page311_i16
#ISCELL
  standard offpage *
  page311_i17
#ISCELL
  standard offpage *
  page311_i18
#ISCELL
  standard offpage *
  page311_i19
#ISCELL
  standard offpage *
  page311_i2
#ISCELL
  standard offpage *
  page311_i20
#ISCELL
  standard offpage *
  page311_i21
#ISCELL
  standard offpage *
  page311_i22
#ISCELL
  standard offpage *
  page311_i23
#ISCELL
  standard offpage *
  page311_i24
#ISCELL
  standard offpage *
  page311_i25
#ISCELL
  standard offpage *
  page311_i26
#ISCELL
  standard offpage *
  page311_i27
#ISCELL
  logical_power universal_power *
  page311_i28
#CELL
  pure_quanta q_res *
  page311_i29
#ISCELL
  logical_power universal_power *
  page311_i3
#ISCELL
  standard offpage *
  page311_i30
#ISCELL
  standard offpage *
  page311_i31
#ISCELL
  standard offpage *
  page311_i32
#CELL
  pure_quanta lcmxo3lf9400c5bg484c *
  page311_i33
#ISCELL
  standard offpage *
  page311_i34
#ISCELL
  standard offpage *
  page311_i35
#ISCELL
  standard offpage *
  page311_i36
#ISCELL
  standard offpage *
  page311_i37
#ISCELL
  standard offpage *
  page311_i38
#ISCELL
  standard offpage *
  page311_i39
#CELL
  pure_quanta q_res *
  page311_i4
#ISCELL
  standard offpage *
  page311_i40
#ISCELL
  standard offpage *
  page311_i41
#ISCELL
  standard offpage *
  page311_i42
#ISCELL
  standard offpage *
  page311_i43
#ISCELL
  standard offpage *
  page311_i44
#ISCELL
  standard offpage *
  page311_i45
#ISCELL
  standard offpage *
  page311_i46
#ISCELL
  standard offpage *
  page311_i47
#ISCELL
  standard offpage *
  page311_i48
#ISCELL
  standard offpage *
  page311_i49
#ISCELL
  standard offpage *
  page311_i5
#ISCELL
  standard offpage *
  page311_i50
#ISCELL
  standard offpage *
  page311_i51
#ISCELL
  standard offpage *
  page311_i52
#ISCELL
  standard offpage *
  page311_i55
#ISCELL
  standard offpage *
  page311_i56
#ISCELL
  standard offpage *
  page311_i57
#ISCELL
  standard offpage *
  page311_i58
#ISCELL
  standard offpage *
  page311_i59
#ISCELL
  standard offpage *
  page311_i60
#ISCELL
  standard offpage *
  page311_i62
#ISCELL
  standard offpage *
  page311_i68
#ISCELL
  standard offpage *
  page311_i69
#ISCELL
  standard offpage *
  page311_i7
#CELL
  pure_quanta lcmxo3lf9400c5bg484c *
  page311_i70
#ISCELL
  standard offpage *
  page311_i71
#ISCELL
  standard offpage *
  page311_i72
#ISCELL
  standard offpage *
  page311_i73
#ISCELL
  standard offpage *
  page311_i74
#ISCELL
  standard offpage *
  page311_i75
#ISCELL
  standard offpage *
  page311_i76
#ISCELL
  standard offpage *
  page311_i77
#ISCELL
  standard offpage *
  page311_i78
#CELL
  pure_quanta q_res *
  page311_i79
#ISCELL
  standard offpage *
  page311_i8
#ISCELL
  standard offpage *
  page311_i80
#ISCELL
  standard offpage *
  page311_i81
#ISCELL
  standard offpage *
  page311_i82
#ISCELL
  standard offpage *
  page311_i83
#ISCELL
  standard offpage *
  page311_i84
#ISCELL
  standard offpage *
  page311_i85
#CELL
  pure_quanta q_res *
  page311_i86
#ISCELL
  standard offpage *
  page311_i87
#ISCELL
  standard offpage *
  page311_i88
#ISCELL
  standard offpage *
  page311_i89
#ISCELL
  standard offpage *
  page311_i9
#CELL
  pure_quanta q_res *
  page311_i90
#ISCELL
  standard offpage *
  page311_i91
#ISCELL
  standard offpage *
  page311_i92
#ISCELL
  standard offpage *
  page311_i93
#ISCELL
  standard offpage *
  page311_i94
#CELL
  pure_quanta q_res *
  page311_i95
#ISCELL
  standard offpage *
  page311_i96
#ISCELL
  standard offpage *
  page311_i97
#ISCELL
  standard offpage *
  page311_i98
#ISCELL
  pure_quanta quanta_title_block_c *
  *
#CELL
  pure_quanta lcmxo3lf9400c5bg484c *
  page202_i1
#ISCELL
  logical_power universal_gnd *
  page202_i10
#CELL
  pure_quanta q_cap *
  page202_i100
#CELL
  pure_quanta q_cap *
  page202_i101
#CELL
  pure_quanta lcmxo3lf9400c5bg484c *
  page202_i102
#ISCELL
  logical_power universal_power *
  page202_i103
#ISCELL
  logical_power universal_power *
  page202_i104
#ISCELL
  logical_power universal_power *
  page202_i105
#ISCELL
  logical_power universal_power *
  page202_i106
#CELL
  pure_quanta q_cap *
  page202_i107
#CELL
  pure_quanta q_res *
  page202_i108
#ISCELL
  logical_power universal_power *
  page202_i109
#ISCELL
  logical_power universal_power *
  page202_i11
#CELL
  pure_quanta q_res *
  page202_i119
#CELL
  pure_quanta q_cap *
  page202_i12
#CELL
  pure_quanta q_cap *
  page202_i120
#CELL
  pure_quanta q_cap *
  page202_i121
#ISCELL
  logical_power universal_gnd *
  page202_i13
#ISCELL
  logical_power universal_power *
  page202_i14
#CELL
  pure_quanta q_cap *
  page202_i15
#ISCELL
  logical_power universal_gnd *
  page202_i16
#ISCELL
  logical_power universal_power *
  page202_i17
#CELL
  pure_quanta q_cap *
  page202_i18
#ISCELL
  logical_power universal_gnd *
  page202_i19
#ISCELL
  logical_power universal_power *
  page202_i2
#CELL
  pure_quanta q_cap *
  page202_i20
#CELL
  pure_quanta q_cap *
  page202_i21
#CELL
  pure_quanta q_cap *
  page202_i22
#CELL
  pure_quanta q_cap *
  page202_i23
#CELL
  pure_quanta q_cap *
  page202_i24
#CELL
  pure_quanta q_cap *
  page202_i25
#CELL
  pure_quanta q_cap *
  page202_i26
#CELL
  pure_quanta q_cap *
  page202_i27
#CELL
  pure_quanta q_cap *
  page202_i28
#CELL
  pure_quanta q_cap *
  page202_i29
#CELL
  pure_quanta q_cap *
  page202_i3
#CELL
  pure_quanta q_cap *
  page202_i30
#ISCELL
  logical_power universal_power *
  page202_i32
#CELL
  pure_quanta q_cap *
  page202_i33
#CELL
  pure_quanta q_cap *
  page202_i34
#CELL
  pure_quanta q_cap *
  page202_i35
#CELL
  pure_quanta q_cap *
  page202_i36
#CELL
  pure_quanta q_cap *
  page202_i37
#CELL
  pure_quanta q_cap *
  page202_i38
#CELL
  pure_quanta q_cap *
  page202_i39
#ISCELL
  logical_power universal_gnd *
  page202_i4
#CELL
  pure_quanta q_cap *
  page202_i40
#CELL
  pure_quanta q_cap *
  page202_i41
#CELL
  pure_quanta q_cap *
  page202_i42
#CELL
  pure_quanta q_cap *
  page202_i43
#CELL
  pure_quanta q_cap *
  page202_i44
#CELL
  pure_quanta q_cap *
  page202_i45
#CELL
  pure_quanta q_cap *
  page202_i46
#CELL
  pure_quanta q_cap *
  page202_i47
#CELL
  pure_quanta q_cap *
  page202_i48
#CELL
  pure_quanta q_cap *
  page202_i49
#CELL
  pure_quanta q_cap *
  page202_i5
#CELL
  pure_quanta q_cap *
  page202_i50
#CELL
  pure_quanta q_cap *
  page202_i51
#CELL
  pure_quanta q_cap *
  page202_i52
#CELL
  pure_quanta q_cap *
  page202_i53
#CELL
  pure_quanta q_cap *
  page202_i54
#CELL
  pure_quanta q_cap *
  page202_i55
#CELL
  pure_quanta q_cap *
  page202_i56
#CELL
  pure_quanta q_cap *
  page202_i57
#CELL
  pure_quanta q_cap *
  page202_i58
#CELL
  pure_quanta q_cap *
  page202_i59
#CELL
  pure_quanta q_res *
  page202_i60
#ISCELL
  logical_power universal_power *
  page202_i61
#CELL
  pure_quanta q_cap *
  page202_i62
#CELL
  pure_quanta q_res *
  page202_i63
#CELL
  pure_quanta q_cap *
  page202_i64
#CELL
  pure_quanta q_cap *
  page202_i65
#CELL
  pure_quanta q_cap *
  page202_i66
#CELL
  pure_quanta q_res *
  page202_i67
#ISCELL
  logical_power universal_power *
  page202_i68
#ISCELL
  logical_power universal_power *
  page202_i69
#CELL
  pure_quanta q_cap *
  page202_i70
#CELL
  pure_quanta q_cap *
  page202_i71
#CELL
  pure_quanta q_res *
  page202_i72
#ISCELL
  logical_power universal_power *
  page202_i73
#CELL
  pure_quanta q_cap *
  page202_i74
#ISCELL
  logical_power universal_gnd *
  page202_i75
#CELL
  pure_quanta q_cap *
  page202_i76
#CELL
  pure_quanta q_cap *
  page202_i77
#ISCELL
  logical_power universal_power *
  page202_i78
#ISCELL
  logical_power universal_gnd *
  page202_i79
#ISCELL
  logical_power universal_power *
  page202_i8
#CELL
  pure_quanta q_cap *
  page202_i80
#CELL
  pure_quanta q_res *
  page202_i81
#CELL
  pure_quanta q_cap *
  page202_i82
#CELL
  pure_quanta q_cap *
  page202_i9
#ISCELL
  logical_power universal_power *
  page202_i92
#ISCELL
  logical_power universal_power *
  page202_i93
#ISCELL
  logical_power universal_power *
  page202_i94
#ISCELL
  logical_power universal_power *
  page202_i95
#ISCELL
  logical_power universal_power *
  page202_i96
#CELL
  pure_quanta q_cap *
  page202_i97
#ISCELL
  logical_power universal_gnd *
  page202_i98
#CELL
  pure_quanta q_cap *
  page202_i99
#ISCELL
  pure_quanta quanta_title_block_c *
  *
#CELL
  pure_quanta mosfet_n *
  page207_i236
#ISCELL
  logical_power universal_gnd *
  page207_i237
#ISCELL
  standard offpage *
  page207_i238
#ISCELL
  logical_power universal_power *
  page207_i240
#ISCELL
  logical_power universal_gnd *
  page207_i267
#CELL
  pure_quanta q_res *
  page207_i268
#ISCELL
  logical_power universal_gnd *
  page207_i269
#ISCELL
  logical_power universal_power *
  page207_i270
#CELL
  pure_quanta mosfet_nch_gds_esd_protected *
  page207_i272
#CELL
  pure_quanta q_res *
  page207_i273
#ISCELL
  logical_power universal_power *
  page207_i274
#CELL
  pure_quanta q_res *
  page207_i275
#ISCELL
  standard offpage *
  page207_i276
#CELL
  pure_quanta q_led *
  page207_i277
#CELL
  pure_quanta q_res *
  page207_i278
#CELL
  pure_quanta q_led *
  page207_i279
#CELL
  pure_quanta q_res *
  page207_i280
#ISCELL
  mstr_misc dns *
  *
#ISCELL
  pure_quanta quanta_title_block_c *
  *
#ISCELL
  standard offpage *
  page208_i1
#CELL
  pure_quanta q_res *
  page208_i10
#CELL
  pure_quanta q_res *
  page208_i11
#CELL
  pure_quanta q_res *
  page208_i12
#CELL
  pure_quanta q_res *
  page208_i13
#CELL
  pure_quanta q_res *
  page208_i14
#CELL
  pure_quanta q_res *
  page208_i15
#CELL
  pure_quanta q_res *
  page208_i16
#CELL
  pure_quanta q_res *
  page208_i17
#CELL
  pure_quanta q_res *
  page208_i18
#CELL
  pure_quanta q_res *
  page208_i19
#ISCELL
  standard offpage *
  page208_i2
#CELL
  pure_quanta q_res *
  page208_i20
#CELL
  pure_quanta q_res *
  page208_i21
#CELL
  pure_quanta q_res *
  page208_i22
#CELL
  pure_quanta q_res *
  page208_i23
#CELL
  pure_quanta q_res *
  page208_i24
#CELL
  pure_quanta q_res *
  page208_i25
#CELL
  pure_quanta q_res *
  page208_i26
#ISCELL
  standard offpage *
  page208_i27
#ISCELL
  standard offpage *
  page208_i28
#ISCELL
  standard offpage *
  page208_i29
#ISCELL
  standard offpage *
  page208_i3
#ISCELL
  standard offpage *
  page208_i30
#ISCELL
  standard offpage *
  page208_i31
#ISCELL
  standard offpage *
  page208_i32
#ISCELL
  standard offpage *
  page208_i33
#ISCELL
  standard offpage *
  page208_i34
#ISCELL
  standard offpage *
  page208_i35
#ISCELL
  standard offpage *
  page208_i36
#ISCELL
  standard offpage *
  page208_i37
#ISCELL
  standard offpage *
  page208_i38
#ISCELL
  standard offpage *
  page208_i39
#CELL
  pure_quanta q_res *
  page208_i4
#ISCELL
  standard offpage *
  page208_i40
#ISCELL
  standard offpage *
  page208_i41
#ISCELL
  standard offpage *
  page208_i42
#ISCELL
  standard offpage *
  page208_i43
#ISCELL
  standard offpage *
  page208_i44
#ISCELL
  standard offpage *
  page208_i45
#ISCELL
  standard offpage *
  page208_i46
#ISCELL
  standard offpage *
  page208_i47
#ISCELL
  standard offpage *
  page208_i48
#ISCELL
  standard offpage *
  page208_i49
#CELL
  pure_quanta q_res *
  page208_i5
#ISCELL
  logical_power universal_gnd *
  page208_i50
#CELL
  pure_quanta q_res *
  page208_i51
#CELL
  pure_quanta q_res *
  page208_i52
#CELL
  pure_quanta q_res *
  page208_i53
#CELL
  pure_quanta q_res *
  page208_i54
#CELL
  pure_quanta q_res *
  page208_i55
#CELL
  pure_quanta q_res *
  page208_i56
#CELL
  pure_quanta q_res *
  page208_i57
#CELL
  pure_quanta q_res *
  page208_i58
#CELL
  pure_quanta q_res *
  page208_i59
#CELL
  pure_quanta q_res *
  page208_i6
#ISCELL
  standard offpage *
  page208_i60
#ISCELL
  standard offpage *
  page208_i61
#ISCELL
  standard offpage *
  page208_i62
#ISCELL
  standard offpage *
  page208_i63
#ISCELL
  standard offpage *
  page208_i64
#ISCELL
  standard offpage *
  page208_i65
#CELL
  pure_quanta q_res *
  page208_i66
#ISCELL
  standard offpage *
  page208_i67
#CELL
  pure_quanta q_res *
  page208_i7
#CELL
  pure_quanta q_res *
  page208_i8
#CELL
  pure_quanta q_res *
  page208_i9
#ISCELL
  logical_power cad_note *
  *
#ISCELL
  mstr_misc dns *
  *
#ISCELL
  pure_quanta quanta_title_block_c *
  *
#ISCELL
  standard offpage *
  page209_i1
#ISCELL
  logical_power universal_gnd *
  page209_i10
#CELL
  pure_quanta q_res *
  page209_i11
#ISCELL
  logical_power universal_power *
  page209_i12
#CELL
  pure_quanta q_res *
  page209_i13
#CELL
  pure_quanta q_res *
  page209_i14
#CELL
  pure_quanta q_res *
  page209_i15
#CELL
  pure_quanta q_res *
  page209_i16
#CELL
  pure_quanta q_res *
  page209_i17
#ISCELL
  standard offpage *
  page209_i18
#ISCELL
  logical_power universal_power *
  page209_i19
#ISCELL
  standard offpage *
  page209_i2
#ISCELL
  logical_power universal_gnd *
  page209_i20
#CELL
  pure_quanta q_res *
  page209_i21
#CELL
  pure_quanta q_res *
  page209_i22
#CELL
  pure_quanta q_res *
  page209_i23
#CELL
  pure_quanta q_res *
  page209_i24
#ISCELL
  standard offpage *
  page209_i25
#ISCELL
  standard offpage *
  page209_i26
#ISCELL
  standard offpage *
  page209_i27
#ISCELL
  standard offpage *
  page209_i28
#ISCELL
  standard offpage *
  page209_i29
#CELL
  pure_quanta q_cap *
  page209_i3
#ISCELL
  standard offpage *
  page209_i30
#ISCELL
  standard offpage *
  page209_i31
#ISCELL
  standard offpage *
  page209_i32
#ISCELL
  standard offpage *
  page209_i33
#ISCELL
  standard offpage *
  page209_i34
#CELL
  pure_quanta q_res *
  page209_i35
#CELL
  pure_quanta q_res *
  page209_i36
#CELL
  pure_quanta q_res *
  page209_i37
#CELL
  pure_quanta q_res *
  page209_i38
#CELL
  pure_quanta q_res *
  page209_i39
#CELL
  pure_quanta q_cap *
  page209_i4
#CELL
  pure_quanta q_res *
  page209_i40
#CELL
  pure_quanta q_res *
  page209_i41
#CELL
  pure_quanta q_res *
  page209_i42
#CELL
  pure_quanta q_res *
  page209_i43
#CELL
  pure_quanta q_res *
  page209_i44
#ISCELL
  logical_power universal_power *
  page209_i45
#CELL
  pure_quanta q_res *
  page209_i46
#ISCELL
  logical_power universal_gnd *
  page209_i47
#ISCELL
  logical_power universal_gnd *
  page209_i5
#ISCELL
  standard offpage *
  page209_i6
#ISCELL
  standard offpage *
  page209_i7
#ISCELL
  standard offpage *
  page209_i8
#ISCELL
  standard offpage *
  page209_i9
#ISCELL
  mstr_misc dns *
  *
#ISCELL
  pure_quanta quanta_title_block_c *
  *
#ISCELL
  standard offpage *
  page210_i15
#CELL
  pure_quanta q_res *
  page210_i19
#CELL
  pure_quanta q_res *
  page210_i20
#ISCELL
  standard offpage *
  page210_i21
#CELL
  pure_quanta q_res *
  page210_i25
#ISCELL
  standard offpage *
  page210_i26
#ISCELL
  standard offpage *
  page210_i29
#CELL
  pure_quanta q_res *
  page210_i54
#ISCELL
  standard offpage *
  page210_i55
#ISCELL
  standard offpage *
  page210_i58
#CELL
  pure_quanta q_res *
  page210_i59
#CELL
  pure_quanta q_res *
  page210_i60
#CELL
  pure_quanta q_res *
  page210_i61
#ISCELL
  logical_power universal_power *
  page210_i62
#CELL
  pure_quanta q_res *
  page210_i63
#ISCELL
  logical_power universal_gnd *
  page210_i64
#ISCELL
  standard offpage *
  page210_i65
#ISCELL
  standard offpage *
  page210_i67
#ISCELL
  standard offpage *
  page210_i72
#CELL
  pure_quanta q_res *
  page210_i75
#CELL
  pure_quanta q_res *
  page210_i76
#ISCELL
  logical_power universal_power *
  page210_i77
#ISCELL
  logical_power universal_gnd *
  page210_i78
#CELL
  pure_quanta conn8_210hp1080br1 *
  page210_i79
#ISCELL
  standard offpage *
  page210_i81
#ISCELL
  standard offpage *
  page210_i82
#ISCELL
  standard offpage *
  page210_i83
#ISCELL
  standard offpage *
  page210_i84
#CELL
  pure_quanta q_cap *
  page210_i86
#CELL
  pure_quanta q_cap *
  page210_i88
#ISCELL
  logical_power universal_gnd *
  page210_i89
#ISCELL
  logical_power universal_gnd *
  page210_i90
#CELL
  pure_quanta schottky_12 *
  page210_i91
#ISCELL
  logical_power universal_power *
  page210_i92
#ISCELL
  pure_quanta quanta_title_block_c *
  *
#ISCELL
  standard offpage *
  page211_i1
#CELL
  pure_quanta q_res *
  page211_i10
#ISCELL
  standard offpage *
  page211_i100
#ISCELL
  standard offpage *
  page211_i101
#ISCELL
  standard offpage *
  page211_i102
#ISCELL
  standard offpage *
  page211_i104
#ISCELL
  standard offpage *
  page211_i105
#ISCELL
  standard offpage *
  page211_i108
#ISCELL
  standard offpage *
  page211_i109
#ISCELL
  standard offpage *
  page211_i11
#CELL
  pure_quanta q_res *
  page211_i110
#CELL
  pure_quanta q_res *
  page211_i111
#ISCELL
  standard offpage *
  page211_i116
#ISCELL
  standard offpage *
  page211_i117
#ISCELL
  standard offpage *
  page211_i12
#ISCELL
  standard offpage *
  page211_i120
#ISCELL
  standard offpage *
  page211_i121
#CELL
  pure_quanta q_res *
  page211_i122
#CELL
  pure_quanta q_res *
  page211_i123
#ISCELL
  standard offpage *
  page211_i125
#ISCELL
  standard offpage *
  page211_i126
#CELL
  pure_quanta q_res *
  page211_i127
#ISCELL
  standard offpage *
  page211_i128
#CELL
  pure_quanta q_res *
  page211_i129
#CELL
  pure_quanta q_res *
  page211_i13
#ISCELL
  standard offpage *
  page211_i14
#CELL
  pure_quanta q_res *
  page211_i15
#ISCELL
  standard offpage *
  page211_i16
#ISCELL
  standard offpage *
  page211_i17
#ISCELL
  standard offpage *
  page211_i18
#ISCELL
  standard offpage *
  page211_i19
#ISCELL
  standard offpage *
  page211_i20
#CELL
  pure_quanta q_res *
  page211_i21
#ISCELL
  standard offpage *
  page211_i22
#CELL
  pure_quanta q_res *
  page211_i23
#CELL
  pure_quanta q_res *
  page211_i24
#CELL
  pure_quanta q_res *
  page211_i25
#ISCELL
  standard offpage *
  page211_i26
#ISCELL
  standard offpage *
  page211_i27
#ISCELL
  standard offpage *
  page211_i28
#ISCELL
  standard offpage *
  page211_i3
#ISCELL
  standard offpage *
  page211_i42
#ISCELL
  standard offpage *
  page211_i43
#CELL
  pure_quanta q_res *
  page211_i44
#ISCELL
  standard offpage *
  page211_i45
#ISCELL
  standard offpage *
  page211_i47
#CELL
  pure_quanta q_res *
  page211_i48
#CELL
  pure_quanta q_res *
  page211_i49
#ISCELL
  standard offpage *
  page211_i50
#ISCELL
  standard offpage *
  page211_i51
#ISCELL
  standard offpage *
  page211_i52
#ISCELL
  standard offpage *
  page211_i53
#CELL
  pure_quanta q_res *
  page211_i54
#ISCELL
  standard offpage *
  page211_i6
#CELL
  pure_quanta q_res *
  page211_i62
#ISCELL
  standard offpage *
  page211_i63
#ISCELL
  standard offpage *
  page211_i64
#ISCELL
  standard offpage *
  page211_i66
#ISCELL
  standard offpage *
  page211_i67
#CELL
  pure_quanta q_res *
  page211_i68
#ISCELL
  standard offpage *
  page211_i7
#ISCELL
  standard offpage *
  page211_i77
#ISCELL
  standard offpage *
  page211_i80
#CELL
  pure_quanta q_res *
  page211_i81
#CELL
  pure_quanta q_res *
  page211_i82
#ISCELL
  standard offpage *
  page211_i83
#CELL
  pure_quanta q_res *
  page211_i84
#ISCELL
  standard offpage *
  page211_i85
#ISCELL
  standard offpage *
  page211_i86
#ISCELL
  standard offpage *
  page211_i87
#CELL
  pure_quanta q_res *
  page211_i88
#ISCELL
  standard offpage *
  page211_i89
#CELL
  pure_quanta q_res *
  page211_i9
#ISCELL
  standard offpage *
  page211_i90
#CELL
  pure_quanta q_res *
  page211_i91
#ISCELL
  standard offpage *
  page211_i92
#ISCELL
  standard offpage *
  page211_i93
#ISCELL
  standard offpage *
  page211_i94
#ISCELL
  standard offpage *
  page211_i95
#CELL
  pure_quanta q_res *
  page211_i96
#ISCELL
  standard offpage *
  page211_i97
#CELL
  pure_quanta q_res *
  page211_i98
#CELL
  pure_quanta q_res *
  page211_i99
#ISCELL
  pure_quanta quanta_title_block_c *
  *
#ISCELL
  standard offpage *
  page212_i1
#CELL
  pure_quanta q_res *
  page212_i10
#ISCELL
  standard offpage *
  page212_i100
#CELL
  pure_quanta q_res *
  page212_i105
#ISCELL
  standard offpage *
  page212_i111
#CELL
  pure_quanta q_res *
  page212_i113
#ISCELL
  standard offpage *
  page212_i126
#CELL
  pure_quanta q_res *
  page212_i127
#ISCELL
  standard offpage *
  page212_i128
#CELL
  pure_quanta q_res *
  page212_i129
#ISCELL
  standard offpage *
  page212_i13
#CELL
  pure_quanta q_res *
  page212_i130
#ISCELL
  standard offpage *
  page212_i131
#ISCELL
  standard offpage *
  page212_i14
#CELL
  pure_quanta q_res *
  page212_i15
#ISCELL
  standard offpage *
  page212_i16
#CELL
  pure_quanta q_res *
  page212_i17
#ISCELL
  standard offpage *
  page212_i18
#CELL
  pure_quanta mosfet_n *
  page212_i19
#ISCELL
  standard offpage *
  page212_i2
#ISCELL
  standard offpage *
  page212_i20
#CELL
  pure_quanta q_res *
  page212_i24
#ISCELL
  logical_power universal_power *
  page212_i25
#ISCELL
  logical_power universal_gnd *
  page212_i26
#CELL
  pure_quanta q_res *
  page212_i27
#ISCELL
  standard offpage *
  page212_i28
#ISCELL
  standard offpage *
  page212_i42
#ISCELL
  standard offpage *
  page212_i43
#CELL
  pure_quanta q_res *
  page212_i44
#ISCELL
  standard offpage *
  page212_i45
#ISCELL
  standard offpage *
  page212_i46
#ISCELL
  standard offpage *
  page212_i49
#ISCELL
  standard offpage *
  page212_i5
#ISCELL
  standard offpage *
  page212_i53
#ISCELL
  standard offpage *
  page212_i54
#CELL
  pure_quanta q_res *
  page212_i55
#CELL
  pure_quanta q_res *
  page212_i56
#ISCELL
  standard offpage *
  page212_i57
#ISCELL
  standard offpage *
  page212_i59
#ISCELL
  standard offpage *
  page212_i6
#CELL
  pure_quanta q_res *
  page212_i7
#ISCELL
  standard offpage *
  page212_i73
#ISCELL
  standard offpage *
  page212_i8
#CELL
  pure_quanta q_res *
  page212_i86
#CELL
  pure_quanta q_res *
  page212_i87
#ISCELL
  standard offpage *
  page212_i88
#ISCELL
  standard offpage *
  page212_i9
#ISCELL
  standard offpage *
  page212_i90
#CELL
  pure_quanta q_res *
  page212_i91
#CELL
  pure_quanta q_res *
  page212_i92
#ISCELL
  logical_power universal_gnd *
  page212_i93
#CELL
  pure_quanta q_res *
  page212_i94
#ISCELL
  standard offpage *
  page212_i95
#ISCELL
  standard offpage *
  page212_i96
#ISCELL
  standard offpage *
  page212_i97
#ISCELL
  logical_power cad_note *
  *
#ISCELL
  mstr_misc dns *
  *
#ISCELL
  pure_quanta quanta_title_block_c *
  *
#ISCELL
  standard offpage *
  page213_i1
#ISCELL
  standard offpage *
  page213_i10
#ISCELL
  standard offpage *
  page213_i12
#ISCELL
  logical_power universal_gnd *
  page213_i17
#CELL
  pure_quanta q_res *
  page213_i18
#ISCELL
  logical_power universal_power *
  page213_i19
#CELL
  pure_quanta 74lvc2g17gw *
  page213_i2
#ISCELL
  logical_power universal_gnd *
  page213_i20
#CELL
  pure_quanta mosfet_nch_dual *
  page213_i21
#CELL
  pure_quanta q_res *
  page213_i22
#ISCELL
  logical_power universal_power *
  page213_i23
#CELL
  pure_quanta mosfet_nch_dual *
  page213_i27
#ISCELL
  standard offpage *
  page213_i28
#CELL
  pure_quanta q_res *
  page213_i29
#ISCELL
  logical_power universal_gnd *
  page213_i3
#ISCELL
  standard offpage *
  page213_i30
#ISCELL
  logical_power universal_power *
  page213_i31
#CELL
  pure_quanta q_res *
  page213_i32
#CELL
  pure_quanta q_res *
  page213_i33
#ISCELL
  logical_power universal_gnd *
  page213_i34
#CELL
  pure_quanta q_cap *
  page213_i35
#ISCELL
  logical_power universal_power *
  page213_i36
#CELL
  pure_quanta 74lvc2g07dw7 *
  page213_i37
#ISCELL
  logical_power universal_gnd *
  page213_i38
#ISCELL
  logical_power universal_power *
  page213_i39
#ISCELL
  logical_power universal_gnd *
  page213_i4
#CELL
  pure_quanta q_res *
  page213_i40
#CELL
  pure_quanta q_res *
  page213_i41
#CELL
  pure_quanta q_cap *
  page213_i42
#ISCELL
  logical_power universal_gnd *
  page213_i43
#ISCELL
  standard offpage *
  page213_i44
#CELL
  pure_quanta q_cap *
  page213_i5
#ISCELL
  logical_power universal_power *
  page213_i6
#CELL
  pure_quanta q_res *
  page213_i7
#ISCELL
  logical_power universal_power *
  page213_i8
#ISCELL
  pure_quanta quanta_title_block_c *
  *
#ISCELL
  logical_power universal_gnd *
  page322_i10
#CELL
  pure_quanta q_cap *
  page322_i101
#ISCELL
  logical_power universal_gnd *
  page322_i102
#ISCELL
  logical_power universal_power *
  page322_i105
#CELL
  pure_quanta q_cap *
  page322_i106
#ISCELL
  logical_power universal_gnd *
  page322_i107
#ISCELL
  logical_power universal_power *
  page322_i11
#ISCELL
  logical_power universal_power *
  page322_i110
#CELL
  pure_quanta q_cap *
  page322_i111
#ISCELL
  logical_power universal_gnd *
  page322_i112
#ISCELL
  logical_power universal_power *
  page322_i115
#ISCELL
  standard offpage *
  page322_i116
#ISCELL
  standard offpage *
  page322_i117
#ISCELL
  standard offpage *
  page322_i118
#ISCELL
  standard offpage *
  page322_i119
#ISCELL
  standard offpage *
  page322_i120
#ISCELL
  standard offpage *
  page322_i121
#ISCELL
  standard offpage *
  page322_i122
#ISCELL
  standard offpage *
  page322_i123
#ISCELL
  standard offpage *
  page322_i126
#CELL
  pure_quanta q_res *
  page322_i128
#CELL
  pure_quanta q_res *
  page322_i129
#CELL
  pure_quanta q_res *
  page322_i130
#CELL
  pure_quanta q_res *
  page322_i131
#ISCELL
  logical_power universal_power *
  page322_i132
#CELL
  pure_quanta q_res *
  page322_i157
#CELL
  pure_quanta q_res *
  page322_i158
#CELL
  pure_quanta q_res *
  page322_i159
#CELL
  pure_quanta q_res *
  page322_i160
#ISCELL
  standard offpage *
  page322_i161
#ISCELL
  standard offpage *
  page322_i162
#CELL
  pure_quanta q_res *
  page322_i163
#CELL
  pure_quanta q_res *
  page322_i164
#ISCELL
  standard offpage *
  page322_i165
#ISCELL
  standard offpage *
  page322_i166
#ISCELL
  standard offpage *
  page322_i167
#ISCELL
  standard offpage *
  page322_i168
#CELL
  pure_quanta q_res *
  page322_i169
#CELL
  pure_quanta q_res *
  page322_i171
#CELL
  pure_quanta q_res *
  page322_i172
#CELL
  pure_quanta q_res *
  page322_i173
#CELL
  pure_quanta q_res *
  page322_i174
#ISCELL
  logical_power universal_power *
  page322_i175
#ISCELL
  logical_power universal_power *
  page322_i176
#CELL
  pure_quanta q_res *
  page322_i177
#ISCELL
  standard offpage *
  page322_i178
#ISCELL
  standard offpage *
  page322_i179
#ISCELL
  standard offpage *
  page322_i180
#CELL
  pure_quanta q_res *
  page322_i181
#CELL
  pure_quanta q_res *
  page322_i182
#CELL
  pure_quanta q_res *
  page322_i183
#CELL
  pure_quanta q_res *
  page322_i184
#ISCELL
  standard offpage *
  page322_i185
#ISCELL
  standard offpage *
  page322_i186
#CELL
  pure_quanta q_res *
  page322_i187
#CELL
  pure_quanta q_res *
  page322_i188
#CELL
  pure_quanta q_res *
  page322_i189
#CELL
  pure_quanta q_res *
  page322_i190
#ISCELL
  logical_power universal_gnd *
  page322_i191
#ISCELL
  logical_power universal_gnd *
  page322_i20
#CELL
  pure_quanta gtl2014pw *
  page322_i27
#ISCELL
  standard offpage *
  page322_i32
#ISCELL
  standard offpage *
  page322_i33
#ISCELL
  standard offpage *
  page322_i34
#ISCELL
  standard offpage *
  page322_i35
#CELL
  pure_quanta q_res *
  page322_i36
#CELL
  pure_quanta q_res *
  page322_i37
#CELL
  pure_quanta q_res *
  page322_i38
#CELL
  pure_quanta q_res *
  page322_i39
#CELL
  pure_quanta gtl2014pw *
  page322_i44
#ISCELL
  logical_power universal_gnd *
  page322_i49
#CELL
  pure_quanta q_res *
  page322_i52
#CELL
  pure_quanta q_res *
  page322_i53
#CELL
  pure_quanta q_res *
  page322_i54
#CELL
  pure_quanta q_res *
  page322_i55
#ISCELL
  logical_power universal_gnd *
  page322_i58
#CELL
  pure_quanta q_cap *
  page322_i59
#ISCELL
  logical_power universal_power *
  page322_i60
#ISCELL
  logical_power universal_gnd *
  page322_i61
#ISCELL
  standard offpage *
  page322_i62
#ISCELL
  standard offpage *
  page322_i63
#ISCELL
  standard offpage *
  page322_i64
#ISCELL
  standard offpage *
  page322_i65
#CELL
  pure_quanta q_res *
  page322_i66
#CELL
  pure_quanta q_res *
  page322_i67
#ISCELL
  logical_power universal_gnd *
  page322_i8
#CELL
  pure_quanta gtl2014pw *
  page322_i80
#CELL
  pure_quanta q_cap *
  page322_i83
#ISCELL
  logical_power universal_power *
  page322_i84
#ISCELL
  logical_power universal_gnd *
  page322_i89
#CELL
  pure_quanta q_cap *
  page322_i9
#CELL
  pure_quanta q_res *
  page322_i91
#CELL
  pure_quanta q_res *
  page322_i94
#ISCELL
  logical_power universal_gnd *
  page322_i96
#ISCELL
  logical_power universal_gnd *
  page322_i97
#ISCELL
  pure_quanta quanta_title_block_c *
  *
#CELL
  pure_quanta q_res *
  page321_i101
#ISCELL
  standard offpage *
  page321_i102
#ISCELL
  logical_power universal_gnd *
  page321_i70
#ISCELL
  standard offpage *
  page321_i71
#ISCELL
  standard offpage *
  page321_i72
#ISCELL
  standard offpage *
  page321_i73
#ISCELL
  logical_power universal_gnd *
  page321_i74
#ISCELL
  logical_power universal_power *
  page321_i75
#CELL
  pure_quanta q_res *
  page321_i77
#CELL
  pure_quanta q_res *
  page321_i78
#CELL
  pure_quanta q_res *
  page321_i79
#CELL
  pure_quanta q_res *
  page321_i80
#CELL
  pure_quanta q_cap *
  page321_i83
#CELL
  pure_quanta q_cap *
  page321_i85
#ISCELL
  logical_power universal_gnd *
  page321_i86
#ISCELL
  logical_power universal_power *
  page321_i87
#CELL
  pure_quanta gtl2014pw *
  page321_i91
#ISCELL
  logical_power universal_gnd *
  page321_i92
#ISCELL
  standard offpage *
  page321_i94
#ISCELL
  standard offpage *
  page321_i95
#ISCELL
  standard offpage *
  page321_i96
#CELL
  pure_quanta q_res *
  page321_i97
#CELL
  pure_quanta q_res *
  page321_i98
#ISCELL
  mstr_misc dns *
  *
#ISCELL
  pure_quanta quanta_title_block_c *
  *
#ISCELL
  standard offpage *
  page214_i100
#CELL
  pure_quanta q_res *
  page214_i101
#ISCELL
  standard offpage *
  page214_i113
#ISCELL
  standard offpage *
  page214_i114
#ISCELL
  standard offpage *
  page214_i115
#ISCELL
  standard offpage *
  page214_i116
#ISCELL
  standard offpage *
  page214_i117
#CELL
  pure_quanta q_res *
  page214_i118
#ISCELL
  standard offpage *
  page214_i122
#ISCELL
  standard offpage *
  page214_i123
#ISCELL
  standard offpage *
  page214_i124
#CELL
  pure_quanta q_res *
  page214_i127
#CELL
  pure_quanta q_res *
  page214_i128
#CELL
  pure_quanta q_res *
  page214_i129
#ISCELL
  standard offpage *
  page214_i130
#ISCELL
  standard offpage *
  page214_i131
#ISCELL
  standard offpage *
  page214_i132
#ISCELL
  standard offpage *
  page214_i133
#ISCELL
  standard offpage *
  page214_i134
#ISCELL
  standard offpage *
  page214_i135
#ISCELL
  standard offpage *
  page214_i136
#CELL
  pure_quanta q_res *
  page214_i137
#ISCELL
  standard offpage *
  page214_i138
#ISCELL
  standard offpage *
  page214_i139
#CELL
  pure_quanta q_res *
  page214_i140
#ISCELL
  standard offpage *
  page214_i141
#ISCELL
  standard offpage *
  page214_i142
#ISCELL
  standard offpage *
  page214_i143
#CELL
  pure_quanta q_res *
  page214_i144
#ISCELL
  standard offpage *
  page214_i145
#ISCELL
  standard offpage *
  page214_i146
#ISCELL
  standard offpage *
  page214_i147
#CELL
  pure_quanta q_res *
  page214_i148
#ISCELL
  standard offpage *
  page214_i149
#ISCELL
  standard offpage *
  page214_i150
#ISCELL
  standard offpage *
  page214_i151
#ISCELL
  standard offpage *
  page214_i152
#CELL
  pure_quanta q_res *
  page214_i153
#ISCELL
  standard offpage *
  page214_i154
#ISCELL
  standard offpage *
  page214_i155
#CELL
  pure_quanta q_res *
  page214_i156
#ISCELL
  standard offpage *
  page214_i157
#ISCELL
  standard offpage *
  page214_i158
#ISCELL
  standard offpage *
  page214_i159
#ISCELL
  standard offpage *
  page214_i160
#CELL
  pure_quanta q_res *
  page214_i161
#ISCELL
  standard offpage *
  page214_i162
#ISCELL
  standard offpage *
  page214_i163
#CELL
  pure_quanta q_res *
  page214_i164
#ISCELL
  standard offpage *
  page214_i165
#ISCELL
  standard offpage *
  page214_i166
#ISCELL
  standard offpage *
  page214_i167
#ISCELL
  standard offpage *
  page214_i33
#CELL
  pure_quanta q_res *
  page214_i34
#ISCELL
  standard offpage *
  page214_i35
#CELL
  pure_quanta pca9539rpw *
  page214_i66
#ISCELL
  logical_power universal_power *
  page214_i73
#CELL
  pure_quanta q_res *
  page214_i74
#CELL
  pure_quanta q_res *
  page214_i75
#CELL
  pure_quanta q_res *
  page214_i76
#CELL
  pure_quanta q_res *
  page214_i77
#ISCELL
  logical_power universal_gnd *
  page214_i78
#ISCELL
  logical_power universal_gnd *
  page214_i79
#ISCELL
  standard offpage *
  page214_i80
#ISCELL
  standard offpage *
  page214_i81
#ISCELL
  standard offpage *
  page214_i82
#ISCELL
  standard offpage *
  page214_i83
#ISCELL
  standard offpage *
  page214_i84
#ISCELL
  standard offpage *
  page214_i85
#ISCELL
  logical_power universal_gnd *
  page214_i86
#CELL
  pure_quanta q_cap *
  page214_i87
#ISCELL
  logical_power universal_power *
  page214_i88
#ISCELL
  logical_power universal_gnd *
  page214_i89
#CELL
  pure_quanta q_res *
  page214_i90
#ISCELL
  logical_power universal_power *
  page214_i91
#ISCELL
  standard offpage *
  page214_i92
#CELL
  pure_quanta q_res *
  page214_i93
#ISCELL
  logical_power universal_power *
  page214_i94
#CELL
  pure_quanta q_res *
  page214_i95
#CELL
  pure_quanta q_res *
  page214_i96
#ISCELL
  standard offpage *
  page214_i97
#ISCELL
  standard offpage *
  page214_i98
#ISCELL
  standard offpage *
  page214_i99
#ISCELL
  pure_quanta quanta_title_block_c *
  *
#ISCELL
  standard offpage *
  page215_i10
#ISCELL
  standard offpage *
  page215_i11
#CELL
  pure_quanta q_res *
  page215_i12
#CELL
  pure_quanta q_res *
  page215_i13
#ISCELL
  standard offpage *
  page215_i14
#ISCELL
  standard offpage *
  page215_i15
#ISCELL
  standard offpage *
  page215_i17
#ISCELL
  standard offpage *
  page215_i18
#ISCELL
  standard offpage *
  page215_i19
#CELL
  pure_quanta q_res *
  page215_i2
#ISCELL
  standard offpage *
  page215_i20
#ISCELL
  logical_power universal_gnd *
  page215_i21
#CELL
  pure_quanta q_res *
  page215_i23
#ISCELL
  standard offpage *
  page215_i24
#ISCELL
  standard offpage *
  page215_i26
#ISCELL
  logical_power universal_gnd *
  page215_i27
#CELL
  pure_quanta q_res *
  page215_i28
#ISCELL
  standard offpage *
  page215_i29
#ISCELL
  standard offpage *
  page215_i3
#ISCELL
  standard offpage *
  page215_i30
#ISCELL
  standard offpage *
  page215_i31
#CELL
  pure_quanta sconn20_513860200cv01 *
  page215_i32
#ISCELL
  standard offpage *
  page215_i4
#ISCELL
  standard offpage *
  page215_i5
#ISCELL
  standard offpage *
  page215_i6
#ISCELL
  standard offpage *
  page215_i7
#ISCELL
  standard offpage *
  page215_i8
#ISCELL
  standard offpage *
  page215_i9
#ISCELL
  mstr_misc dns *
  *
#ISCELL
  pure_quanta quanta_title_block_c *
  *
#ISCELL
  standard offpage *
  page217_i1
#ISCELL
  standard offpage *
  page217_i10
#ISCELL
  standard offpage *
  page217_i11
#ISCELL
  logical_power universal_gnd *
  page217_i12
#CELL
  pure_quanta q_res *
  page217_i13
#ISCELL
  standard offpage *
  page217_i14
#ISCELL
  standard offpage *
  page217_i15
#CELL
  pure_quanta q_res *
  page217_i16
#CELL
  pure_quanta q_res *
  page217_i17
#CELL
  pure_quanta q_res *
  page217_i18
#CELL
  pure_quanta qs3vh257qg8 *
  page217_i19
#ISCELL
  standard offpage *
  page217_i2
#CELL
  pure_quanta q_res *
  page217_i20
#ISCELL
  logical_power universal_gnd *
  page217_i21
#ISCELL
  logical_power universal_gnd *
  page217_i22
#ISCELL
  logical_power universal_power *
  page217_i23
#CELL
  pure_quanta q_cap *
  page217_i24
#CELL
  pure_quanta q_res *
  page217_i25
#CELL
  pure_quanta q_res *
  page217_i26
#ISCELL
  standard offpage *
  page217_i27
#ISCELL
  standard offpage *
  page217_i28
#CELL
  pure_quanta q_res *
  page217_i29
#CELL
  pure_quanta q_res *
  page217_i30
#ISCELL
  logical_power universal_power *
  page217_i31
#CELL
  pure_quanta q_res *
  page217_i32
#CELL
  pure_quanta q_res *
  page217_i33
#CELL
  pure_quanta q_res *
  page217_i34
#CELL
  pure_quanta q_res *
  page217_i35
#ISCELL
  standard offpage *
  page217_i36
#CELL
  pure_quanta q_res *
  page217_i37
#CELL
  pure_quanta q_res *
  page217_i38
#CELL
  pure_quanta q_res *
  page217_i39
#ISCELL
  standard offpage *
  page217_i4
#CELL
  pure_quanta q_res *
  page217_i40
#ISCELL
  logical_power universal_gnd *
  page217_i41
#CELL
  pure_quanta q_res *
  page217_i42
#CELL
  pure_quanta q_res *
  page217_i43
#ISCELL
  logical_power universal_power *
  page217_i44
#ISCELL
  standard offpage *
  page217_i45
#ISCELL
  standard offpage *
  page217_i46
#ISCELL
  standard offpage *
  page217_i47
#ISCELL
  standard offpage *
  page217_i48
#ISCELL
  standard offpage *
  page217_i49
#ISCELL
  standard offpage *
  page217_i5
#ISCELL
  standard offpage *
  page217_i50
#ISCELL
  standard offpage *
  page217_i51
#ISCELL
  standard offpage *
  page217_i52
#CELL
  pure_quanta q_res *
  page217_i53
#ISCELL
  standard offpage *
  page217_i6
#ISCELL
  standard offpage *
  page217_i7
#ISCELL
  standard offpage *
  page217_i8
#ISCELL
  standard offpage *
  page217_i9
#ISCELL
  mstr_misc dns *
  *
#ISCELL
  pure_quanta quanta_title_block_c *
  *
#ISCELL
  standard offpage *
  page218_i1
#ISCELL
  standard offpage *
  page218_i10
#ISCELL
  standard offpage *
  page218_i11
#CELL
  pure_quanta qs3vh257qg8 *
  page218_i12
#ISCELL
  standard offpage *
  page218_i13
#ISCELL
  standard offpage *
  page218_i14
#ISCELL
  standard offpage *
  page218_i15
#ISCELL
  standard offpage *
  page218_i16
#CELL
  pure_quanta q_res *
  page218_i17
#CELL
  pure_quanta q_res *
  page218_i18
#ISCELL
  logical_power universal_power *
  page218_i19
#ISCELL
  standard offpage *
  page218_i2
#CELL
  pure_quanta q_res *
  page218_i20
#CELL
  pure_quanta q_res *
  page218_i21
#CELL
  pure_quanta q_res *
  page218_i22
#CELL
  pure_quanta q_res *
  page218_i23
#ISCELL
  logical_power universal_gnd *
  page218_i24
#CELL
  pure_quanta q_cap *
  page218_i25
#ISCELL
  logical_power universal_gnd *
  page218_i26
#ISCELL
  logical_power universal_power *
  page218_i27
#CELL
  pure_quanta q_res *
  page218_i28
#CELL
  pure_quanta q_res *
  page218_i29
#ISCELL
  logical_power universal_gnd *
  page218_i3
#CELL
  pure_quanta q_res *
  page218_i30
#CELL
  pure_quanta q_res *
  page218_i31
#CELL
  pure_quanta q_res *
  page218_i32
#CELL
  pure_quanta q_res *
  page218_i33
#CELL
  pure_quanta q_res *
  page218_i34
#CELL
  pure_quanta q_res *
  page218_i35
#CELL
  pure_quanta q_res *
  page218_i36
#CELL
  pure_quanta q_res *
  page218_i37
#ISCELL
  standard offpage *
  page218_i38
#ISCELL
  standard offpage *
  page218_i39
#CELL
  pure_quanta q_res *
  page218_i4
#ISCELL
  standard offpage *
  page218_i40
#ISCELL
  standard offpage *
  page218_i41
#ISCELL
  standard offpage *
  page218_i42
#ISCELL
  standard offpage *
  page218_i43
#ISCELL
  standard offpage *
  page218_i44
#ISCELL
  standard offpage *
  page218_i45
#ISCELL
  standard offpage *
  page218_i5
#ISCELL
  standard offpage *
  page218_i6
#ISCELL
  standard offpage *
  page218_i7
#ISCELL
  standard offpage *
  page218_i8
#ISCELL
  standard offpage *
  page218_i9
#ISCELL
  mstr_misc dns *
  *
#ISCELL
  pure_quanta quanta_title_block_c *
  *
#ISCELL
  logical_power universal_gnd *
  page219_i1
#CELL
  pure_quanta q_res *
  page219_i10
#ISCELL
  standard offpage *
  page219_i11
#ISCELL
  standard offpage *
  page219_i12
#ISCELL
  standard offpage *
  page219_i13
#ISCELL
  standard offpage *
  page219_i14
#ISCELL
  standard offpage *
  page219_i15
#ISCELL
  standard offpage *
  page219_i16
#ISCELL
  standard offpage *
  page219_i17
#CELL
  pure_quanta q_res *
  page219_i18
#ISCELL
  logical_power universal_power *
  page219_i19
#CELL
  pure_quanta q_res *
  page219_i2
#CELL
  pure_quanta q_res *
  page219_i20
#CELL
  pure_quanta q_res *
  page219_i21
#CELL
  pure_quanta q_res *
  page219_i22
#CELL
  pure_quanta q_res *
  page219_i23
#CELL
  pure_quanta q_res *
  page219_i24
#CELL
  pure_quanta q_res *
  page219_i25
#ISCELL
  standard offpage *
  page219_i26
#ISCELL
  standard offpage *
  page219_i27
#ISCELL
  standard offpage *
  page219_i28
#ISCELL
  standard offpage *
  page219_i29
#CELL
  pure_quanta q_res *
  page219_i3
#ISCELL
  standard offpage *
  page219_i30
#ISCELL
  standard offpage *
  page219_i31
#ISCELL
  standard offpage *
  page219_i32
#ISCELL
  standard offpage *
  page219_i33
#ISCELL
  standard offpage *
  page219_i34
#CELL
  pure_quanta q_res *
  page219_i35
#CELL
  pure_quanta q_res *
  page219_i36
#CELL
  pure_quanta q_res *
  page219_i37
#CELL
  pure_quanta q_res *
  page219_i38
#CELL
  pure_quanta q_res *
  page219_i39
#ISCELL
  logical_power universal_power *
  page219_i4
#CELL
  pure_quanta q_res *
  page219_i40
#CELL
  pure_quanta q_res *
  page219_i41
#ISCELL
  standard offpage *
  page219_i42
#ISCELL
  standard offpage *
  page219_i43
#ISCELL
  standard offpage *
  page219_i44
#CELL
  pure_quanta tca9548apwr *
  page219_i45
#ISCELL
  logical_power universal_gnd *
  page219_i46
#CELL
  pure_quanta q_cap *
  page219_i47
#ISCELL
  logical_power universal_power *
  page219_i48
#CELL
  pure_quanta q_res *
  page219_i49
#ISCELL
  logical_power universal_gnd *
  page219_i5
#CELL
  pure_quanta q_res *
  page219_i50
#CELL
  pure_quanta q_res *
  page219_i51
#CELL
  pure_quanta q_res *
  page219_i52
#CELL
  pure_quanta q_res *
  page219_i53
#CELL
  pure_quanta q_res *
  page219_i54
#ISCELL
  logical_power universal_power *
  page219_i55
#CELL
  pure_quanta q_res *
  page219_i56
#CELL
  pure_quanta q_res *
  page219_i57
#ISCELL
  logical_power universal_gnd *
  page219_i58
#CELL
  pure_quanta q_res *
  page219_i59
#CELL
  pure_quanta q_res *
  page219_i6
#CELL
  pure_quanta q_res *
  page219_i60
#CELL
  pure_quanta q_res *
  page219_i61
#CELL
  pure_quanta q_res *
  page219_i62
#CELL
  pure_quanta q_res *
  page219_i63
#CELL
  pure_quanta q_res *
  page219_i64
#CELL
  pure_quanta q_res *
  page219_i65
#CELL
  pure_quanta q_res *
  page219_i66
#ISCELL
  standard offpage *
  page219_i67
#ISCELL
  standard offpage *
  page219_i68
#ISCELL
  standard offpage *
  page219_i69
#ISCELL
  logical_power universal_gnd *
  page219_i7
#ISCELL
  standard offpage *
  page219_i70
#ISCELL
  standard offpage *
  page219_i71
#ISCELL
  standard offpage *
  page219_i72
#ISCELL
  standard offpage *
  page219_i73
#ISCELL
  standard offpage *
  page219_i74
#ISCELL
  standard offpage *
  page219_i75
#ISCELL
  standard offpage *
  page219_i76
#ISCELL
  standard offpage *
  page219_i77
#ISCELL
  standard offpage *
  page219_i78
#ISCELL
  standard offpage *
  page219_i79
#CELL
  pure_quanta q_res *
  page219_i8
#ISCELL
  standard offpage *
  page219_i80
#ISCELL
  standard offpage *
  page219_i81
#ISCELL
  standard offpage *
  page219_i82
#CELL
  pure_quanta q_res *
  page219_i9
#ISCELL
  pure_quanta quanta_title_block_c *
  *
#ISCELL
  standard offpage *
  page220_i1
#CELL
  pure_quanta q_res *
  page220_i11
#ISCELL
  standard offpage *
  page220_i12
#ISCELL
  standard offpage *
  page220_i13
#ISCELL
  standard offpage *
  page220_i14
#ISCELL
  standard offpage *
  page220_i15
#CELL
  pure_quanta q_res *
  page220_i16
#CELL
  pure_quanta q_res *
  page220_i17
#CELL
  pure_quanta q_res *
  page220_i18
#CELL
  pure_quanta q_res *
  page220_i19
#ISCELL
  standard offpage *
  page220_i2
#CELL
  pure_quanta q_res *
  page220_i20
#CELL
  pure_quanta q_res *
  page220_i21
#ISCELL
  standard offpage *
  page220_i22
#ISCELL
  standard offpage *
  page220_i23
#ISCELL
  standard offpage *
  page220_i24
#ISCELL
  standard offpage *
  page220_i25
#CELL
  pure_quanta q_res *
  page220_i26
#CELL
  pure_quanta q_res *
  page220_i3
#CELL
  pure_quanta q_res *
  page220_i4
#ISCELL
  standard offpage *
  page220_i7
#ISCELL
  standard offpage *
  page220_i8
#ISCELL
  mstr_misc dns *
  *
#ISCELL
  pure_quanta quanta_title_block_c *
  *
#ISCELL
  logical_power universal_gnd *
  page221_i1
#CELL
  pure_quanta q_res *
  page221_i10
#ISCELL
  standard offpage *
  page221_i100
#ISCELL
  standard offpage *
  page221_i101
#CELL
  pure_quanta q_res *
  page221_i102
#CELL
  pure_quanta tca9548apwr *
  page221_i103
#ISCELL
  logical_power universal_power *
  page221_i104
#ISCELL
  logical_power universal_gnd *
  page221_i105
#CELL
  pure_quanta q_cap *
  page221_i106
#ISCELL
  standard offpage *
  page221_i107
#ISCELL
  standard offpage *
  page221_i109
#ISCELL
  standard offpage *
  page221_i110
#ISCELL
  standard offpage *
  page221_i113
#ISCELL
  standard offpage *
  page221_i114
#CELL
  pure_quanta q_res *
  page221_i115
#CELL
  pure_quanta q_res *
  page221_i116
#ISCELL
  standard offpage *
  page221_i117
#ISCELL
  standard offpage *
  page221_i118
#CELL
  pure_quanta q_res *
  page221_i119
#CELL
  pure_quanta q_res *
  page221_i120
#ISCELL
  standard offpage *
  page221_i121
#ISCELL
  standard offpage *
  page221_i122
#ISCELL
  standard offpage *
  page221_i123
#ISCELL
  standard offpage *
  page221_i124
#ISCELL
  standard offpage *
  page221_i125
#ISCELL
  standard offpage *
  page221_i126
#ISCELL
  standard offpage *
  page221_i127
#ISCELL
  standard offpage *
  page221_i128
#CELL
  pure_quanta q_res *
  page221_i137
#CELL
  pure_quanta q_res *
  page221_i138
#CELL
  pure_quanta q_res *
  page221_i139
#CELL
  pure_quanta q_res *
  page221_i140
#CELL
  pure_quanta q_res *
  page221_i141
#CELL
  pure_quanta q_res *
  page221_i142
#CELL
  pure_quanta q_res *
  page221_i143
#CELL
  pure_quanta q_res *
  page221_i144
#CELL
  pure_quanta q_res *
  page221_i145
#ISCELL
  logical_power universal_power *
  page221_i146
#CELL
  pure_quanta q_res *
  page221_i147
#ISCELL
  standard offpage *
  page221_i148
#ISCELL
  logical_power universal_gnd *
  page221_i149
#CELL
  pure_quanta q_res *
  page221_i2
#CELL
  pure_quanta q_res *
  page221_i3
#ISCELL
  standard offpage *
  page221_i33
#CELL
  pure_quanta q_res *
  page221_i34
#ISCELL
  standard offpage *
  page221_i35
#ISCELL
  standard offpage *
  page221_i36
#ISCELL
  standard offpage *
  page221_i37
#ISCELL
  logical_power universal_power *
  page221_i4
#CELL
  pure_quanta q_res *
  page221_i48
#CELL
  pure_quanta q_res *
  page221_i49
#ISCELL
  logical_power universal_gnd *
  page221_i5
#CELL
  pure_quanta q_res *
  page221_i50
#CELL
  pure_quanta q_res *
  page221_i51
#CELL
  pure_quanta q_res *
  page221_i52
#CELL
  pure_quanta q_res *
  page221_i53
#ISCELL
  logical_power universal_power *
  page221_i54
#CELL
  pure_quanta q_res *
  page221_i55
#CELL
  pure_quanta q_res *
  page221_i56
#CELL
  pure_quanta q_res *
  page221_i6
#ISCELL
  logical_power universal_gnd *
  page221_i7
#ISCELL
  standard offpage *
  page221_i75
#ISCELL
  standard offpage *
  page221_i76
#ISCELL
  standard offpage *
  page221_i77
#ISCELL
  standard offpage *
  page221_i78
#ISCELL
  standard offpage *
  page221_i79
#CELL
  pure_quanta q_res *
  page221_i8
#ISCELL
  standard offpage *
  page221_i80
#ISCELL
  standard offpage *
  page221_i81
#ISCELL
  standard offpage *
  page221_i82
#ISCELL
  standard offpage *
  page221_i83
#CELL
  pure_quanta q_res *
  page221_i9
#CELL
  pure_quanta q_res *
  page221_i98
#CELL
  pure_quanta q_res *
  page221_i99
#ISCELL
  mstr_misc dns *
  *
#ISCELL
  pure_quanta quanta_title_block_c *
  *
#ISCELL
  standard offpage *
  page222_i1
#ISCELL
  logical_power universal_gnd *
  page222_i10
#CELL
  pure_quanta ltc4307cms8 *
  page222_i11
#CELL
  pure_quanta q_res *
  page222_i12
#CELL
  pure_quanta q_res *
  page222_i13
#ISCELL
  logical_power universal_gnd *
  page222_i14
#ISCELL
  logical_power universal_gnd *
  page222_i15
#CELL
  pure_quanta q_res *
  page222_i16
#CELL
  pure_quanta q_res *
  page222_i17
#CELL
  pure_quanta q_res *
  page222_i18
#CELL
  pure_quanta q_res *
  page222_i19
#ISCELL
  standard offpage *
  page222_i2
#CELL
  pure_quanta q_cap *
  page222_i20
#ISCELL
  logical_power universal_gnd *
  page222_i21
#ISCELL
  logical_power universal_power *
  page222_i22
#CELL
  pure_quanta q_res *
  page222_i23
#ISCELL
  logical_power universal_power *
  page222_i24
#CELL
  pure_quanta q_res *
  page222_i25
#CELL
  pure_quanta q_res *
  page222_i26
#CELL
  pure_quanta q_res *
  page222_i27
#ISCELL
  logical_power universal_gnd *
  page222_i28
#CELL
  pure_quanta q_res *
  page222_i29
#ISCELL
  standard offpage *
  page222_i3
#CELL
  pure_quanta q_res *
  page222_i30
#CELL
  pure_quanta ltc4307cms8 *
  page222_i31
#ISCELL
  logical_power universal_gnd *
  page222_i32
#CELL
  pure_quanta q_res *
  page222_i33
#CELL
  pure_quanta q_cap *
  page222_i34
#ISCELL
  logical_power universal_power *
  page222_i35
#ISCELL
  standard offpage *
  page222_i36
#ISCELL
  standard offpage *
  page222_i37
#CELL
  pure_quanta q_res *
  page222_i38
#ISCELL
  standard offpage *
  page222_i39
#ISCELL
  standard offpage *
  page222_i4
#ISCELL
  standard offpage *
  page222_i40
#ISCELL
  standard offpage *
  page222_i41
#CELL
  pure_quanta q_res *
  page222_i42
#CELL
  pure_quanta q_res *
  page222_i43
#CELL
  pure_quanta q_res *
  page222_i44
#ISCELL
  standard offpage *
  page222_i45
#ISCELL
  standard offpage *
  page222_i46
#ISCELL
  standard offpage *
  page222_i47
#CELL
  pure_quanta q_res *
  page222_i48
#ISCELL
  logical_power universal_gnd *
  page222_i49
#ISCELL
  standard offpage *
  page222_i5
#CELL
  pure_quanta ltc4307cms8 *
  page222_i50
#CELL
  pure_quanta q_res *
  page222_i51
#CELL
  pure_quanta q_res *
  page222_i52
#CELL
  pure_quanta q_res *
  page222_i53
#CELL
  pure_quanta q_res *
  page222_i54
#CELL
  pure_quanta q_res *
  page222_i55
#ISCELL
  logical_power universal_gnd *
  page222_i56
#ISCELL
  logical_power universal_power *
  page222_i57
#CELL
  pure_quanta q_cap *
  page222_i58
#CELL
  pure_quanta q_res *
  page222_i59
#ISCELL
  standard offpage *
  page222_i6
#ISCELL
  logical_power universal_power *
  page222_i60
#CELL
  pure_quanta q_res *
  page222_i61
#ISCELL
  logical_power universal_gnd *
  page222_i62
#CELL
  pure_quanta ltc4307cms8 *
  page222_i63
#CELL
  pure_quanta q_res *
  page222_i64
#CELL
  pure_quanta q_res *
  page222_i65
#CELL
  pure_quanta q_cap *
  page222_i66
#ISCELL
  logical_power universal_gnd *
  page222_i67
#ISCELL
  logical_power universal_power *
  page222_i68
#ISCELL
  standard offpage *
  page222_i69
#CELL
  pure_quanta q_res *
  page222_i7
#ISCELL
  standard offpage *
  page222_i70
#CELL
  pure_quanta q_res *
  page222_i71
#CELL
  pure_quanta q_res *
  page222_i72
#ISCELL
  standard offpage *
  page222_i73
#ISCELL
  standard offpage *
  page222_i74
#CELL
  pure_quanta q_res *
  page222_i75
#ISCELL
  logical_power universal_power *
  page222_i76
#CELL
  pure_quanta q_res *
  page222_i77
#CELL
  pure_quanta q_res *
  page222_i78
#CELL
  pure_quanta q_res *
  page222_i79
#CELL
  pure_quanta q_res *
  page222_i8
#CELL
  pure_quanta q_res *
  page222_i80
#CELL
  pure_quanta q_res *
  page222_i81
#ISCELL
  logical_power universal_power *
  page222_i82
#ISCELL
  standard offpage *
  page222_i83
#ISCELL
  standard offpage *
  page222_i84
#CELL
  pure_quanta q_res *
  page222_i9
#ISCELL
  logical_power design_note *
  *
#ISCELL
  pure_quanta quanta_title_block_c *
  *
#ISCELL
  logical_power universal_gnd *
  page223_i10
#CELL
  pure_quanta q_res *
  page223_i100
#CELL
  pure_quanta q_res *
  page223_i101
#CELL
  pure_quanta q_res *
  page223_i102
#CELL
  pure_quanta mosfet_nch_dual *
  page223_i104
#CELL
  pure_quanta mosfet_nch_dual *
  page223_i106
#CELL
  pure_quanta mosfet_nch_dual *
  page223_i108
#CELL
  pure_quanta mosfet_nch_dual *
  page223_i109
#ISCELL
  logical_power universal_power *
  page223_i11
#CELL
  pure_quanta q_res *
  page223_i12
#ISCELL
  logical_power universal_power *
  page223_i16
#ISCELL
  logical_power universal_gnd *
  page223_i17
#CELL
  pure_quanta q_cap *
  page223_i18
#ISCELL
  logical_power universal_power *
  page223_i19
#CELL
  pure_quanta q_cap *
  page223_i20
#ISCELL
  logical_power universal_gnd *
  page223_i21
#CELL
  pure_quanta q_res *
  page223_i22
#ISCELL
  logical_power universal_power *
  page223_i23
#CELL
  pure_quanta q_res *
  page223_i24
#ISCELL
  logical_power universal_power *
  page223_i30
#CELL
  pure_quanta q_cap *
  page223_i31
#ISCELL
  logical_power universal_gnd *
  page223_i32
#ISCELL
  logical_power universal_power *
  page223_i33
#CELL
  pure_quanta q_res *
  page223_i34
#ISCELL
  logical_power universal_gnd *
  page223_i35
#ISCELL
  logical_power universal_power *
  page223_i37
#CELL
  pure_quanta q_res *
  page223_i38
#CELL
  pure_quanta pca9617adp *
  page223_i39
#ISCELL
  logical_power universal_gnd *
  page223_i40
#ISCELL
  logical_power universal_power *
  page223_i41
#CELL
  pure_quanta q_cap *
  page223_i42
#CELL
  pure_quanta pca9617adp *
  page223_i43
#ISCELL
  logical_power universal_gnd *
  page223_i44
#ISCELL
  logical_power universal_gnd *
  page223_i45
#CELL
  pure_quanta q_res *
  page223_i46
#ISCELL
  logical_power universal_power *
  page223_i47
#CELL
  pure_quanta q_res *
  page223_i48
#ISCELL
  standard offpage *
  page223_i5
#ISCELL
  logical_power universal_power *
  page223_i51
#CELL
  pure_quanta q_res *
  page223_i52
#CELL
  pure_quanta q_res *
  page223_i53
#ISCELL
  logical_power universal_power *
  page223_i54
#CELL
  pure_quanta q_res *
  page223_i55
#ISCELL
  standard offpage *
  page223_i56
#ISCELL
  standard offpage *
  page223_i57
#ISCELL
  standard offpage *
  page223_i58
#ISCELL
  standard offpage *
  page223_i59
#ISCELL
  standard offpage *
  page223_i6
#ISCELL
  standard offpage *
  page223_i60
#ISCELL
  standard offpage *
  page223_i61
#ISCELL
  standard offpage *
  page223_i62
#ISCELL
  logical_power universal_gnd *
  page223_i63
#CELL
  pure_quanta conn3_210hp1030br1 *
  page223_i64
#ISCELL
  logical_power universal_gnd *
  page223_i65
#ISCELL
  logical_power universal_gnd *
  page223_i67
#CELL
  pure_quanta q_res *
  page223_i69
#ISCELL
  logical_power universal_power *
  page223_i7
#ISCELL
  standard offpage *
  page223_i70
#CELL
  pure_quanta q_res *
  page223_i76
#CELL
  pure_quanta q_res *
  page223_i77
#ISCELL
  standard offpage *
  page223_i78
#ISCELL
  standard offpage *
  page223_i79
#CELL
  pure_quanta q_res *
  page223_i8
#ISCELL
  logical_power universal_power *
  page223_i80
#CELL
  pure_quanta q_res *
  page223_i81
#CELL
  pure_quanta q_res *
  page223_i82
#CELL
  pure_quanta q_res *
  page223_i88
#CELL
  pure_quanta q_res *
  page223_i89
#ISCELL
  standard offpage *
  page223_i90
#ISCELL
  standard offpage *
  page223_i91
#ISCELL
  logical_power universal_power *
  page223_i92
#CELL
  pure_quanta q_res *
  page223_i93
#CELL
  pure_quanta q_res *
  page223_i94
#CELL
  pure_quanta q_res *
  page223_i99
#ISCELL
  mstr_misc dns *
  *
#ISCELL
  pure_quanta quanta_title_block_c *
  *
#ISCELL
  standard offpage *
  page224_i1
#CELL
  pure_quanta q_res *
  page224_i101
#ISCELL
  logical_power universal_power *
  page224_i102
#CELL
  pure_quanta q_res *
  page224_i103
#ISCELL
  logical_power universal_power *
  page224_i104
#ISCELL
  standard offpage *
  page224_i105
#CELL
  pure_quanta pca9545apw *
  page224_i106
#ISCELL
  standard offpage *
  page224_i107
#ISCELL
  standard offpage *
  page224_i108
#CELL
  pure_quanta q_res *
  page224_i109
#CELL
  pure_quanta q_res *
  page224_i110
#CELL
  pure_quanta q_res *
  page224_i111
#ISCELL
  standard offpage *
  page224_i112
#ISCELL
  standard offpage *
  page224_i113
#CELL
  pure_quanta q_res *
  page224_i114
#CELL
  pure_quanta q_res *
  page224_i115
#CELL
  pure_quanta q_res *
  page224_i116
#CELL
  pure_quanta q_res *
  page224_i117
#ISCELL
  standard offpage *
  page224_i118
#ISCELL
  standard offpage *
  page224_i119
#ISCELL
  standard offpage *
  page224_i123
#ISCELL
  standard offpage *
  page224_i124
#ISCELL
  standard offpage *
  page224_i125
#CELL
  pure_quanta q_res *
  page224_i13
#CELL
  pure_quanta q_res *
  page224_i130
#CELL
  pure_quanta q_res *
  page224_i131
#CELL
  pure_quanta q_res *
  page224_i132
#CELL
  pure_quanta q_res *
  page224_i133
#ISCELL
  logical_power universal_power *
  page224_i138
#ISCELL
  standard offpage *
  page224_i139
#CELL
  pure_quanta q_res *
  page224_i14
#CELL
  pure_quanta q_res *
  page224_i142
#CELL
  pure_quanta q_res *
  page224_i143
#ISCELL
  logical_power universal_power *
  page224_i15
#CELL
  pure_quanta q_res *
  page224_i16
#ISCELL
  standard offpage *
  page224_i2
#ISCELL
  logical_power universal_power *
  page224_i21
#CELL
  pure_quanta q_cap *
  page224_i22
#ISCELL
  logical_power universal_gnd *
  page224_i23
#ISCELL
  logical_power universal_power *
  page224_i24
#CELL
  pure_quanta q_cap *
  page224_i25
#ISCELL
  logical_power universal_gnd *
  page224_i26
#CELL
  pure_quanta pca9517ad *
  page224_i28
#ISCELL
  logical_power universal_gnd *
  page224_i29
#CELL
  pure_quanta q_res *
  page224_i3
#ISCELL
  logical_power universal_power *
  page224_i31
#ISCELL
  logical_power universal_gnd *
  page224_i32
#CELL
  pure_quanta q_cap *
  page224_i33
#ISCELL
  logical_power universal_power *
  page224_i34
#CELL
  pure_quanta q_cap *
  page224_i35
#ISCELL
  logical_power universal_gnd *
  page224_i36
#CELL
  pure_quanta pca9517ad *
  page224_i37
#ISCELL
  logical_power universal_gnd *
  page224_i38
#ISCELL
  standard offpage *
  page224_i4
#ISCELL
  logical_power universal_power *
  page224_i41
#CELL
  pure_quanta q_res *
  page224_i42
#CELL
  pure_quanta q_res *
  page224_i43
#CELL
  pure_quanta q_res *
  page224_i44
#ISCELL
  standard offpage *
  page224_i46
#ISCELL
  standard offpage *
  page224_i47
#ISCELL
  logical_power universal_power *
  page224_i48
#CELL
  pure_quanta q_res *
  page224_i49
#ISCELL
  standard offpage *
  page224_i5
#CELL
  pure_quanta q_res *
  page224_i50
#CELL
  pure_quanta q_res *
  page224_i51
#ISCELL
  standard offpage *
  page224_i53
#ISCELL
  standard offpage *
  page224_i54
#CELL
  pure_quanta q_res *
  page224_i6
#CELL
  pure_quanta q_res *
  page224_i62
#CELL
  pure_quanta q_res *
  page224_i63
#CELL
  pure_quanta q_res *
  page224_i64
#CELL
  pure_quanta q_res *
  page224_i65
#ISCELL
  logical_power universal_gnd *
  page224_i67
#CELL
  pure_quanta q_cap *
  page224_i68
#ISCELL
  logical_power universal_gnd *
  page224_i69
#ISCELL
  logical_power universal_power *
  page224_i7
#ISCELL
  logical_power universal_power *
  page224_i70
#CELL
  pure_quanta q_res *
  page224_i8
#CELL
  pure_quanta q_res *
  page224_i83
#CELL
  pure_quanta q_res *
  page224_i84
#CELL
  pure_quanta q_res *
  page224_i85
#CELL
  pure_quanta q_res *
  page224_i86
#ISCELL
  logical_power universal_power *
  page224_i87
#ISCELL
  logical_power universal_gnd *
  page224_i88
#ISCELL
  standard offpage *
  page224_i89
#ISCELL
  standard offpage *
  page224_i90
#ISCELL
  standard offpage *
  page224_i91
#ISCELL
  standard offpage *
  page224_i92
#ISCELL
  standard offpage *
  page224_i93
#ISCELL
  standard offpage *
  page224_i95
#ISCELL
  standard offpage *
  page224_i96
#CELL
  pure_quanta q_res *
  page224_i97
#ISCELL
  standard offpage *
  page224_i99
#ISCELL
  pure_quanta quanta_title_block_c *
  *
#CELL
  pure_quanta q_res *
  page225_i11
#CELL
  pure_quanta q_res *
  page225_i12
#ISCELL
  logical_power universal_power *
  page225_i13
#CELL
  pure_quanta pca9617adp *
  page225_i17
#ISCELL
  standard offpage *
  page225_i18
#ISCELL
  standard offpage *
  page225_i19
#ISCELL
  standard offpage *
  page225_i22
#ISCELL
  standard offpage *
  page225_i23
#CELL
  pure_quanta q_res *
  page225_i24
#CELL
  pure_quanta q_res *
  page225_i25
#CELL
  pure_quanta q_res *
  page225_i26
#CELL
  pure_quanta q_res *
  page225_i27
#ISCELL
  standard offpage *
  page225_i28
#ISCELL
  standard offpage *
  page225_i29
#ISCELL
  logical_power universal_gnd *
  page225_i3
#ISCELL
  standard offpage *
  page225_i30
#ISCELL
  standard offpage *
  page225_i31
#CELL
  pure_quanta q_res *
  page225_i32
#CELL
  pure_quanta q_res *
  page225_i33
#CELL
  pure_quanta q_res *
  page225_i34
#ISCELL
  standard offpage *
  page225_i35
#ISCELL
  standard offpage *
  page225_i36
#ISCELL
  logical_power universal_gnd *
  page225_i4
#CELL
  pure_quanta q_cap *
  page225_i5
#ISCELL
  logical_power universal_power *
  page225_i6
#ISCELL
  logical_power universal_gnd *
  page225_i7
#CELL
  pure_quanta q_cap *
  page225_i8
#ISCELL
  logical_power universal_power *
  page225_i9
#ISCELL
  pure_quanta quanta_title_block_c *
  *
#ISCELL
  standard offpage *
  page216_i1
#CELL
  pure_quanta q_cap *
  page216_i10
#CELL
  pure_quanta q_cap *
  page216_i11
#ISCELL
  standard offpage *
  page216_i12
#ISCELL
  standard offpage *
  page216_i13
#ISCELL
  logical_power universal_power *
  page216_i14
#ISCELL
  logical_power universal_gnd *
  page216_i15
#ISCELL
  logical_power universal_gnd *
  page216_i16
#CELL
  pure_quanta q_cap *
  page216_i17
#ISCELL
  logical_power universal_power *
  page216_i18
#ISCELL
  logical_power universal_power *
  page216_i19
#ISCELL
  standard offpage *
  page216_i2
#ISCELL
  logical_power universal_power *
  page216_i20
#CELL
  pure_quanta q_res *
  page216_i21
#ISCELL
  standard offpage *
  page216_i22
#CELL
  pure_quanta q_cap *
  page216_i23
#ISCELL
  logical_power universal_gnd *
  page216_i24
#ISCELL
  standard offpage *
  page216_i25
#ISCELL
  standard offpage *
  page216_i26
#ISCELL
  standard offpage *
  page216_i27
#CELL
  pure_quanta pca9617adp *
  page216_i28
#ISCELL
  logical_power universal_power *
  page216_i29
#ISCELL
  logical_power universal_gnd *
  page216_i3
#CELL
  pure_quanta q_res *
  page216_i30
#CELL
  pure_quanta q_res *
  page216_i31
#ISCELL
  logical_power universal_power *
  page216_i32
#CELL
  pure_quanta q_res *
  page216_i33
#CELL
  pure_quanta q_res *
  page216_i34
#ISCELL
  logical_power universal_gnd *
  page216_i4
#CELL
  pure_quanta pca9617adp *
  page216_i5
#ISCELL
  logical_power universal_gnd *
  page216_i6
#CELL
  pure_quanta q_res *
  page216_i7
#ISCELL
  standard offpage *
  page216_i8
#ISCELL
  standard offpage *
  page216_i9
#ISCELL
  logical_power design_note *
  *
#ISCELL
  mstr_misc dns *
  *
#ISCELL
  pure_quanta quanta_title_block_c *
  *
#CELL
  pure_quanta q_res *
  page226_i1
#CELL
  pure_quanta q_res *
  page226_i10
#CELL
  pure_quanta q_res *
  page226_i11
#CELL
  pure_quanta q_res *
  page226_i12
#CELL
  pure_quanta q_res *
  page226_i13
#CELL
  pure_quanta q_res *
  page226_i14
#ISCELL
  logical_power universal_power *
  page226_i15
#CELL
  pure_quanta q_cap *
  page226_i16
#ISCELL
  logical_power universal_gnd *
  page226_i17
#CELL
  pure_quanta gtl2014pw *
  page226_i18
#ISCELL
  logical_power universal_gnd *
  page226_i19
#ISCELL
  standard offpage *
  page226_i2
#CELL
  pure_quanta q_res *
  page226_i20
#ISCELL
  standard offpage *
  page226_i21
#ISCELL
  standard offpage *
  page226_i22
#ISCELL
  standard offpage *
  page226_i26
#CELL
  pure_quanta q_cap *
  page226_i27
#ISCELL
  logical_power universal_power *
  page226_i28
#ISCELL
  logical_power universal_gnd *
  page226_i29
#ISCELL
  standard offpage *
  page226_i3
#ISCELL
  logical_power universal_power *
  page226_i30
#CELL
  pure_quanta q_res *
  page226_i31
#ISCELL
  logical_power universal_gnd *
  page226_i32
#CELL
  pure_quanta q_res *
  page226_i34
#CELL
  pure_quanta q_res *
  page226_i36
#CELL
  pure_quanta q_res *
  page226_i37
#CELL
  pure_quanta nx3l2267gm *
  page226_i38
#ISCELL
  logical_power universal_gnd *
  page226_i39
#ISCELL
  standard offpage *
  page226_i4
#ISCELL
  standard offpage *
  page226_i40
#ISCELL
  standard offpage *
  page226_i41
#ISCELL
  logical_power universal_power *
  page226_i42
#CELL
  pure_quanta q_cap *
  page226_i43
#ISCELL
  logical_power universal_gnd *
  page226_i44
#CELL
  pure_quanta gtl2014pw *
  page226_i45
#ISCELL
  logical_power universal_gnd *
  page226_i46
#CELL
  pure_quanta q_res *
  page226_i47
#CELL
  pure_quanta q_res *
  page226_i48
#ISCELL
  logical_power universal_gnd *
  page226_i49
#ISCELL
  standard offpage *
  page226_i5
#ISCELL
  standard offpage *
  page226_i51
#ISCELL
  standard offpage *
  page226_i52
#ISCELL
  standard offpage *
  page226_i53
#ISCELL
  logical_power universal_power *
  page226_i54
#CELL
  pure_quanta q_cap *
  page226_i55
#ISCELL
  logical_power universal_gnd *
  page226_i56
#CELL
  pure_quanta q_res *
  page226_i57
#CELL
  pure_quanta q_res *
  page226_i58
#CELL
  pure_quanta q_res *
  page226_i59
#ISCELL
  logical_power universal_power *
  page226_i6
#ISCELL
  standard offpage *
  page226_i60
#ISCELL
  standard offpage *
  page226_i61
#ISCELL
  standard offpage *
  page226_i62
#ISCELL
  standard offpage *
  page226_i63
#CELL
  pure_quanta q_res *
  page226_i64
#CELL
  pure_quanta q_res *
  page226_i65
#ISCELL
  standard offpage *
  page226_i66
#ISCELL
  standard offpage *
  page226_i67
#CELL
  pure_quanta nx3l2267gm *
  page226_i68
#ISCELL
  logical_power universal_gnd *
  page226_i69
#CELL
  pure_quanta q_res *
  page226_i7
#ISCELL
  standard offpage *
  page226_i70
#ISCELL
  standard offpage *
  page226_i71
#ISCELL
  standard offpage *
  page226_i72
#ISCELL
  logical_power universal_power *
  page226_i76
#CELL
  pure_quanta q_res *
  page226_i77
#ISCELL
  logical_power universal_gnd *
  page226_i78
#CELL
  pure_quanta q_res *
  page226_i79
#ISCELL
  logical_power universal_gnd *
  page226_i8
#CELL
  pure_quanta q_res *
  page226_i80
#ISCELL
  standard offpage *
  page226_i81
#CELL
  pure_quanta q_res *
  page226_i82
#ISCELL
  standard offpage *
  page226_i83
#ISCELL
  standard offpage *
  page226_i84
#ISCELL
  standard offpage *
  page226_i85
#ISCELL
  logical_power universal_power *
  page226_i86
#CELL
  pure_quanta q_res *
  page226_i87
#CELL
  pure_quanta q_res *
  page226_i88
#CELL
  pure_quanta q_res *
  page226_i89
#ISCELL
  logical_power universal_power *
  page226_i9
#CELL
  pure_quanta q_res *
  page226_i90
#CELL
  pure_quanta q_res *
  page226_i91
#ISCELL
  logical_power universal_power *
  page226_i92
#CELL
  pure_quanta q_cap *
  page226_i93
#ISCELL
  standard offpage *
  page226_i94
#ISCELL
  standard offpage *
  page226_i95
#ISCELL
  logical_power design_note *
  *
#ISCELL
  mstr_misc dns *
  *
#ISCELL
  pure_quanta quanta_title_block_c *
  *
#ISCELL
  logical_power universal_gnd *
  page227_i1
#ISCELL
  standard offpage *
  page227_i10
#CELL
  pure_quanta q_res *
  page227_i100
#CELL
  pure_quanta q_res *
  page227_i101
#CELL
  pure_quanta q_res *
  page227_i102
#ISCELL
  standard offpage *
  page227_i103
#ISCELL
  standard offpage *
  page227_i104
#ISCELL
  standard offpage *
  page227_i105
#ISCELL
  standard offpage *
  page227_i106
#ISCELL
  standard offpage *
  page227_i107
#ISCELL
  standard offpage *
  page227_i108
#ISCELL
  standard offpage *
  page227_i109
#ISCELL
  standard offpage *
  page227_i11
#ISCELL
  standard offpage *
  page227_i110
#ISCELL
  standard offpage *
  page227_i111
#ISCELL
  standard offpage *
  page227_i112
#ISCELL
  standard offpage *
  page227_i113
#ISCELL
  standard offpage *
  page227_i114
#ISCELL
  standard offpage *
  page227_i115
#ISCELL
  standard offpage *
  page227_i116
#ISCELL
  standard offpage *
  page227_i117
#ISCELL
  standard offpage *
  page227_i118
#ISCELL
  standard offpage *
  page227_i119
#ISCELL
  standard offpage *
  page227_i12
#ISCELL
  standard offpage *
  page227_i120
#ISCELL
  standard offpage *
  page227_i121
#ISCELL
  standard offpage *
  page227_i122
#ISCELL
  standard offpage *
  page227_i123
#ISCELL
  standard offpage *
  page227_i124
#ISCELL
  standard offpage *
  page227_i125
#ISCELL
  logical_power universal_power *
  page227_i126
#ISCELL
  standard offpage *
  page227_i127
#ISCELL
  standard offpage *
  page227_i128
#ISCELL
  standard offpage *
  page227_i129
#ISCELL
  standard offpage *
  page227_i13
#ISCELL
  standard offpage *
  page227_i130
#ISCELL
  standard offpage *
  page227_i131
#ISCELL
  standard offpage *
  page227_i132
#ISCELL
  standard offpage *
  page227_i133
#ISCELL
  standard offpage *
  page227_i134
#ISCELL
  standard offpage *
  page227_i135
#ISCELL
  standard offpage *
  page227_i136
#ISCELL
  standard offpage *
  page227_i137
#ISCELL
  standard offpage *
  page227_i138
#ISCELL
  standard offpage *
  page227_i139
#ISCELL
  standard offpage *
  page227_i14
#ISCELL
  standard offpage *
  page227_i140
#ISCELL
  standard offpage *
  page227_i141
#ISCELL
  standard offpage *
  page227_i142
#ISCELL
  standard offpage *
  page227_i143
#ISCELL
  standard offpage *
  page227_i144
#ISCELL
  standard offpage *
  page227_i145
#ISCELL
  standard offpage *
  page227_i146
#ISCELL
  standard offpage *
  page227_i147
#ISCELL
  standard offpage *
  page227_i148
#ISCELL
  standard offpage *
  page227_i149
#ISCELL
  standard offpage *
  page227_i15
#ISCELL
  standard offpage *
  page227_i150
#ISCELL
  standard offpage *
  page227_i151
#ISCELL
  standard offpage *
  page227_i152
#ISCELL
  standard offpage *
  page227_i153
#ISCELL
  standard offpage *
  page227_i154
#ISCELL
  standard offpage *
  page227_i155
#ISCELL
  standard offpage *
  page227_i156
#ISCELL
  standard offpage *
  page227_i157
#ISCELL
  standard offpage *
  page227_i158
#CELL
  pure_quanta q_res *
  page227_i159
#ISCELL
  standard offpage *
  page227_i16
#ISCELL
  logical_power universal_power *
  page227_i160
#ISCELL
  standard offpage *
  page227_i161
#ISCELL
  standard offpage *
  page227_i162
#ISCELL
  standard offpage *
  page227_i163
#CELL
  pure_quanta q_res *
  page227_i164
#ISCELL
  standard offpage *
  page227_i165
#ISCELL
  standard offpage *
  page227_i166
#CELL
  pure_quanta q_res *
  page227_i167
#ISCELL
  standard offpage *
  page227_i168
#ISCELL
  standard offpage *
  page227_i169
#ISCELL
  standard offpage *
  page227_i17
#ISCELL
  standard offpage *
  page227_i170
#ISCELL
  logical_power universal_gnd *
  page227_i171
#CELL
  pure_quanta q_res *
  page227_i172
#CELL
  pure_quanta sconn168_me1016810202011 *
  page227_i173
#CELL
  pure_quanta q_res *
  page227_i18
#CELL
  pure_quanta q_res *
  page227_i19
#CELL
  pure_quanta q_res *
  page227_i2
#CELL
  pure_quanta q_res *
  page227_i20
#CELL
  pure_quanta q_res *
  page227_i21
#CELL
  pure_quanta q_res *
  page227_i22
#CELL
  pure_quanta q_res *
  page227_i23
#CELL
  pure_quanta q_res *
  page227_i24
#CELL
  pure_quanta q_res *
  page227_i25
#CELL
  pure_quanta q_res *
  page227_i26
#CELL
  pure_quanta q_res *
  page227_i27
#CELL
  pure_quanta q_res *
  page227_i28
#ISCELL
  standard offpage *
  page227_i29
#ISCELL
  standard offpage *
  page227_i3
#ISCELL
  standard offpage *
  page227_i30
#ISCELL
  standard offpage *
  page227_i31
#ISCELL
  standard offpage *
  page227_i32
#ISCELL
  standard offpage *
  page227_i33
#ISCELL
  standard offpage *
  page227_i34
#ISCELL
  standard offpage *
  page227_i35
#ISCELL
  standard offpage *
  page227_i36
#ISCELL
  standard offpage *
  page227_i37
#ISCELL
  standard offpage *
  page227_i38
#ISCELL
  standard offpage *
  page227_i39
#ISCELL
  standard offpage *
  page227_i4
#ISCELL
  logical_power universal_gnd *
  page227_i40
#ISCELL
  logical_power universal_gnd *
  page227_i41
#ISCELL
  standard offpage *
  page227_i42
#ISCELL
  standard offpage *
  page227_i43
#ISCELL
  standard offpage *
  page227_i44
#ISCELL
  standard offpage *
  page227_i45
#ISCELL
  standard offpage *
  page227_i46
#ISCELL
  standard offpage *
  page227_i47
#CELL
  pure_quanta q_res *
  page227_i48
#CELL
  pure_quanta q_res *
  page227_i49
#ISCELL
  standard offpage *
  page227_i5
#ISCELL
  standard offpage *
  page227_i50
#ISCELL
  standard offpage *
  page227_i51
#ISCELL
  standard offpage *
  page227_i52
#ISCELL
  standard offpage *
  page227_i53
#ISCELL
  standard offpage *
  page227_i54
#ISCELL
  standard offpage *
  page227_i55
#ISCELL
  standard offpage *
  page227_i56
#CELL
  pure_quanta q_res *
  page227_i57
#CELL
  pure_quanta q_res *
  page227_i58
#ISCELL
  standard offpage *
  page227_i59
#ISCELL
  standard offpage *
  page227_i6
#ISCELL
  standard offpage *
  page227_i60
#ISCELL
  standard offpage *
  page227_i61
#ISCELL
  standard offpage *
  page227_i62
#ISCELL
  standard offpage *
  page227_i63
#ISCELL
  standard offpage *
  page227_i64
#ISCELL
  standard offpage *
  page227_i65
#ISCELL
  standard offpage *
  page227_i66
#ISCELL
  standard offpage *
  page227_i67
#ISCELL
  standard offpage *
  page227_i68
#ISCELL
  standard offpage *
  page227_i69
#ISCELL
  standard offpage *
  page227_i7
#ISCELL
  standard offpage *
  page227_i70
#ISCELL
  standard offpage *
  page227_i71
#ISCELL
  standard offpage *
  page227_i72
#ISCELL
  standard offpage *
  page227_i73
#ISCELL
  standard offpage *
  page227_i74
#ISCELL
  standard offpage *
  page227_i75
#ISCELL
  standard offpage *
  page227_i76
#ISCELL
  standard offpage *
  page227_i77
#ISCELL
  standard offpage *
  page227_i78
#ISCELL
  standard offpage *
  page227_i79
#ISCELL
  standard offpage *
  page227_i8
#ISCELL
  standard offpage *
  page227_i80
#ISCELL
  logical_power universal_gnd *
  page227_i81
#CELL
  pure_quanta q_cap *
  page227_i82
#ISCELL
  logical_power universal_power *
  page227_i83
#CELL
  pure_quanta q_res *
  page227_i84
#CELL
  pure_quanta q_res *
  page227_i85
#CELL
  pure_quanta q_res *
  page227_i86
#CELL
  pure_quanta q_res *
  page227_i87
#CELL
  pure_quanta q_res *
  page227_i88
#CELL
  pure_quanta q_res *
  page227_i89
#ISCELL
  standard offpage *
  page227_i9
#CELL
  pure_quanta q_res *
  page227_i90
#CELL
  pure_quanta q_res *
  page227_i91
#CELL
  pure_quanta q_res *
  page227_i92
#CELL
  pure_quanta q_res *
  page227_i93
#CELL
  pure_quanta q_res *
  page227_i94
#CELL
  pure_quanta q_res *
  page227_i95
#CELL
  pure_quanta q_res *
  page227_i96
#CELL
  pure_quanta q_res *
  page227_i97
#CELL
  pure_quanta q_res *
  page227_i98
#CELL
  pure_quanta q_res *
  page227_i99
#ISCELL
  logical_power cad_note *
  *
#ISCELL
  mstr_misc dns *
  *
#ISCELL
  pure_quanta quanta_title_block_c *
  *
#ISCELL
  logical_power universal_power *
  page228_i1
#ISCELL
  standard offpage *
  page228_i10
#ISCELL
  standard offpage *
  page228_i100
#ISCELL
  standard offpage *
  page228_i101
#ISCELL
  standard offpage *
  page228_i11
#ISCELL
  standard offpage *
  page228_i12
#ISCELL
  standard offpage *
  page228_i13
#ISCELL
  standard offpage *
  page228_i16
#ISCELL
  standard offpage *
  page228_i17
#CELL
  pure_quanta q_res *
  page228_i172
#CELL
  pure_quanta q_res *
  page228_i173
#CELL
  pure_quanta q_res *
  page228_i176
#CELL
  pure_quanta q_res *
  page228_i177
#ISCELL
  standard offpage *
  page228_i178
#ISCELL
  standard offpage *
  page228_i179
#ISCELL
  standard offpage *
  page228_i18
#ISCELL
  standard offpage *
  page228_i182
#ISCELL
  standard offpage *
  page228_i183
#ISCELL
  standard offpage *
  page228_i19
#ISCELL
  standard offpage *
  page228_i199
#CELL
  pure_quanta q_res *
  page228_i2
#ISCELL
  standard offpage *
  page228_i20
#ISCELL
  standard offpage *
  page228_i201
#CELL
  pure_quanta q_res *
  page228_i202
#CELL
  pure_quanta q_res *
  page228_i203
#ISCELL
  standard offpage *
  page228_i204
#ISCELL
  standard offpage *
  page228_i205
#CELL
  pure_quanta q_res *
  page228_i206
#CELL
  pure_quanta q_res *
  page228_i207
#ISCELL
  standard offpage *
  page228_i208
#ISCELL
  standard offpage *
  page228_i209
#ISCELL
  standard offpage *
  page228_i21
#ISCELL
  standard offpage *
  page228_i210
#ISCELL
  standard offpage *
  page228_i211
#ISCELL
  standard offpage *
  page228_i214
#ISCELL
  standard offpage *
  page228_i215
#CELL
  pure_quanta q_res *
  page228_i216
#CELL
  pure_quanta q_res *
  page228_i217
#CELL
  pure_quanta q_res *
  page228_i218
#CELL
  pure_quanta q_res *
  page228_i219
#ISCELL
  standard offpage *
  page228_i22
#ISCELL
  standard offpage *
  page228_i226
#ISCELL
  standard offpage *
  page228_i227
#CELL
  pure_quanta q_res *
  page228_i228
#CELL
  pure_quanta q_res *
  page228_i229
#ISCELL
  standard offpage *
  page228_i23
#CELL
  pure_quanta q_res *
  page228_i230
#CELL
  pure_quanta q_res *
  page228_i231
#ISCELL
  standard offpage *
  page228_i232
#ISCELL
  standard offpage *
  page228_i233
#CELL
  pure_quanta q_res *
  page228_i234
#ISCELL
  standard offpage *
  page228_i235
#ISCELL
  standard offpage *
  page228_i236
#CELL
  pure_quanta q_res *
  page228_i237
#ISCELL
  standard offpage *
  page228_i238
#ISCELL
  standard offpage *
  page228_i239
#ISCELL
  standard offpage *
  page228_i240
#ISCELL
  standard offpage *
  page228_i241
#CELL
  pure_quanta q_res *
  page228_i242
#CELL
  pure_quanta q_res *
  page228_i243
#CELL
  pure_quanta q_res *
  page228_i250
#CELL
  pure_quanta q_res *
  page228_i251
#ISCELL
  standard offpage *
  page228_i252
#ISCELL
  standard offpage *
  page228_i253
#ISCELL
  standard offpage *
  page228_i254
#ISCELL
  standard offpage *
  page228_i255
#ISCELL
  standard offpage *
  page228_i256
#ISCELL
  standard offpage *
  page228_i257
#CELL
  pure_quanta q_res *
  page228_i258
#CELL
  pure_quanta q_res *
  page228_i259
#CELL
  pure_quanta q_res *
  page228_i260
#CELL
  pure_quanta q_res *
  page228_i261
#ISCELL
  standard offpage *
  page228_i262
#ISCELL
  standard offpage *
  page228_i263
#CELL
  pure_quanta q_res *
  page228_i264
#ISCELL
  standard offpage *
  page228_i266
#ISCELL
  standard offpage *
  page228_i267
#CELL
  pure_quanta q_res *
  page228_i268
#ISCELL
  standard offpage *
  page228_i269
#ISCELL
  standard offpage *
  page228_i270
#CELL
  pure_quanta q_res *
  page228_i271
#CELL
  pure_quanta q_res *
  page228_i272
#CELL
  pure_quanta q_res *
  page228_i273
#CELL
  pure_quanta q_res *
  page228_i274
#ISCELL
  standard offpage *
  page228_i275
#ISCELL
  standard offpage *
  page228_i276
#ISCELL
  standard offpage *
  page228_i277
#ISCELL
  standard offpage *
  page228_i278
#ISCELL
  standard offpage *
  page228_i28
#CELL
  pure_quanta q_res *
  page228_i284
#CELL
  pure_quanta q_res *
  page228_i285
#ISCELL
  standard offpage *
  page228_i286
#ISCELL
  standard offpage *
  page228_i287
#ISCELL
  standard offpage *
  page228_i288
#ISCELL
  standard offpage *
  page228_i289
#ISCELL
  standard offpage *
  page228_i29
#ISCELL
  standard offpage *
  page228_i290
#ISCELL
  standard offpage *
  page228_i291
#CELL
  pure_quanta q_res *
  page228_i293
#ISCELL
  standard offpage *
  page228_i294
#ISCELL
  standard offpage *
  page228_i295
#CELL
  pure_quanta q_res *
  page228_i296
#ISCELL
  standard offpage *
  page228_i299
#CELL
  pure_quanta q_res *
  page228_i3
#ISCELL
  standard offpage *
  page228_i30
#ISCELL
  standard offpage *
  page228_i300
#ISCELL
  standard offpage *
  page228_i301
#ISCELL
  standard offpage *
  page228_i302
#CELL
  pure_quanta q_res *
  page228_i303
#CELL
  pure_quanta q_res *
  page228_i304
#CELL
  pure_quanta q_res *
  page228_i305
#CELL
  pure_quanta q_res *
  page228_i306
#ISCELL
  standard offpage *
  page228_i307
#ISCELL
  standard offpage *
  page228_i308
#ISCELL
  standard offpage *
  page228_i309
#ISCELL
  standard offpage *
  page228_i31
#ISCELL
  standard offpage *
  page228_i310
#CELL
  pure_quanta q_res *
  page228_i311
#CELL
  pure_quanta q_res *
  page228_i312
#CELL
  pure_quanta q_res *
  page228_i313
#CELL
  pure_quanta q_res *
  page228_i314
#CELL
  pure_quanta q_res *
  page228_i315
#CELL
  pure_quanta q_res *
  page228_i316
#CELL
  pure_quanta q_res *
  page228_i317
#CELL
  pure_quanta q_res *
  page228_i318
#ISCELL
  standard offpage *
  page228_i32
#ISCELL
  standard offpage *
  page228_i33
#ISCELL
  standard offpage *
  page228_i34
#ISCELL
  standard offpage *
  page228_i35
#CELL
  pure_quanta q_res *
  page228_i38
#CELL
  pure_quanta q_res *
  page228_i39
#CELL
  pure_quanta q_res *
  page228_i4
#CELL
  pure_quanta q_res *
  page228_i40
#CELL
  pure_quanta q_res *
  page228_i41
#CELL
  pure_quanta q_res *
  page228_i42
#CELL
  pure_quanta q_res *
  page228_i43
#CELL
  pure_quanta q_res *
  page228_i44
#CELL
  pure_quanta q_res *
  page228_i45
#CELL
  pure_quanta q_res *
  page228_i5
#ISCELL
  standard offpage *
  page228_i52
#ISCELL
  standard offpage *
  page228_i53
#ISCELL
  standard offpage *
  page228_i54
#ISCELL
  standard offpage *
  page228_i55
#ISCELL
  standard offpage *
  page228_i56
#ISCELL
  standard offpage *
  page228_i57
#CELL
  pure_quanta q_res *
  page228_i6
#ISCELL
  standard offpage *
  page228_i66
#ISCELL
  standard offpage *
  page228_i67
#ISCELL
  standard offpage *
  page228_i68
#ISCELL
  standard offpage *
  page228_i69
#CELL
  pure_quanta q_res *
  page228_i7
#ISCELL
  standard offpage *
  page228_i70
#ISCELL
  standard offpage *
  page228_i71
#ISCELL
  standard offpage *
  page228_i72
#ISCELL
  standard offpage *
  page228_i73
#ISCELL
  standard offpage *
  page228_i8
#CELL
  pure_quanta q_res *
  page228_i89
#ISCELL
  standard offpage *
  page228_i9
#CELL
  pure_quanta q_res *
  page228_i90
#ISCELL
  standard offpage *
  page228_i91
#ISCELL
  standard offpage *
  page228_i92
#ISCELL
  mstr_misc dns *
  *
#ISCELL
  pure_quanta quanta_title_block_c *
  *
#ISCELL
  standard offpage *
  page229_i1
#ISCELL
  logical_power universal_gnd *
  page229_i10
#CELL
  pure_quanta q_res *
  page229_i11
#CELL
  pure_quanta q_res *
  page229_i12
#ISCELL
  logical_power gnd *
  page229_i13
#CELL
  pure_quanta q_res *
  page229_i14
#ISCELL
  standard offpage *
  page229_i15
#ISCELL
  logical_power universal_power *
  page229_i16
#CELL
  pure_quanta q_res *
  page229_i17
#CELL
  pure_quanta q_res *
  page229_i18
#ISCELL
  logical_power universal_power *
  page229_i19
#CELL
  pure_quanta q_res *
  page229_i2
#CELL
  pure_quanta q_res *
  page229_i20
#CELL
  pure_quanta mosfet_nch_dual *
  page229_i21
#ISCELL
  logical_power gnd *
  page229_i22
#ISCELL
  logical_power gnd *
  page229_i23
#CELL
  pure_quanta q_res *
  page229_i24
#ISCELL
  logical_power universal_power *
  page229_i25
#CELL
  pure_quanta mosfet_nch_dual *
  page229_i26
#CELL
  pure_quanta q_res *
  page229_i27
#ISCELL
  logical_power gnd *
  page229_i28
#CELL
  pure_quanta diode_tvs *
  page229_i29
#CELL
  pure_quanta q_res *
  page229_i3
#ISCELL
  logical_power universal_power *
  page229_i30
#CELL
  pure_quanta q_cap *
  page229_i31
#ISCELL
  logical_power gnd *
  page229_i32
#CELL
  pure_quanta q_cap *
  page229_i33
#CELL
  pure_quanta q_res *
  page229_i34
#ISCELL
  logical_power gnd *
  page229_i35
#ISCELL
  logical_power gnd *
  page229_i36
#CELL
  pure_quanta q_cap *
  page229_i37
#ISCELL
  logical_power universal_power *
  page229_i38
#CELL
  pure_quanta q_res *
  page229_i39
#ISCELL
  logical_power gnd *
  page229_i4
#CELL
  pure_quanta q_cap *
  page229_i42
#ISCELL
  logical_power gnd *
  page229_i43
#CELL
  pure_quanta q_res *
  page229_i44
#ISCELL
  logical_power gnd *
  page229_i45
#ISCELL
  standard offpage *
  page229_i46
#ISCELL
  standard offpage *
  page229_i47
#CELL
  pure_quanta q_res *
  page229_i48
#ISCELL
  logical_power vccaux15 *
  page229_i49
#ISCELL
  logical_power gnd *
  page229_i5
#CELL
  pure_quanta q_res *
  page229_i50
#CELL
  pure_quanta q_res *
  page229_i51
#CELL
  pure_quanta q_res *
  page229_i52
#CELL
  pure_quanta q_cap *
  page229_i53
#CELL
  pure_quanta q_res *
  page229_i54
#ISCELL
  logical_power universal_power *
  page229_i55
#ISCELL
  logical_power gnd *
  page229_i56
#CELL
  pure_quanta q_cap *
  page229_i57
#ISCELL
  logical_power universal_power *
  page229_i58
#ISCELL
  standard offpage *
  page229_i59
#ISCELL
  logical_power gnd *
  page229_i6
#ISCELL
  logical_power gnd *
  page229_i60
#CELL
  pure_quanta q_res *
  page229_i61
#ISCELL
  logical_power gnd *
  page229_i62
#CELL
  pure_quanta q_res *
  page229_i63
#CELL
  pure_quanta q_res *
  page229_i64
#ISCELL
  logical_power gnd *
  page229_i65
#CELL
  pure_quanta q_cap *
  page229_i66
#CELL
  pure_quanta q_res *
  page229_i67
#CELL
  pure_quanta q_cap *
  page229_i68
#CELL
  pure_quanta max15090bewit *
  page229_i69
#CELL
  pure_quanta q_cap *
  page229_i7
#CELL
  pure_quanta q_res *
  page229_i70
#ISCELL
  logical_power gnd *
  page229_i71
#CELL
  pure_quanta q_res *
  page229_i72
#CELL
  pure_quanta q_cap *
  page229_i73
#CELL
  pure_quanta q_res *
  page229_i74
#CELL
  pure_quanta q_cap *
  page229_i75
#CELL
  pure_quanta q_res *
  page229_i76
#CELL
  pure_quanta q_res *
  page229_i77
#ISCELL
  logical_power gnd *
  page229_i78
#CELL
  pure_quanta q_res *
  page229_i79
#CELL
  pure_quanta q_cap *
  page229_i8
#ISCELL
  logical_power vccaux15 *
  page229_i80
#CELL
  pure_quanta q_res *
  page229_i81
#CELL
  pure_quanta schottky_ac *
  page229_i82
#CELL
  pure_quanta q_cap *
  page229_i83
#CELL
  pure_quanta q_cap *
  page229_i84
#ISCELL
  standard offpage *
  page229_i85
#ISCELL
  standard offpage *
  page229_i86
#ISCELL
  logical_power gnd *
  page229_i87
#CELL
  pure_quanta q_cap *
  page229_i88
#ISCELL
  logical_power universal_power *
  page229_i89
#CELL
  pure_quanta mosfet_nch_gds_esd_protected *
  page229_i9
#CELL
  pure_quanta rs31312r *
  page229_i90
#CELL
  pure_quanta q_res *
  page229_i91
#CELL
  pure_quanta q_res *
  page229_i92
#ISCELL
  logical_power vccaux15 *
  page229_i93
#ISCELL
  standard offpage *
  page229_i94
#ISCELL
  mstr_misc dns *
  *
#ISCELL
  pure_quanta quanta_title_block_c *
  *
#CELL
  pure_quanta m24128bwmn6tp *
  page231_i35
#ISCELL
  standard offpage *
  page231_i40
#ISCELL
  standard offpage *
  page231_i41
#CELL
  pure_quanta q_res *
  page231_i45
#CELL
  pure_quanta q_res *
  page231_i47
#ISCELL
  logical_power universal_gnd *
  page231_i49
#CELL
  pure_quanta q_res *
  page231_i50
#ISCELL
  logical_power universal_gnd *
  page231_i51
#CELL
  pure_quanta q_res *
  page231_i52
#ISCELL
  logical_power universal_gnd *
  page231_i53
#ISCELL
  logical_power universal_power *
  page231_i54
#CELL
  pure_quanta q_cap *
  page231_i55
#ISCELL
  logical_power universal_gnd *
  page231_i56
#CELL
  pure_quanta q_res *
  page231_i57
#ISCELL
  logical_power universal_gnd *
  page231_i58
#ISCELL
  logical_power universal_gnd *
  page231_i59
#ISCELL
  logical_power universal_power *
  page231_i60
#CELL
  pure_quanta q_res *
  page231_i61
#CELL
  pure_quanta q_res *
  page231_i62
#CELL
  pure_quanta q_res *
  page231_i93
#CELL
  pure_quanta q_res *
  page231_i95
#ISCELL
  logical_power universal_power *
  page231_i96
#ISCELL
  logical_power bom_note *
  *
#ISCELL
  logical_power cad_note *
  *
#ISCELL
  mstr_misc dns *
  *
#ISCELL
  pure_quanta quanta_title_block_c *
  *
#ISCELL
  standard offpage *
  page232_i1
#ISCELL
  logical_power universal_gnd *
  page232_i10
#CELL
  pure_quanta 74lvc1g07se7 *
  page232_i11
#ISCELL
  logical_power universal_power *
  page232_i12
#CELL
  pure_quanta q_res *
  page232_i13
#CELL
  pure_quanta mosfet_nch_gds_esd_protected *
  page232_i14
#ISCELL
  logical_power universal_gnd *
  page232_i15
#CELL
  pure_quanta q_res *
  page232_i16
#ISCELL
  logical_power universal_gnd *
  page232_i17
#CELL
  pure_quanta q_res *
  page232_i18
#ISCELL
  logical_power universal_power *
  page232_i19
#ISCELL
  logical_power universal_gnd *
  page232_i2
#CELL
  pure_quanta q_res *
  page232_i20
#CELL
  pure_quanta q_res *
  page232_i21
#CELL
  pure_quanta q_res *
  page232_i22
#ISCELL
  logical_power universal_gnd *
  page232_i23
#CELL
  pure_quanta q_cap *
  page232_i24
#ISCELL
  standard offpage *
  page232_i25
#CELL
  pure_quanta tps3895adryr *
  page232_i26
#CELL
  pure_quanta adm1086akszreel7 *
  page232_i27
#ISCELL
  logical_power universal_power *
  page232_i28
#ISCELL
  logical_power universal_power *
  page232_i29
#CELL
  pure_quanta q_res *
  page232_i3
#ISCELL
  logical_power universal_gnd *
  page232_i30
#CELL
  pure_quanta q_res *
  page232_i31
#CELL
  pure_quanta q_res *
  page232_i32
#CELL
  pure_quanta q_res *
  page232_i33
#ISCELL
  logical_power universal_gnd *
  page232_i34
#CELL
  pure_quanta q_cap *
  page232_i35
#CELL
  pure_quanta q_res *
  page232_i36
#ISCELL
  logical_power universal_power *
  page232_i37
#ISCELL
  logical_power universal_gnd *
  page232_i38
#CELL
  pure_quanta mosfet_nch_gds_esd_protected *
  page232_i39
#CELL
  pure_quanta q_res *
  page232_i4
#CELL
  pure_quanta q_res *
  page232_i40
#ISCELL
  logical_power universal_power *
  page232_i41
#ISCELL
  standard offpage *
  page232_i42
#ISCELL
  standard offpage *
  page232_i43
#ISCELL
  standard offpage *
  page232_i44
#ISCELL
  logical_power universal_gnd *
  page232_i45
#ISCELL
  logical_power universal_gnd *
  page232_i46
#CELL
  pure_quanta q_cap *
  page232_i47
#ISCELL
  standard offpage *
  page232_i48
#ISCELL
  logical_power universal_power *
  page232_i5
#ISCELL
  logical_power universal_gnd *
  page232_i6
#CELL
  pure_quanta q_cap *
  page232_i7
#ISCELL
  logical_power universal_gnd *
  page232_i8
#CELL
  pure_quanta q_cap *
  page232_i9
#ISCELL
  mstr_misc dns *
  *
#ISCELL
  pure_quanta quanta_title_block_c *
  *
#ISCELL
  standard offpage *
  page233_i1
#CELL
  pure_quanta q_res *
  page233_i10
#ISCELL
  logical_power universal_gnd *
  page233_i11
#CELL
  pure_quanta conn60_101062636003k02lf *
  page233_i12
#ISCELL
  logical_power universal_gnd *
  page233_i13
#CELL
  pure_quanta q_res *
  page233_i14
#CELL
  pure_quanta q_res *
  page233_i15
#CELL
  pure_quanta ltc4307cms8 *
  page233_i16
#ISCELL
  logical_power universal_gnd *
  page233_i17
#ISCELL
  logical_power universal_power *
  page233_i18
#CELL
  pure_quanta q_cap *
  page233_i19
#ISCELL
  logical_power universal_gnd *
  page233_i2
#CELL
  pure_quanta q_res *
  page233_i20
#CELL
  pure_quanta q_res *
  page233_i21
#CELL
  pure_quanta q_res *
  page233_i22
#ISCELL
  logical_power universal_power *
  page233_i23
#CELL
  pure_quanta q_res *
  page233_i24
#ISCELL
  standard offpage *
  page233_i25
#ISCELL
  standard offpage *
  page233_i26
#ISCELL
  standard offpage *
  page233_i27
#ISCELL
  standard offpage *
  page233_i28
#ISCELL
  standard offpage *
  page233_i29
#CELL
  pure_quanta q_res *
  page233_i3
#ISCELL
  standard offpage *
  page233_i30
#ISCELL
  standard offpage *
  page233_i31
#ISCELL
  standard offpage *
  page233_i32
#ISCELL
  standard offpage *
  page233_i33
#CELL
  pure_quanta q_res *
  page233_i34
#CELL
  pure_quanta q_res *
  page233_i35
#ISCELL
  logical_power universal_power *
  page233_i36
#CELL
  pure_quanta q_res *
  page233_i37
#CELL
  pure_quanta q_res *
  page233_i38
#CELL
  pure_quanta q_res *
  page233_i39
#CELL
  pure_quanta q_res *
  page233_i4
#ISCELL
  standard offpage *
  page233_i40
#CELL
  pure_quanta q_res *
  page233_i41
#ISCELL
  logical_power universal_power *
  page233_i42
#ISCELL
  standard offpage *
  page233_i43
#ISCELL
  standard offpage *
  page233_i44
#ISCELL
  standard offpage *
  page233_i45
#ISCELL
  standard offpage *
  page233_i46
#ISCELL
  standard offpage *
  page233_i47
#ISCELL
  standard offpage *
  page233_i48
#ISCELL
  standard offpage *
  page233_i49
#ISCELL
  logical_power universal_power *
  page233_i5
#ISCELL
  standard offpage *
  page233_i50
#CELL
  pure_quanta q_cap *
  page233_i51
#CELL
  pure_quanta q_cap *
  page233_i52
#CELL
  pure_quanta q_cap *
  page233_i53
#CELL
  pure_quanta q_cap *
  page233_i54
#CELL
  pure_quanta q_cap *
  page233_i55
#ISCELL
  logical_power universal_gnd *
  page233_i56
#CELL
  pure_quanta q_cap *
  page233_i57
#ISCELL
  standard offpage *
  page233_i6
#ISCELL
  standard offpage *
  page233_i7
#CELL
  pure_quanta q_res *
  page233_i8
#CELL
  pure_quanta q_res *
  page233_i9
#ISCELL
  mstr_misc dns *
  *
#ISCELL
  pure_quanta quanta_title_block_c *
  *
#ISCELL
  logical_power universal_power *
  page230_i10
#ISCELL
  logical_power universal_gnd *
  page230_i12
#ISCELL
  logical_power universal_gnd *
  page230_i13
#CELL
  pure_quanta q_cap *
  page230_i14
#ISCELL
  logical_power universal_power *
  page230_i15
#ISCELL
  logical_power universal_gnd *
  page230_i22
#CELL
  pure_quanta q_res *
  page230_i24
#CELL
  pure_quanta q_res *
  page230_i25
#ISCELL
  logical_power universal_power *
  page230_i26
#ISCELL
  standard offpage *
  page230_i27
#CELL
  pure_quanta q_res *
  page230_i28
#CELL
  pure_quanta q_res *
  page230_i29
#CELL
  pure_quanta q_res *
  page230_i30
#CELL
  pure_quanta 74lvc1g08w57 *
  page230_i31
#CELL
  pure_quanta q_res *
  page230_i34
#ISCELL
  standard offpage *
  page230_i35
#ISCELL
  logical_power universal_gnd *
  page230_i36
#CELL
  pure_quanta 74lvc2g07dw7 *
  page230_i37
#ISCELL
  logical_power universal_power *
  page230_i38
#ISCELL
  logical_power universal_gnd *
  page230_i39
#CELL
  pure_quanta q_cap *
  page230_i40
#CELL
  pure_quanta q_res *
  page230_i41
#ISCELL
  standard offpage *
  page230_i42
#CELL
  pure_quanta q_res *
  page230_i43
#ISCELL
  logical_power universal_gnd *
  page230_i44
#ISCELL
  standard offpage *
  page230_i45
#ISCELL
  logical_power universal_power *
  page230_i46
#CELL
  pure_quanta q_res *
  page230_i47
#CELL
  pure_quanta q_res *
  page230_i48
#ISCELL
  standard offpage *
  page230_i49
#CELL
  pure_quanta q_res *
  page230_i50
#CELL
  pure_quanta q_res *
  page230_i51
#ISCELL
  logical_power universal_power *
  page230_i52
#CELL
  pure_quanta mosfet_nch_dual *
  page230_i53
#ISCELL
  logical_power universal_gnd *
  page230_i54
#CELL
  pure_quanta q_res *
  page230_i55
#ISCELL
  logical_power universal_power *
  page230_i56
#ISCELL
  logical_power universal_gnd *
  page230_i57
#CELL
  pure_quanta mosfet_nch_dual *
  page230_i58
#CELL
  pure_quanta q_res *
  page230_i59
#ISCELL
  logical_power universal_gnd *
  page230_i6
#ISCELL
  logical_power universal_power *
  page230_i60
#ISCELL
  logical_power universal_gnd *
  page230_i61
#CELL
  pure_quanta q_cap *
  page230_i62
#ISCELL
  standard offpage *
  page230_i63
#ISCELL
  logical_power universal_gnd *
  page230_i64
#ISCELL
  standard offpage *
  page230_i7
#ISCELL
  pure_quanta quanta_title_block_c *
  *
#ISCELL
  standard offpage *
  page234_i1
#CELL
  pure_quanta q_res *
  page234_i10
#ISCELL
  logical_power universal_power *
  page234_i11
#CELL
  pure_quanta mosfet_nch_gds_esd_protected *
  page234_i14
#ISCELL
  logical_power universal_gnd *
  page234_i15
#CELL
  pure_quanta q_res *
  page234_i3
#ISCELL
  logical_power universal_gnd *
  page234_i5
#CELL
  pure_quanta mosfet_nch_gds_esd_protected *
  page234_i6
#CELL
  pure_quanta q_res *
  page234_i7
#CELL
  pure_quanta q_res *
  page234_i8
#ISCELL
  logical_power universal_power *
  page234_i9
#ISCELL
  mstr_misc dns *
  *
#ISCELL
  pure_quanta quanta_title_block_c *
  *
#ISCELL
  logical_power universal_gnd *
  page235_i1
#ISCELL
  logical_power universal_gnd *
  page235_i10
#CELL
  pure_quanta q_res *
  page235_i11
#ISCELL
  logical_power universal_power *
  page235_i12
#CELL
  pure_quanta conn3_210hp1030br1 *
  page235_i13
#CELL
  pure_quanta q_res *
  page235_i14
#CELL
  pure_quanta q_res *
  page235_i15
#CELL
  pure_quanta q_res *
  page235_i16
#CELL
  pure_quanta q_res *
  page235_i17
#CELL
  pure_quanta q_res *
  page235_i18
#CELL
  pure_quanta 74cbtlv3126pw *
  page235_i19
#ISCELL
  standard offpage *
  page235_i2
#ISCELL
  logical_power universal_gnd *
  page235_i20
#ISCELL
  logical_power universal_power *
  page235_i21
#ISCELL
  logical_power universal_gnd *
  page235_i22
#CELL
  pure_quanta q_cap *
  page235_i23
#CELL
  pure_quanta q_res *
  page235_i24
#CELL
  pure_quanta q_res *
  page235_i25
#CELL
  pure_quanta q_res *
  page235_i26
#CELL
  pure_quanta q_res *
  page235_i27
#ISCELL
  standard offpage *
  page235_i28
#ISCELL
  standard offpage *
  page235_i29
#CELL
  pure_quanta q_res *
  page235_i3
#ISCELL
  standard offpage *
  page235_i30
#ISCELL
  standard offpage *
  page235_i31
#CELL
  pure_quanta q_res *
  page235_i4
#ISCELL
  logical_power universal_power *
  page235_i5
#ISCELL
  standard offpage *
  page235_i6
#ISCELL
  standard offpage *
  page235_i7
#ISCELL
  standard offpage *
  page235_i8
#ISCELL
  standard offpage *
  page235_i9
#ISCELL
  pure_quanta quanta_title_block_c *
  *
#ISCELL
  logical_power cad_note *
  *
#ISCELL
  mstr_misc dns *
  *
#ISCELL
  pure_quanta quanta_title_block_c *
  *
#ISCELL
  logical_power universal_gnd *
  page239_i101
#ISCELL
  logical_power universal_gnd *
  page239_i102
#CELL
  pure_quanta adc128d818cimtxnopb *
  page239_i103
#ISCELL
  standard offpage *
  page239_i108
#ISCELL
  standard offpage *
  page239_i109
#CELL
  pure_quanta q_res *
  page239_i110
#CELL
  pure_quanta q_res *
  page239_i111
#ISCELL
  standard offpage *
  page239_i112
#ISCELL
  standard offpage *
  page239_i113
#ISCELL
  standard offpage *
  page239_i114
#ISCELL
  standard offpage *
  page239_i115
#ISCELL
  logical_power universal_power *
  page239_i117
#CELL
  pure_quanta q_inductor *
  page239_i118
#ISCELL
  standard offpage *
  page239_i125
#ISCELL
  standard offpage *
  page239_i126
#CELL
  pure_quanta q_cap *
  page239_i127
#CELL
  pure_quanta q_cap *
  page239_i128
#CELL
  pure_quanta q_res *
  page239_i129
#ISCELL
  logical_power universal_gnd *
  page239_i130
#CELL
  pure_quanta q_res *
  page239_i131
#ISCELL
  logical_power universal_gnd *
  page239_i132
#ISCELL
  logical_power universal_gnd *
  page239_i133
#ISCELL
  logical_power universal_power *
  page239_i140
#CELL
  pure_quanta q_res *
  page239_i141
#CELL
  pure_quanta q_res *
  page239_i149
#ISCELL
  logical_power universal_gnd *
  page239_i150
#ISCELL
  logical_power universal_power *
  page239_i160
#CELL
  pure_quanta q_res *
  page239_i161
#CELL
  pure_quanta q_res *
  page239_i162
#CELL
  pure_quanta q_res *
  page239_i163
#ISCELL
  logical_power universal_power *
  page239_i167
#CELL
  pure_quanta q_res *
  page239_i168
#ISCELL
  logical_power universal_power *
  page239_i172
#CELL
  pure_quanta q_res *
  page239_i173
#CELL
  pure_quanta q_res *
  page239_i174
#CELL
  pure_quanta q_res *
  page239_i176
#ISCELL
  standard offpage *
  page239_i177
#ISCELL
  standard offpage *
  page239_i178
#CELL
  pure_quanta q_res *
  page239_i179
#CELL
  pure_quanta q_cap *
  page239_i180
#CELL
  pure_quanta q_cap *
  page239_i181
#ISCELL
  logical_power universal_gnd *
  page239_i182
#ISCELL
  logical_power universal_gnd *
  page239_i183
#ISCELL
  standard offpage *
  page239_i184
#ISCELL
  standard offpage *
  page239_i185
#ISCELL
  logical_power universal_gnd *
  page239_i186
#CELL
  pure_quanta q_cap *
  page239_i187
#CELL
  pure_quanta q_cap *
  page239_i188
#ISCELL
  logical_power universal_gnd *
  page239_i189
#CELL
  pure_quanta q_res *
  page239_i19
#CELL
  pure_quanta q_res *
  page239_i190
#CELL
  pure_quanta q_res *
  page239_i191
#ISCELL
  logical_power universal_gnd *
  page239_i192
#ISCELL
  standard offpage *
  page239_i193
#ISCELL
  standard offpage *
  page239_i194
#ISCELL
  logical_power universal_gnd *
  page239_i195
#CELL
  pure_quanta q_cap *
  page239_i196
#CELL
  pure_quanta q_cap *
  page239_i197
#ISCELL
  logical_power universal_gnd *
  page239_i198
#CELL
  pure_quanta q_res *
  page239_i199
#CELL
  pure_quanta q_res *
  page239_i20
#CELL
  pure_quanta q_res *
  page239_i200
#ISCELL
  logical_power universal_gnd *
  page239_i201
#ISCELL
  logical_power universal_gnd *
  page239_i202
#ISCELL
  standard offpage *
  page239_i203
#ISCELL
  standard offpage *
  page239_i204
#CELL
  pure_quanta q_cap *
  page239_i205
#ISCELL
  logical_power universal_gnd *
  page239_i206
#CELL
  pure_quanta q_cap *
  page239_i207
#ISCELL
  logical_power universal_gnd *
  page239_i208
#CELL
  pure_quanta q_res *
  page239_i209
#ISCELL
  standard offpage *
  page239_i21
#CELL
  pure_quanta q_res *
  page239_i210
#ISCELL
  standard offpage *
  page239_i214
#ISCELL
  standard offpage *
  page239_i218
#ISCELL
  standard offpage *
  page239_i22
#ISCELL
  logical_power universal_gnd *
  page239_i222
#CELL
  pure_quanta q_res *
  page239_i223
#CELL
  pure_quanta q_res *
  page239_i224
#ISCELL
  logical_power universal_power *
  page239_i225
#ISCELL
  logical_power universal_gnd *
  page239_i226
#CELL
  pure_quanta q_res *
  page239_i227
#CELL
  pure_quanta q_res *
  page239_i228
#ISCELL
  standard offpage *
  page239_i229
#ISCELL
  standard offpage *
  page239_i23
#ISCELL
  standard offpage *
  page239_i230
#ISCELL
  standard offpage *
  page239_i231
#ISCELL
  standard offpage *
  page239_i232
#ISCELL
  standard offpage *
  page239_i233
#ISCELL
  standard offpage *
  page239_i234
#ISCELL
  standard offpage *
  page239_i235
#CELL
  pure_quanta q_cap *
  page239_i236
#ISCELL
  logical_power universal_gnd *
  page239_i237
#CELL
  pure_quanta q_cap *
  page239_i238
#ISCELL
  logical_power universal_gnd *
  page239_i239
#ISCELL
  standard offpage *
  page239_i24
#CELL
  pure_quanta q_res *
  page239_i240
#CELL
  pure_quanta q_res *
  page239_i241
#ISCELL
  standard offpage *
  page239_i288
#ISCELL
  standard offpage *
  page239_i289
#ISCELL
  standard offpage *
  page239_i290
#ISCELL
  standard offpage *
  page239_i291
#ISCELL
  standard offpage *
  page239_i292
#ISCELL
  standard offpage *
  page239_i293
#ISCELL
  standard offpage *
  page239_i294
#ISCELL
  standard offpage *
  page239_i295
#ISCELL
  standard offpage *
  page239_i297
#ISCELL
  standard offpage *
  page239_i298
#ISCELL
  standard offpage *
  page239_i299
#ISCELL
  standard offpage *
  page239_i300
#ISCELL
  standard offpage *
  page239_i301
#ISCELL
  standard offpage *
  page239_i302
#ISCELL
  logical_power universal_gnd *
  page239_i303
#CELL
  pure_quanta q_cap *
  page239_i304
#CELL
  pure_quanta q_cap *
  page239_i305
#ISCELL
  logical_power universal_gnd *
  page239_i306
#ISCELL
  standard offpage *
  page239_i307
#ISCELL
  standard offpage *
  page239_i308
#CELL
  pure_quanta q_cap *
  page239_i309
#ISCELL
  logical_power universal_gnd *
  page239_i310
#CELL
  pure_quanta q_cap *
  page239_i311
#ISCELL
  logical_power universal_gnd *
  page239_i312
#CELL
  pure_quanta q_res *
  page239_i313
#CELL
  pure_quanta q_res *
  page239_i314
#CELL
  pure_quanta q_res *
  page239_i315
#CELL
  pure_quanta q_res *
  page239_i316
#ISCELL
  standard offpage *
  page239_i317
#ISCELL
  standard offpage *
  page239_i318
#ISCELL
  standard offpage *
  page239_i319
#ISCELL
  standard offpage *
  page239_i320
#CELL
  pure_quanta q_res *
  page239_i321
#CELL
  pure_quanta q_res *
  page239_i322
#CELL
  pure_quanta q_res *
  page239_i323
#CELL
  pure_quanta q_res *
  page239_i324
#ISCELL
  standard offpage *
  page239_i325
#ISCELL
  standard offpage *
  page239_i326
#ISCELL
  standard offpage *
  page239_i327
#ISCELL
  standard offpage *
  page239_i328
#ISCELL
  standard offpage *
  page239_i329
#CELL
  pure_quanta q_res *
  page239_i330
#ISCELL
  standard offpage *
  page239_i331
#ISCELL
  standard offpage *
  page239_i332
#CELL
  pure_quanta q_cap *
  page239_i333
#ISCELL
  logical_power universal_gnd *
  page239_i334
#ISCELL
  logical_power universal_gnd *
  page239_i335
#CELL
  pure_quanta q_cap *
  page239_i336
#CELL
  pure_quanta q_res *
  page239_i337
#CELL
  pure_quanta q_res *
  page239_i338
#CELL
  pure_quanta q_res *
  page239_i339
#ISCELL
  standard offpage *
  page239_i340
#ISCELL
  standard offpage *
  page239_i341
#ISCELL
  standard offpage *
  page239_i342
#ISCELL
  standard offpage *
  page239_i343
#ISCELL
  standard offpage *
  page239_i344
#CELL
  pure_quanta q_res *
  page239_i346
#ISCELL
  logical_power universal_gnd *
  page239_i347
#CELL
  pure_quanta q_res *
  page239_i348
#CELL
  pure_quanta max11617eeet *
  page239_i57
#CELL
  pure_quanta q_cap *
  page239_i58
#ISCELL
  logical_power universal_gnd *
  page239_i60
#CELL
  pure_quanta q_cap *
  page239_i61
#CELL
  pure_quanta q_inductor *
  page239_i62
#ISCELL
  logical_power universal_power *
  page239_i63
#ISCELL
  logical_power universal_gnd *
  page239_i64
#CELL
  pure_quanta q_cap *
  page239_i68
#ISCELL
  logical_power universal_gnd *
  page239_i69
#CELL
  pure_quanta q_cap *
  page239_i70
#ISCELL
  logical_power universal_gnd *
  page239_i71
#CELL
  pure_quanta q_res *
  page239_i72
#ISCELL
  mstr_misc dns *
  *
#ISCELL
  pure_quanta quanta_title_block_c *
  *
#ISCELL
  standard offpage *
  page240_i1
#ISCELL
  standard offpage *
  page240_i10
#CELL
  pure_quanta q_res_4p_12 *
  page240_i11
#ISCELL
  standard offpage *
  page240_i12
#ISCELL
  logical_power universal_power *
  page240_i13
#ISCELL
  logical_power universal_gnd *
  page240_i14
#CELL
  pure_quanta q_cap *
  page240_i15
#CELL
  pure_quanta q_res *
  page240_i16
#ISCELL
  logical_power universal_gnd *
  page240_i17
#CELL
  pure_quanta q_res *
  page240_i18
#CELL
  pure_quanta q_res *
  page240_i19
#ISCELL
  logical_power universal_power *
  page240_i2
#ISCELL
  standard offpage *
  page240_i20
#ISCELL
  standard offpage *
  page240_i21
#CELL
  pure_quanta ina183a1idbvr *
  page240_i22
#ISCELL
  logical_power universal_gnd *
  page240_i23
#ISCELL
  standard offpage *
  page240_i24
#ISCELL
  standard offpage *
  page240_i25
#ISCELL
  standard offpage *
  page240_i26
#ISCELL
  logical_power universal_gnd *
  page240_i28
#CELL
  pure_quanta ina183a1idbvr *
  page240_i29
#CELL
  pure_quanta q_res_4p_12 *
  page240_i3
#ISCELL
  logical_power universal_gnd *
  page240_i30
#ISCELL
  standard offpage *
  page240_i31
#ISCELL
  logical_power universal_gnd *
  page240_i32
#CELL
  pure_quanta q_cap *
  page240_i33
#ISCELL
  logical_power universal_power *
  page240_i34
#CELL
  pure_quanta q_res *
  page240_i35
#ISCELL
  logical_power universal_power *
  page240_i36
#CELL
  pure_quanta q_res *
  page240_i37
#CELL
  pure_quanta q_res *
  page240_i38
#CELL
  pure_quanta ina230airgtr *
  page240_i39
#ISCELL
  logical_power universal_power *
  page240_i4
#ISCELL
  standard offpage *
  page240_i5
#ISCELL
  standard offpage *
  page240_i6
#ISCELL
  logical_power universal_power *
  page240_i7
#ISCELL
  standard offpage *
  page240_i8
#ISCELL
  standard offpage *
  page240_i9
#ISCELL
  pure_quanta quanta_title_block_c *
  *
#ISCELL
  standard offpage *
  page242_i1
#ISCELL
  logical_power universal_gnd *
  page242_i10
#CELL
  pure_quanta q_led *
  page242_i11
#CELL
  pure_quanta q_res *
  page242_i12
#CELL
  pure_quanta q_led *
  page242_i13
#CELL
  pure_quanta q_res *
  page242_i14
#CELL
  pure_quanta q_res *
  page242_i15
#ISCELL
  standard offpage *
  page242_i16
#CELL
  pure_quanta mosfet_nch_dual *
  page242_i17
#CELL
  pure_quanta q_led *
  page242_i18
#CELL
  pure_quanta q_res *
  page242_i19
#ISCELL
  standard offpage *
  page242_i2
#ISCELL
  logical_power universal_power *
  page242_i20
#ISCELL
  logical_power universal_power *
  page242_i23
#ISCELL
  standard offpage *
  page242_i24
#ISCELL
  logical_power universal_power *
  page242_i25
#CELL
  pure_quanta mosfet_nch_dual *
  page242_i26
#ISCELL
  logical_power universal_gnd *
  page242_i28
#CELL
  pure_quanta mosfet_nch_dual *
  page242_i3
#ISCELL
  logical_power universal_gnd *
  page242_i30
#CELL
  pure_quanta q_led *
  page242_i31
#ISCELL
  logical_power universal_power *
  page242_i32
#ISCELL
  standard offpage *
  page242_i33
#CELL
  pure_quanta mosfet_nch_dual *
  page242_i34
#CELL
  pure_quanta q_led *
  page242_i35
#CELL
  pure_quanta q_res *
  page242_i37
#ISCELL
  logical_power universal_power *
  page242_i39
#ISCELL
  logical_power universal_gnd *
  page242_i4
#ISCELL
  logical_power universal_power *
  page242_i40
#CELL
  pure_quanta q_res *
  page242_i41
#CELL
  pure_quanta q_led *
  page242_i42
#ISCELL
  logical_power universal_gnd *
  page242_i49
#ISCELL
  logical_power universal_gnd *
  page242_i5
#ISCELL
  logical_power universal_power *
  page242_i51
#CELL
  pure_quanta q_led *
  page242_i52
#CELL
  pure_quanta q_led *
  page242_i53
#ISCELL
  logical_power universal_power *
  page242_i54
#ISCELL
  logical_power universal_gnd *
  page242_i56
#ISCELL
  logical_power universal_gnd *
  page242_i57
#ISCELL
  logical_power universal_power *
  page242_i59
#CELL
  pure_quanta mosfet_nch_dual *
  page242_i6
#CELL
  pure_quanta q_led *
  page242_i60
#CELL
  pure_quanta q_res *
  page242_i61
#CELL
  pure_quanta q_res *
  page242_i62
#CELL
  pure_quanta q_res *
  page242_i64
#ISCELL
  standard offpage *
  page242_i7
#CELL
  pure_quanta mosfet_nch_dual *
  page242_i8
#ISCELL
  logical_power universal_gnd *
  page242_i9
#ISCELL
  pure_quanta quanta_title_block_c *
  *
#ISCELL
  standard offpage *
  page305_i1
#CELL
  pure_quanta q_led *
  page305_i10
#ISCELL
  logical_power universal_gnd *
  page305_i11
#ISCELL
  logical_power universal_gnd *
  page305_i12
#CELL
  pure_quanta q_led *
  page305_i13
#ISCELL
  logical_power universal_power *
  page305_i17
#ISCELL
  standard offpage *
  page305_i18
#ISCELL
  logical_power universal_power *
  page305_i19
#CELL
  pure_quanta mosfet_nch_dual *
  page305_i2
#ISCELL
  logical_power universal_gnd *
  page305_i20
#CELL
  pure_quanta q_led *
  page305_i21
#CELL
  pure_quanta q_led *
  page305_i22
#ISCELL
  logical_power universal_power *
  page305_i25
#ISCELL
  standard offpage *
  page305_i26
#ISCELL
  logical_power universal_power *
  page305_i27
#ISCELL
  standard offpage *
  page305_i28
#ISCELL
  standard offpage *
  page305_i3
#CELL
  pure_quanta mosfet_nch_dual *
  page305_i32
#ISCELL
  logical_power universal_gnd *
  page305_i33
#ISCELL
  logical_power universal_gnd *
  page305_i34
#CELL
  pure_quanta q_led *
  page305_i35
#ISCELL
  logical_power universal_power *
  page305_i39
#CELL
  pure_quanta mosfet_nch_dual *
  page305_i4
#CELL
  pure_quanta mosfet_nch_dual *
  page305_i40
#CELL
  pure_quanta mosfet_nch_dual *
  page305_i41
#ISCELL
  logical_power universal_gnd *
  page305_i42
#CELL
  pure_quanta q_led *
  page305_i43
#CELL
  pure_quanta q_led *
  page305_i44
#ISCELL
  logical_power universal_power *
  page305_i46
#ISCELL
  logical_power universal_power *
  page305_i48
#CELL
  pure_quanta q_res *
  page305_i49
#ISCELL
  standard offpage *
  page305_i5
#CELL
  pure_quanta q_res *
  page305_i50
#CELL
  pure_quanta q_res *
  page305_i51
#CELL
  pure_quanta q_res *
  page305_i52
#CELL
  pure_quanta q_res *
  page305_i53
#CELL
  pure_quanta q_res *
  page305_i54
#CELL
  pure_quanta q_res *
  page305_i55
#ISCELL
  standard offpage *
  page305_i6
#CELL
  pure_quanta mosfet_nch_dual *
  page305_i7
#CELL
  pure_quanta mosfet_nch_dual *
  page305_i8
#ISCELL
  logical_power universal_gnd *
  page305_i9
#ISCELL
  pure_quanta quanta_title_block_c *
  *
#ISCELL
  standard offpage *
  page306_i1
#ISCELL
  logical_power universal_gnd *
  page306_i10
#CELL
  pure_quanta q_led *
  page306_i11
#CELL
  pure_quanta q_res *
  page306_i12
#CELL
  pure_quanta q_led *
  page306_i13
#CELL
  pure_quanta q_led *
  page306_i14
#CELL
  pure_quanta q_res *
  page306_i15
#CELL
  pure_quanta q_res *
  page306_i16
#ISCELL
  standard offpage *
  page306_i17
#CELL
  pure_quanta mosfet_nch_dual *
  page306_i18
#CELL
  pure_quanta q_led *
  page306_i19
#ISCELL
  standard offpage *
  page306_i2
#CELL
  pure_quanta q_res *
  page306_i20
#ISCELL
  logical_power universal_power *
  page306_i21
#ISCELL
  standard offpage *
  page306_i22
#ISCELL
  logical_power universal_power *
  page306_i24
#ISCELL
  standard offpage *
  page306_i25
#ISCELL
  logical_power universal_power *
  page306_i26
#CELL
  pure_quanta mosfet_nch_dual *
  page306_i27
#ISCELL
  logical_power universal_gnd *
  page306_i28
#ISCELL
  logical_power universal_gnd *
  page306_i29
#CELL
  pure_quanta mosfet_nch_dual *
  page306_i3
#CELL
  pure_quanta q_led *
  page306_i30
#ISCELL
  logical_power universal_gnd *
  page306_i31
#CELL
  pure_quanta q_led *
  page306_i32
#ISCELL
  logical_power universal_power *
  page306_i33
#ISCELL
  standard offpage *
  page306_i34
#CELL
  pure_quanta mosfet_nch_dual *
  page306_i35
#CELL
  pure_quanta q_led *
  page306_i36
#CELL
  pure_quanta q_res *
  page306_i37
#CELL
  pure_quanta q_res *
  page306_i38
#ISCELL
  logical_power universal_power *
  page306_i39
#ISCELL
  logical_power universal_gnd *
  page306_i4
#ISCELL
  logical_power universal_power *
  page306_i40
#CELL
  pure_quanta q_res *
  page306_i41
#ISCELL
  logical_power universal_power *
  page306_i42
#CELL
  pure_quanta mosfet_nch_dual *
  page306_i43
#ISCELL
  logical_power universal_gnd *
  page306_i5
#CELL
  pure_quanta mosfet_nch_dual *
  page306_i6
#ISCELL
  standard offpage *
  page306_i7
#CELL
  pure_quanta mosfet_nch_dual *
  page306_i8
#ISCELL
  logical_power universal_gnd *
  page306_i9
#ISCELL
  pure_quanta quanta_title_block_c *
  *
#ISCELL
  logical_power universal_gnd *
  page241_i10
#CELL
  pure_quanta q_led *
  page241_i11
#ISCELL
  logical_power universal_power *
  page241_i15
#CELL
  pure_quanta mosfet_nch_dual *
  page241_i16
#CELL
  pure_quanta mosfet_nch_dual *
  page241_i17
#ISCELL
  logical_power universal_gnd *
  page241_i18
#CELL
  pure_quanta q_led *
  page241_i19
#CELL
  pure_quanta q_led *
  page241_i20
#ISCELL
  logical_power universal_power *
  page241_i24
#ISCELL
  logical_power universal_power *
  page241_i25
#ISCELL
  standard offpage *
  page241_i26
#ISCELL
  standard offpage *
  page241_i3
#ISCELL
  logical_power universal_gnd *
  page241_i31
#CELL
  pure_quanta q_led *
  page241_i33
#ISCELL
  logical_power universal_power *
  page241_i37
#CELL
  pure_quanta q_res *
  page241_i38
#CELL
  pure_quanta q_res *
  page241_i39
#ISCELL
  standard offpage *
  page241_i4
#CELL
  pure_quanta q_res *
  page241_i40
#CELL
  pure_quanta q_res *
  page241_i41
#CELL
  pure_quanta mosfet_nch_dual *
  page241_i42
#ISCELL
  logical_power universal_power *
  page241_i47
#CELL
  pure_quanta q_led *
  page241_i49
#ISCELL
  standard offpage *
  page241_i5
#ISCELL
  logical_power universal_gnd *
  page241_i50
#ISCELL
  logical_power universal_power *
  page241_i54
#CELL
  pure_quanta q_led *
  page241_i58
#ISCELL
  logical_power universal_gnd *
  page241_i59
#CELL
  pure_quanta q_res *
  page241_i61
#CELL
  pure_quanta q_res *
  page241_i62
#CELL
  pure_quanta q_res *
  page241_i63
#CELL
  pure_quanta q_res *
  page241_i64
#CELL
  pure_quanta q_res *
  page241_i65
#CELL
  pure_quanta q_res *
  page241_i66
#CELL
  pure_quanta q_led *
  page241_i67
#CELL
  pure_quanta q_res *
  page241_i68
#CELL
  pure_quanta mosfet_nch_dual *
  page241_i69
#ISCELL
  logical_power universal_power *
  page241_i71
#CELL
  pure_quanta mosfet_nch_dual *
  page241_i72
#ISCELL
  logical_power universal_gnd *
  page241_i73
#CELL
  pure_quanta q_res *
  page241_i74
#ISCELL
  logical_power universal_power *
  page241_i75
#ISCELL
  logical_power universal_gnd *
  page241_i76
#ISCELL
  standard offpage *
  page241_i77
#CELL
  pure_quanta mosfet_nch_dual *
  page241_i8
#ISCELL
  logical_power universal_gnd *
  page241_i9
#ISCELL
  pure_quanta quanta_title_block_c *
  *
#ISCELL
  standard offpage *
  page304_i1
#ISCELL
  logical_power universal_gnd *
  page304_i10
#CELL
  pure_quanta q_led *
  page304_i12
#ISCELL
  logical_power universal_power *
  page304_i14
#ISCELL
  logical_power universal_power *
  page304_i16
#ISCELL
  standard offpage *
  page304_i17
#ISCELL
  logical_power universal_gnd *
  page304_i19
#ISCELL
  standard offpage *
  page304_i2
#CELL
  pure_quanta q_led *
  page304_i20
#CELL
  pure_quanta q_led *
  page304_i21
#ISCELL
  logical_power universal_power *
  page304_i24
#ISCELL
  standard offpage *
  page304_i25
#ISCELL
  logical_power universal_power *
  page304_i26
#ISCELL
  logical_power universal_gnd *
  page304_i29
#ISCELL
  standard offpage *
  page304_i3
#CELL
  pure_quanta q_led *
  page304_i31
#CELL
  pure_quanta q_led *
  page304_i32
#ISCELL
  logical_power universal_power *
  page304_i35
#ISCELL
  logical_power universal_power *
  page304_i36
#CELL
  pure_quanta q_res *
  page304_i49
#ISCELL
  standard offpage *
  page304_i5
#CELL
  pure_quanta q_res *
  page304_i50
#CELL
  pure_quanta q_res *
  page304_i51
#CELL
  pure_quanta q_res *
  page304_i52
#CELL
  pure_quanta q_res *
  page304_i53
#CELL
  pure_quanta q_res *
  page304_i54
#ISCELL
  logical_power universal_power *
  page304_i55
#ISCELL
  logical_power universal_power *
  page304_i56
#CELL
  pure_quanta q_res *
  page304_i57
#CELL
  pure_quanta q_led *
  page304_i58
#ISCELL
  logical_power universal_gnd *
  page304_i59
#ISCELL
  logical_power universal_gnd *
  page304_i6
#ISCELL
  standard offpage *
  page304_i61
#CELL
  pure_quanta q_res *
  page304_i62
#CELL
  pure_quanta q_led *
  page304_i63
#ISCELL
  logical_power universal_gnd *
  page304_i64
#ISCELL
  standard offpage *
  page304_i66
#ISCELL
  logical_power universal_gnd *
  page304_i67
#CELL
  pure_quanta mosfet_nch_dual *
  page304_i68
#CELL
  pure_quanta mosfet_nch_dual *
  page304_i69
#CELL
  pure_quanta mosfet_nch_dual *
  page304_i70
#CELL
  pure_quanta mosfet_nch_dual *
  page304_i71
#CELL
  pure_quanta mosfet_nch_dual *
  page304_i72
#CELL
  pure_quanta mosfet_nch_dual *
  page304_i74
#CELL
  pure_quanta mosfet_nch_dual *
  page304_i75
#CELL
  pure_quanta mosfet_nch_dual *
  page304_i76
#ISCELL
  logical_power universal_gnd *
  page304_i8
#CELL
  pure_quanta q_led *
  page304_i9
#ISCELL
  logical_power design_note *
  *
#ISCELL
  mstr_misc dns *
  *
#ISCELL
  pure_quanta quanta_title_block_c *
  *
#ISCELL
  logical_power vcc15 *
  page243_i1
#ISCELL
  logical_power universal_gnd *
  page243_i11
#ISCELL
  logical_power universal_power *
  page243_i12
#CELL
  pure_quanta q_res *
  page243_i13
#ISCELL
  standard offpage *
  page243_i14
#CELL
  pure_quanta mosfet_n *
  page243_i15
#CELL
  pure_quanta q_res *
  page243_i16
#ISCELL
  logical_power universal_power *
  page243_i17
#ISCELL
  logical_power universal_gnd *
  page243_i18
#CELL
  pure_quanta q_res *
  page243_i19
#CELL
  pure_quanta q_res *
  page243_i2
#ISCELL
  standard offpage *
  page243_i20
#ISCELL
  logical_power universal_power *
  page243_i3
#CELL
  pure_quanta q_cap *
  page243_i4
#CELL
  pure_quanta q_cap *
  page243_i5
#ISCELL
  logical_power universal_power *
  page243_i6
#CELL
  pure_quanta q_res *
  page243_i7
#CELL
  pure_quanta q_res *
  page243_i8
#ISCELL
  logical_power universal_gnd *
  page243_i9
#ISCELL
  pure_quanta quanta_title_block_c *
  *
#ISCELL
  logical_power gnd *
  page244_i1
#CELL
  pure_quanta q_res *
  page244_i10
#CELL
  pure_quanta q_cap *
  page244_i11
#CELL
  pure_quanta q_cap *
  page244_i12
#ISCELL
  standard offpage *
  page244_i13
#CELL
  pure_quanta q_cap *
  page244_i14
#ISCELL
  logical_power gnd *
  page244_i15
#CELL
  pure_quanta q_res *
  page244_i16
#ISCELL
  logical_power gnd *
  page244_i17
#ISCELL
  logical_power gnd *
  page244_i18
#ISCELL
  logical_power gnd *
  page244_i19
#CELL
  pure_quanta q_cap *
  page244_i2
#CELL
  pure_quanta rs53318lr *
  page244_i20
#CELL
  pure_quanta q_cap *
  page244_i21
#CELL
  pure_quanta q_cap *
  page244_i22
#ISCELL
  logical_power gnd *
  page244_i23
#ISCELL
  logical_power gnd *
  page244_i24
#CELL
  pure_quanta q_res *
  page244_i25
#CELL
  pure_quanta q_cap *
  page244_i26
#CELL
  pure_quanta q_res *
  page244_i27
#CELL
  pure_quanta q_res *
  page244_i28
#ISCELL
  logical_power p1v0_aux *
  page244_i3
#CELL
  pure_quanta q_inductor *
  page244_i30
#ISCELL
  standard offpage *
  page244_i31
#CELL
  pure_quanta q_capp *
  page244_i32
#CELL
  pure_quanta q_cap *
  page244_i33
#CELL
  pure_quanta q_cap *
  page244_i34
#ISCELL
  logical_power gnd *
  page244_i35
#CELL
  pure_quanta q_cap *
  page244_i36
#ISCELL
  logical_power universal_power *
  page244_i37
#ISCELL
  logical_power p1v0 *
  page244_i38
#CELL
  pure_quanta q_res *
  page244_i39
#ISCELL
  logical_power gnd *
  page244_i4
#CELL
  pure_quanta q_inductor *
  page244_i5
#ISCELL
  logical_power gnd *
  page244_i6
#CELL
  pure_quanta q_cap *
  page244_i7
#CELL
  pure_quanta q_cap *
  page244_i8
#ISCELL
  logical_power universal_power *
  page244_i9
#ISCELL
  mstr_misc dns *
  *
#ISCELL
  pure_quanta quanta_title_block_c *
  *
#CELL
  pure_quanta q_cap *
  page245_i100
#CELL
  pure_quanta q_cap *
  page245_i101
#ISCELL
  logical_power gnd *
  page245_i102
#CELL
  pure_quanta q_capp *
  page245_i103
#CELL
  pure_quanta q_capp *
  page245_i104
#CELL
  pure_quanta q_cap *
  page245_i105
#CELL
  pure_quanta q_cap *
  page245_i106
#CELL
  pure_quanta q_cap *
  page245_i107
#CELL
  pure_quanta q_cap *
  page245_i108
#CELL
  pure_quanta q_cap *
  page245_i109
#CELL
  pure_quanta q_cap *
  page245_i110
#CELL
  pure_quanta q_cap *
  page245_i111
#CELL
  pure_quanta q_cap *
  page245_i112
#CELL
  pure_quanta q_cap *
  page245_i113
#CELL
  pure_quanta q_cap *
  page245_i114
#CELL
  pure_quanta q_cap *
  page245_i115
#ISCELL
  logical_power universal_power *
  page245_i116
#ISCELL
  logical_power gnd *
  page245_i117
#CELL
  pure_quanta q_cap *
  page245_i118
#ISCELL
  logical_power gnd *
  page245_i119
#ISCELL
  logical_power gnd *
  page245_i120
#CELL
  pure_quanta q_res *
  page245_i121
#CELL
  pure_quanta q_cap *
  page245_i122
#CELL
  pure_quanta q_res *
  page245_i123
#ISCELL
  logical_power gnd *
  page245_i124
#CELL
  pure_quanta q_res *
  page245_i125
#ISCELL
  logical_power universal_power *
  page245_i126
#CELL
  pure_quanta q_cap *
  page245_i127
#CELL
  pure_quanta q_res *
  page245_i128
#CELL
  pure_quanta q_inductor *
  page245_i129
#ISCELL
  standard offpage *
  page245_i130
#CELL
  pure_quanta q_capp *
  page245_i131
#CELL
  pure_quanta q_capp *
  page245_i132
#CELL
  pure_quanta q_cap *
  page245_i133
#CELL
  pure_quanta q_cap *
  page245_i134
#ISCELL
  logical_power gnd *
  page245_i135
#CELL
  pure_quanta q_cap *
  page245_i136
#CELL
  pure_quanta q_cap *
  page245_i137
#ISCELL
  logical_power universal_power *
  page245_i138
#CELL
  pure_quanta q_res *
  page245_i139
#ISCELL
  logical_power universal_power *
  page245_i140
#CELL
  pure_quanta q_diode *
  page245_i71
#CELL
  pure_quanta q_res *
  page245_i72
#CELL
  pure_quanta q_cap *
  page245_i73
#ISCELL
  logical_power gnd *
  page245_i74
#ISCELL
  logical_power gnd *
  page245_i75
#CELL
  pure_quanta q_res *
  page245_i76
#ISCELL
  logical_power gnd *
  page245_i77
#CELL
  pure_quanta q_res *
  page245_i78
#ISCELL
  standard offpage *
  page245_i79
#ISCELL
  logical_power p1v0_aux *
  page245_i80
#ISCELL
  logical_power gnd *
  page245_i83
#CELL
  pure_quanta q_res *
  page245_i84
#CELL
  pure_quanta q_cap *
  page245_i86
#ISCELL
  logical_power gnd *
  page245_i87
#ISCELL
  logical_power gnd *
  page245_i88
#CELL
  pure_quanta q_res *
  page245_i89
#ISCELL
  logical_power gnd *
  page245_i90
#CELL
  pure_quanta q_res *
  page245_i91
#ISCELL
  logical_power gnd *
  page245_i92
#CELL
  pure_quanta q_cap *
  page245_i93
#CELL
  pure_quanta q_res *
  page245_i94
#CELL
  pure_quanta ir3889mtrpbf *
  page245_i95
#ISCELL
  logical_power gnd *
  page245_i96
#CELL
  pure_quanta q_cap *
  page245_i97
#CELL
  pure_quanta q_inductor *
  page245_i98
#ISCELL
  logical_power universal_power *
  page245_i99
#ISCELL
  mstr_misc dns *
  *
#ISCELL
  pure_quanta quanta_title_block_c *
  *
#ISCELL
  logical_power universal_gnd *
  page246_i1
#CELL
  pure_quanta q_res *
  page246_i10
#ISCELL
  logical_power universal_gnd *
  page246_i100
#ISCELL
  logical_power universal_power *
  page246_i101
#CELL
  pure_quanta q_res *
  page246_i102
#ISCELL
  logical_power universal_gnd *
  page246_i103
#CELL
  pure_quanta q_res *
  page246_i104
#CELL
  pure_quanta apx80929sag7 *
  page246_i105
#ISCELL
  logical_power universal_gnd *
  page246_i106
#CELL
  pure_quanta q_cap *
  page246_i107
#ISCELL
  logical_power universal_power *
  page246_i108
#CELL
  pure_quanta q_res *
  page246_i109
#CELL
  pure_quanta q_cap *
  page246_i11
#ISCELL
  logical_power universal_gnd *
  page246_i110
#ISCELL
  logical_power universal_power *
  page246_i111
#CELL
  pure_quanta q_res *
  page246_i112
#ISCELL
  logical_power universal_gnd *
  page246_i113
#ISCELL
  logical_power universal_power *
  page246_i114
#ISCELL
  logical_power universal_gnd *
  page246_i12
#ISCELL
  logical_power universal_gnd *
  page246_i13
#CELL
  pure_quanta q_res *
  page246_i14
#ISCELL
  logical_power universal_gnd *
  page246_i15
#CELL
  pure_quanta q_res *
  page246_i17
#ISCELL
  logical_power universal_power *
  page246_i18
#CELL
  pure_quanta q_cap *
  page246_i2
#ISCELL
  logical_power universal_gnd *
  page246_i20
#CELL
  pure_quanta q_res *
  page246_i22
#ISCELL
  logical_power universal_power *
  page246_i23
#CELL
  pure_quanta q_cap *
  page246_i24
#CELL
  pure_quanta q_cap *
  page246_i25
#ISCELL
  logical_power p1v0_aux *
  page246_i26
#CELL
  pure_quanta q_res *
  page246_i27
#ISCELL
  logical_power universal_gnd *
  page246_i28
#ISCELL
  logical_power universal_power *
  page246_i3
#CELL
  pure_quanta mosfet_nch_1d3s *
  page246_i30
#ISCELL
  logical_power universal_power *
  page246_i31
#CELL
  pure_quanta bat547f *
  page246_i32
#ISCELL
  logical_power universal_power *
  page246_i34
#CELL
  pure_quanta rt9818c44gv *
  page246_i4
#ISCELL
  logical_power universal_power *
  page246_i42
#ISCELL
  logical_power universal_gnd *
  page246_i43
#CELL
  pure_quanta q_cap *
  page246_i44
#CELL
  pure_quanta q_cap *
  page246_i45
#ISCELL
  logical_power universal_gnd *
  page246_i47
#CELL
  pure_quanta q_cap *
  page246_i48
#CELL
  pure_quanta q_cap *
  page246_i49
#ISCELL
  logical_power universal_gnd *
  page246_i5
#CELL
  pure_quanta q_cap *
  page246_i50
#CELL
  pure_quanta mosfet_nch_1d3s *
  page246_i51
#ISCELL
  logical_power p1v0_aux *
  page246_i53
#CELL
  pure_quanta q_cap *
  page246_i58
#ISCELL
  logical_power universal_power *
  page246_i59
#CELL
  pure_quanta q_res *
  page246_i6
#ISCELL
  logical_power universal_gnd *
  page246_i60
#CELL
  pure_quanta q_cap *
  page246_i61
#ISCELL
  standard offpage *
  page246_i63
#ISCELL
  standard offpage *
  page246_i64
#ISCELL
  logical_power universal_gnd *
  page246_i65
#CELL
  pure_quanta mosfet_nch_gds_esd_protected *
  page246_i67
#CELL
  pure_quanta q_cap *
  page246_i68
#CELL
  pure_quanta mosfet_nch_dual *
  page246_i69
#ISCELL
  standard offpage *
  page246_i7
#CELL
  pure_quanta mosfet_nch_dual *
  page246_i76
#CELL
  pure_quanta q_res *
  page246_i77
#CELL
  pure_quanta q_res *
  page246_i78
#CELL
  pure_quanta q_res *
  page246_i79
#ISCELL
  standard offpage *
  page246_i8
#CELL
  pure_quanta q_res *
  page246_i80
#ISCELL
  logical_power universal_gnd *
  page246_i87
#CELL
  pure_quanta q_res *
  page246_i89
#CELL
  pure_quanta q_res *
  page246_i9
#CELL
  pure_quanta q_res *
  page246_i91
#ISCELL
  standard offpage *
  page246_i92
#ISCELL
  logical_power universal_power *
  page246_i93
#CELL
  pure_quanta q_cap *
  page246_i94
#ISCELL
  logical_power universal_gnd *
  page246_i95
#CELL
  pure_quanta q_res *
  page246_i96
#CELL
  pure_quanta mosfet_nch_dual *
  page246_i98
#CELL
  pure_quanta mosfet_nch_dual *
  page246_i99
#ISCELL
  pure_quanta quanta_title_block_c *
  *
#ISCELL
  mstr_misc dns *
  *
#ISCELL
  pure_quanta quanta_title_block_c *
  *
#ISCELL
  logical_power universal_gnd *
  page248_i1
#CELL
  pure_quanta q_res *
  page248_i10
#CELL
  pure_quanta rs53319lr *
  page248_i11
#ISCELL
  logical_power universal_gnd *
  page248_i12
#ISCELL
  logical_power universal_gnd *
  page248_i13
#CELL
  pure_quanta q_cap *
  page248_i14
#ISCELL
  logical_power universal_gnd *
  page248_i15
#CELL
  pure_quanta q_cap *
  page248_i16
#ISCELL
  logical_power gnd *
  page248_i17
#CELL
  pure_quanta q_cap *
  page248_i18
#CELL
  pure_quanta q_inductor *
  page248_i19
#CELL
  pure_quanta q_cap *
  page248_i2
#ISCELL
  logical_power vccaux15 *
  page248_i20
#ISCELL
  standard offpage *
  page248_i21
#ISCELL
  logical_power universal_gnd *
  page248_i22
#CELL
  pure_quanta q_capp *
  page248_i23
#ISCELL
  logical_power vccaux15 *
  page248_i24
#CELL
  pure_quanta q_cap *
  page248_i25
#CELL
  pure_quanta q_res *
  page248_i26
#CELL
  pure_quanta q_res *
  page248_i27
#CELL
  pure_quanta q_cap *
  page248_i28
#CELL
  pure_quanta q_cap *
  page248_i29
#CELL
  pure_quanta q_res *
  page248_i3
#CELL
  pure_quanta q_cap *
  page248_i30
#CELL
  pure_quanta q_cap *
  page248_i31
#CELL
  pure_quanta q_res *
  page248_i32
#ISCELL
  logical_power universal_power *
  page248_i33
#CELL
  pure_quanta q_res *
  page248_i34
#CELL
  pure_quanta q_cap *
  page248_i35
#CELL
  pure_quanta q_res *
  page248_i36
#CELL
  pure_quanta q_cap *
  page248_i37
#CELL
  pure_quanta q_cap *
  page248_i38
#ISCELL
  logical_power universal_gnd *
  page248_i39
#ISCELL
  logical_power universal_power *
  page248_i4
#CELL
  pure_quanta q_capp *
  page248_i40
#CELL
  pure_quanta q_capp *
  page248_i41
#CELL
  pure_quanta q_short *
  page248_i42
#CELL
  pure_quanta q_short *
  page248_i43
#CELL
  pure_quanta q_cap *
  page248_i44
#CELL
  pure_quanta q_cap *
  page248_i45
#ISCELL
  logical_power universal_gnd *
  page248_i46
#CELL
  pure_quanta q_capp *
  page248_i47
#CELL
  pure_quanta q_capp *
  page248_i48
#ISCELL
  logical_power vccaux15 *
  page248_i49
#ISCELL
  logical_power universal_gnd *
  page248_i5
#ISCELL
  logical_power universal_gnd *
  page248_i50
#CELL
  pure_quanta q_res *
  page248_i51
#CELL
  pure_quanta q_res *
  page248_i52
#CELL
  pure_quanta q_inductor *
  page248_i53
#ISCELL
  standard offpage *
  page248_i54
#ISCELL
  standard offpage *
  page248_i55
#ISCELL
  logical_power universal_power *
  page248_i56
#CELL
  pure_quanta q_res *
  page248_i6
#ISCELL
  logical_power universal_gnd *
  page248_i7
#CELL
  pure_quanta q_cap *
  page248_i8
#CELL
  pure_quanta q_res *
  page248_i9
#ISCELL
  logical_power cad_note *
  *
#ISCELL
  mstr_misc dns *
  *
#ISCELL
  pure_quanta quanta_title_block_c *
  *
#ISCELL
  logical_power universal_power *
  page249_i1
#ISCELL
  logical_power universal_gnd *
  page249_i10
#CELL
  pure_quanta q_res *
  page249_i11
#ISCELL
  standard offpage *
  page249_i12
#ISCELL
  logical_power gnd *
  page249_i13
#CELL
  pure_quanta q_cap *
  page249_i14
#ISCELL
  logical_power vccaux15 *
  page249_i15
#CELL
  pure_quanta q_inductor *
  page249_i16
#CELL
  pure_quanta q_res *
  page249_i17
#ISCELL
  logical_power universal_gnd *
  page249_i18
#CELL
  pure_quanta q_cap *
  page249_i19
#CELL
  pure_quanta q_res *
  page249_i2
#CELL
  pure_quanta q_cap *
  page249_i20
#CELL
  pure_quanta q_cap *
  page249_i21
#ISCELL
  logical_power universal_power *
  page249_i22
#ISCELL
  logical_power universal_power *
  page249_i23
#CELL
  pure_quanta q_res *
  page249_i24
#ISCELL
  logical_power universal_gnd *
  page249_i25
#CELL
  pure_quanta nb682gdz *
  page249_i26
#ISCELL
  logical_power universal_gnd *
  page249_i27
#CELL
  pure_quanta q_cap *
  page249_i28
#CELL
  pure_quanta q_cap *
  page249_i29
#ISCELL
  logical_power universal_gnd *
  page249_i3
#CELL
  pure_quanta q_cap *
  page249_i30
#CELL
  pure_quanta q_res *
  page249_i31
#ISCELL
  logical_power universal_power *
  page249_i32
#CELL
  pure_quanta q_res *
  page249_i34
#ISCELL
  logical_power universal_gnd *
  page249_i35
#CELL
  pure_quanta q_cap *
  page249_i36
#CELL
  pure_quanta q_cap *
  page249_i37
#CELL
  pure_quanta q_cap *
  page249_i38
#CELL
  pure_quanta q_cap *
  page249_i39
#CELL
  pure_quanta q_cap *
  page249_i4
#ISCELL
  logical_power universal_gnd *
  page249_i40
#CELL
  pure_quanta q_cap *
  page249_i41
#CELL
  pure_quanta q_res *
  page249_i42
#ISCELL
  standard offpage *
  page249_i43
#ISCELL
  logical_power universal_power *
  page249_i44
#CELL
  pure_quanta q_inductor *
  page249_i45
#CELL
  pure_quanta q_res *
  page249_i5
#ISCELL
  logical_power universal_power *
  page249_i6
#ISCELL
  logical_power universal_power *
  page249_i7
#CELL
  pure_quanta q_res *
  page249_i8
#ISCELL
  logical_power universal_gnd *
  page249_i9
#ISCELL
  pure_quanta quanta_title_block_c *
  *
#ISCELL
  pure_quanta quanta_title_block_c *
  *
#ISCELL
  mstr_misc dns *
  *
#ISCELL
  pure_quanta quanta_title_block_c *
  *
#ISCELL
  standard offpage *
  page252_i1
#CELL
  pure_quanta q_res *
  page252_i10
#ISCELL
  standard offpage *
  page252_i100
#ISCELL
  standard offpage *
  page252_i101
#ISCELL
  standard offpage *
  page252_i102
#ISCELL
  standard offpage *
  page252_i103
#ISCELL
  standard offpage *
  page252_i104
#ISCELL
  standard offpage *
  page252_i105
#ISCELL
  standard offpage *
  page252_i106
#ISCELL
  standard offpage *
  page252_i107
#ISCELL
  standard offpage *
  page252_i108
#ISCELL
  standard offpage *
  page252_i109
#CELL
  pure_quanta q_res *
  page252_i11
#ISCELL
  standard offpage *
  page252_i110
#ISCELL
  standard offpage *
  page252_i111
#ISCELL
  standard offpage *
  page252_i112
#ISCELL
  standard offpage *
  page252_i113
#ISCELL
  logical_power universal_gnd *
  page252_i114
#ISCELL
  standard offpage *
  page252_i115
#CELL
  pure_quanta q_cap *
  page252_i116
#ISCELL
  standard offpage *
  page252_i117
#ISCELL
  standard offpage *
  page252_i118
#ISCELL
  standard offpage *
  page252_i119
#ISCELL
  logical_power vcc15 *
  page252_i12
#ISCELL
  logical_power universal_gnd *
  page252_i120
#CELL
  pure_quanta q_res *
  page252_i121
#ISCELL
  standard offpage *
  page252_i122
#CELL
  pure_quanta q_res *
  page252_i123
#CELL
  pure_quanta q_res *
  page252_i124
#CELL
  pure_quanta q_res *
  page252_i125
#ISCELL
  logical_power universal_gnd *
  page252_i126
#CELL
  pure_quanta q_cap *
  page252_i127
#CELL
  pure_quanta q_cap *
  page252_i128
#ISCELL
  logical_power vcc15 *
  page252_i129
#ISCELL
  logical_power vcc15 *
  page252_i13
#ISCELL
  logical_power universal_gnd *
  page252_i130
#ISCELL
  standard offpage *
  page252_i131
#ISCELL
  logical_power universal_gnd *
  page252_i132
#CELL
  pure_quanta q_res *
  page252_i133
#ISCELL
  logical_power vcc15 *
  page252_i134
#CELL
  pure_quanta q_cap *
  page252_i136
#ISCELL
  standard offpage *
  page252_i14
#CELL
  pure_quanta q_res *
  page252_i15
#ISCELL
  logical_power vcc15 *
  page252_i16
#CELL
  pure_quanta q_res *
  page252_i17
#ISCELL
  standard offpage *
  page252_i18
#CELL
  pure_quanta q_res *
  page252_i19
#ISCELL
  standard offpage *
  page252_i2
#CELL
  pure_quanta q_res *
  page252_i20
#ISCELL
  logical_power universal_gnd *
  page252_i21
#ISCELL
  logical_power vcc15 *
  page252_i22
#CELL
  pure_quanta q_res *
  page252_i23
#CELL
  pure_quanta q_short *
  page252_i24
#CELL
  pure_quanta q_res *
  page252_i25
#CELL
  pure_quanta q_res *
  page252_i26
#ISCELL
  logical_power vcc15 *
  page252_i27
#ISCELL
  logical_power universal_gnd *
  page252_i28
#ISCELL
  standard offpage *
  page252_i29
#ISCELL
  standard offpage *
  page252_i3
#ISCELL
  standard offpage *
  page252_i30
#ISCELL
  standard offpage *
  page252_i31
#CELL
  pure_quanta conn3_210hp1030br1 *
  page252_i32
#ISCELL
  standard offpage *
  page252_i33
#ISCELL
  logical_power universal_gnd *
  page252_i34
#ISCELL
  standard offpage *
  page252_i35
#ISCELL
  standard offpage *
  page252_i36
#CELL
  pure_quanta q_short *
  page252_i37
#CELL
  pure_quanta q_res *
  page252_i38
#ISCELL
  logical_power vcc15 *
  page252_i39
#ISCELL
  standard offpage *
  page252_i4
#CELL
  pure_quanta q_res *
  page252_i40
#CELL
  pure_quanta q_res *
  page252_i41
#CELL
  pure_quanta q_res *
  page252_i42
#CELL
  pure_quanta q_res *
  page252_i43
#CELL
  pure_quanta q_res *
  page252_i44
#ISCELL
  standard offpage *
  page252_i45
#ISCELL
  standard offpage *
  page252_i46
#ISCELL
  logical_power vcc15 *
  page252_i47
#CELL
  pure_quanta q_res *
  page252_i48
#CELL
  pure_quanta q_res *
  page252_i49
#CELL
  pure_quanta q_res *
  page252_i5
#CELL
  pure_quanta q_res *
  page252_i50
#CELL
  pure_quanta q_res *
  page252_i51
#ISCELL
  logical_power universal_gnd *
  page252_i52
#CELL
  pure_quanta q_cap *
  page252_i53
#CELL
  pure_quanta q_res *
  page252_i54
#CELL
  pure_quanta q_res *
  page252_i55
#CELL
  pure_quanta q_res *
  page252_i56
#CELL
  pure_quanta q_cap *
  page252_i57
#CELL
  pure_quanta q_cap *
  page252_i58
#ISCELL
  logical_power universal_gnd *
  page252_i59
#ISCELL
  standard offpage *
  page252_i6
#CELL
  pure_quanta q_res *
  page252_i60
#CELL
  pure_quanta q_cap *
  page252_i61
#ISCELL
  logical_power universal_gnd *
  page252_i62
#CELL
  pure_quanta raa229126gnpha0 *
  page252_i63
#ISCELL
  logical_power universal_gnd *
  page252_i64
#ISCELL
  logical_power universal_gnd *
  page252_i65
#CELL
  pure_quanta q_res *
  page252_i66
#CELL
  pure_quanta q_cap *
  page252_i67
#CELL
  pure_quanta q_res *
  page252_i68
#ISCELL
  logical_power universal_gnd *
  page252_i69
#ISCELL
  standard offpage *
  page252_i7
#CELL
  pure_quanta q_cap *
  page252_i70
#ISCELL
  logical_power universal_gnd *
  page252_i71
#CELL
  pure_quanta q_res *
  page252_i72
#CELL
  pure_quanta q_res *
  page252_i73
#CELL
  pure_quanta q_res *
  page252_i74
#ISCELL
  logical_power universal_gnd *
  page252_i75
#ISCELL
  logical_power universal_gnd *
  page252_i76
#CELL
  pure_quanta q_res *
  page252_i77
#CELL
  pure_quanta q_res *
  page252_i78
#CELL
  pure_quanta q_cap *
  page252_i79
#CELL
  pure_quanta q_res *
  page252_i8
#CELL
  pure_quanta q_res *
  page252_i80
#ISCELL
  logical_power vcc15 *
  page252_i81
#CELL
  pure_quanta q_cap *
  page252_i82
#ISCELL
  logical_power universal_gnd *
  page252_i83
#CELL
  pure_quanta q_cap *
  page252_i84
#ISCELL
  logical_power universal_gnd *
  page252_i85
#CELL
  pure_quanta q_cap *
  page252_i86
#CELL
  pure_quanta q_cap *
  page252_i87
#CELL
  pure_quanta q_cap *
  page252_i88
#CELL
  pure_quanta q_cap *
  page252_i89
#ISCELL
  logical_power universal_gnd *
  page252_i9
#ISCELL
  standard offpage *
  page252_i90
#ISCELL
  standard offpage *
  page252_i91
#ISCELL
  standard offpage *
  page252_i92
#ISCELL
  standard offpage *
  page252_i93
#ISCELL
  standard offpage *
  page252_i94
#ISCELL
  standard offpage *
  page252_i95
#ISCELL
  standard offpage *
  page252_i96
#ISCELL
  standard offpage *
  page252_i97
#ISCELL
  standard offpage *
  page252_i98
#ISCELL
  standard offpage *
  page252_i99
#ISCELL
  mstr_misc dns *
  *
#ISCELL
  pure_quanta quanta_title_block_c *
  *
#ISCELL
  logical_power universal_gnd *
  page253_i1
#ISCELL
  logical_power universal_gnd *
  page253_i10
#CELL
  pure_quanta q_cap *
  page253_i11
#CELL
  pure_quanta q_res *
  page253_i12
#ISCELL
  logical_power vcc15 *
  page253_i13
#ISCELL
  logical_power universal_gnd *
  page253_i14
#CELL
  pure_quanta q_cap *
  page253_i15
#ISCELL
  logical_power universal_gnd *
  page253_i16
#ISCELL
  standard offpage *
  page253_i17
#CELL
  pure_quanta q_res *
  page253_i18
#CELL
  pure_quanta q_cap *
  page253_i19
#CELL
  pure_quanta q_res *
  page253_i2
#CELL
  pure_quanta q_cap *
  page253_i20
#CELL
  pure_quanta q_inductor4p_14 *
  page253_i21
#CELL
  pure_quanta q_cap *
  page253_i22
#CELL
  pure_quanta q_cap *
  page253_i23
#CELL
  pure_quanta q_cap *
  page253_i24
#ISCELL
  logical_power universal_gnd *
  page253_i25
#CELL
  pure_quanta q_res *
  page253_i26
#ISCELL
  logical_power vcc15 *
  page253_i27
#ISCELL
  logical_power universal_gnd *
  page253_i28
#CELL
  pure_quanta q_res *
  page253_i29
#ISCELL
  logical_power universal_gnd *
  page253_i3
#ISCELL
  standard offpage *
  page253_i30
#ISCELL
  standard offpage *
  page253_i31
#ISCELL
  standard offpage *
  page253_i32
#ISCELL
  standard offpage *
  page253_i33
#CELL
  pure_quanta q_cap *
  page253_i34
#ISCELL
  logical_power universal_gnd *
  page253_i35
#CELL
  pure_quanta q_cap *
  page253_i36
#CELL
  pure_quanta q_res *
  page253_i37
#ISCELL
  logical_power universal_gnd *
  page253_i38
#CELL
  pure_quanta q_cap *
  page253_i39
#ISCELL
  standard offpage *
  page253_i4
#CELL
  pure_quanta isl99390frztr5935 *
  page253_i40
#ISCELL
  logical_power vcc15 *
  page253_i41
#CELL
  pure_quanta q_res *
  page253_i42
#ISCELL
  logical_power universal_gnd *
  page253_i43
#CELL
  pure_quanta q_cap *
  page253_i44
#ISCELL
  standard offpage *
  page253_i45
#CELL
  pure_quanta q_inductor4p_14 *
  page253_i46
#CELL
  pure_quanta q_cap *
  page253_i47
#CELL
  pure_quanta q_cap *
  page253_i48
#CELL
  pure_quanta q_cap *
  page253_i49
#ISCELL
  standard offpage *
  page253_i5
#CELL
  pure_quanta q_cap *
  page253_i50
#CELL
  pure_quanta q_res *
  page253_i51
#ISCELL
  standard offpage *
  page253_i52
#ISCELL
  logical_power universal_gnd *
  page253_i53
#CELL
  pure_quanta q_cap *
  page253_i54
#ISCELL
  logical_power vcc15 *
  page253_i55
#CELL
  pure_quanta q_capp *
  page253_i56
#CELL
  pure_quanta q_cap *
  page253_i57
#CELL
  pure_quanta q_cap *
  page253_i58
#CELL
  pure_quanta q_res *
  page253_i59
#CELL
  pure_quanta isl99390frztr5935 *
  page253_i6
#CELL
  pure_quanta q_capp *
  page253_i60
#CELL
  pure_quanta q_capp *
  page253_i61
#CELL
  pure_quanta q_capp *
  page253_i62
#CELL
  pure_quanta q_capp *
  page253_i63
#CELL
  pure_quanta q_capp *
  page253_i64
#ISCELL
  logical_power universal_gnd *
  page253_i65
#CELL
  pure_quanta q_capp *
  page253_i66
#CELL
  pure_quanta q_capp *
  page253_i67
#ISCELL
  logical_power vcc15 *
  page253_i68
#ISCELL
  logical_power universal_gnd *
  page253_i69
#ISCELL
  standard offpage *
  page253_i7
#CELL
  pure_quanta q_capp *
  page253_i70
#ISCELL
  logical_power universal_gnd *
  page253_i71
#ISCELL
  logical_power vcc15 *
  page253_i72
#CELL
  pure_quanta q_res *
  page253_i73
#ISCELL
  logical_power universal_gnd *
  page253_i74
#CELL
  pure_quanta q_cap *
  page253_i75
#ISCELL
  standard offpage *
  page253_i76
#ISCELL
  logical_power gnd *
  page253_i77
#ISCELL
  logical_power vcc15 *
  page253_i78
#ISCELL
  logical_power vcc15 *
  page253_i79
#ISCELL
  standard offpage *
  page253_i8
#CELL
  pure_quanta q_cap *
  page253_i80
#CELL
  pure_quanta q_res *
  page253_i81
#CELL
  pure_quanta q_inductor *
  page253_i82
#CELL
  pure_quanta q_cap *
  page253_i83
#CELL
  pure_quanta q_cap *
  page253_i84
#CELL
  pure_quanta q_cap *
  page253_i85
#CELL
  pure_quanta q_cap *
  page253_i86
#ISCELL
  logical_power universal_gnd *
  page253_i87
#ISCELL
  logical_power vcc15 *
  page253_i88
#ISCELL
  logical_power vcc15 *
  page253_i89
#CELL
  pure_quanta q_cap *
  page253_i9
#ISCELL
  logical_power universal_gnd *
  page253_i90
#CELL
  pure_quanta q_capp *
  page253_i91
#CELL
  pure_quanta q_capp *
  page253_i92
#CELL
  pure_quanta q_capp *
  page253_i93
#CELL
  pure_quanta q_capp *
  page253_i94
#CELL
  pure_quanta q_capp *
  page253_i95
#ISCELL
  logical_power vcc15 *
  page253_i96
#CELL
  pure_quanta q_res *
  page253_i97
#ISCELL
  mstr_misc dns *
  *
#ISCELL
  pure_quanta quanta_title_block_c *
  *
#ISCELL
  logical_power universal_gnd *
  page254_i1
#ISCELL
  logical_power universal_gnd *
  page254_i10
#CELL
  pure_quanta q_cap *
  page254_i11
#CELL
  pure_quanta q_cap *
  page254_i12
#CELL
  pure_quanta isl99390frztr5935 *
  page254_i13
#CELL
  pure_quanta q_res *
  page254_i14
#ISCELL
  logical_power vcc15 *
  page254_i15
#ISCELL
  logical_power universal_gnd *
  page254_i16
#CELL
  pure_quanta q_cap *
  page254_i17
#ISCELL
  standard offpage *
  page254_i18
#ISCELL
  standard offpage *
  page254_i19
#CELL
  pure_quanta q_res *
  page254_i2
#CELL
  pure_quanta isl99390frztr5935 *
  page254_i20
#ISCELL
  logical_power universal_gnd *
  page254_i21
#ISCELL
  standard offpage *
  page254_i22
#ISCELL
  standard offpage *
  page254_i23
#ISCELL
  logical_power universal_gnd *
  page254_i24
#CELL
  pure_quanta q_cap *
  page254_i25
#CELL
  pure_quanta q_cap *
  page254_i26
#CELL
  pure_quanta q_res *
  page254_i27
#ISCELL
  logical_power vcc15 *
  page254_i28
#ISCELL
  logical_power universal_gnd *
  page254_i29
#ISCELL
  logical_power universal_gnd *
  page254_i3
#CELL
  pure_quanta q_cap *
  page254_i30
#ISCELL
  logical_power universal_gnd *
  page254_i31
#ISCELL
  standard offpage *
  page254_i32
#CELL
  pure_quanta q_inductor4p_14 *
  page254_i33
#CELL
  pure_quanta q_cap *
  page254_i34
#CELL
  pure_quanta q_cap *
  page254_i35
#CELL
  pure_quanta q_res *
  page254_i36
#ISCELL
  logical_power universal_gnd *
  page254_i37
#CELL
  pure_quanta q_cap *
  page254_i38
#CELL
  pure_quanta q_cap *
  page254_i39
#CELL
  pure_quanta q_res *
  page254_i4
#CELL
  pure_quanta q_cap *
  page254_i40
#CELL
  pure_quanta q_res *
  page254_i41
#ISCELL
  standard offpage *
  page254_i42
#CELL
  pure_quanta q_cap *
  page254_i43
#ISCELL
  logical_power universal_gnd *
  page254_i44
#ISCELL
  logical_power vcc15 *
  page254_i45
#CELL
  pure_quanta q_res *
  page254_i46
#ISCELL
  standard offpage *
  page254_i47
#CELL
  pure_quanta q_cap *
  page254_i48
#CELL
  pure_quanta q_res *
  page254_i49
#ISCELL
  logical_power universal_gnd *
  page254_i5
#CELL
  pure_quanta q_inductor4p_14 *
  page254_i50
#CELL
  pure_quanta q_cap *
  page254_i51
#CELL
  pure_quanta q_cap *
  page254_i52
#CELL
  pure_quanta q_cap *
  page254_i53
#CELL
  pure_quanta q_cap *
  page254_i54
#ISCELL
  logical_power universal_gnd *
  page254_i55
#CELL
  pure_quanta q_cap *
  page254_i56
#ISCELL
  logical_power vcc15 *
  page254_i57
#ISCELL
  standard offpage *
  page254_i58
#CELL
  pure_quanta q_cap *
  page254_i59
#ISCELL
  standard offpage *
  page254_i6
#CELL
  pure_quanta q_cap *
  page254_i60
#CELL
  pure_quanta q_cap *
  page254_i61
#ISCELL
  logical_power universal_gnd *
  page254_i62
#ISCELL
  logical_power vcc15 *
  page254_i63
#ISCELL
  logical_power universal_gnd *
  page254_i64
#CELL
  pure_quanta q_cap *
  page254_i65
#ISCELL
  logical_power vcc15 *
  page254_i66
#ISCELL
  standard offpage *
  page254_i7
#ISCELL
  standard offpage *
  page254_i8
#ISCELL
  standard offpage *
  page254_i9
#ISCELL
  mstr_misc dns *
  *
#ISCELL
  pure_quanta quanta_title_block_c *
  *
#ISCELL
  logical_power universal_gnd *
  page255_i1
#ISCELL
  logical_power universal_gnd *
  page255_i10
#CELL
  pure_quanta q_cap *
  page255_i11
#CELL
  pure_quanta isl99390frztr5935 *
  page255_i12
#CELL
  pure_quanta q_cap *
  page255_i13
#CELL
  pure_quanta q_res *
  page255_i14
#ISCELL
  logical_power vcc15 *
  page255_i15
#ISCELL
  logical_power universal_gnd *
  page255_i16
#CELL
  pure_quanta q_cap *
  page255_i17
#ISCELL
  standard offpage *
  page255_i18
#ISCELL
  standard offpage *
  page255_i19
#CELL
  pure_quanta q_res *
  page255_i2
#ISCELL
  logical_power universal_gnd *
  page255_i20
#ISCELL
  standard offpage *
  page255_i21
#ISCELL
  standard offpage *
  page255_i22
#ISCELL
  logical_power universal_gnd *
  page255_i23
#CELL
  pure_quanta q_cap *
  page255_i24
#CELL
  pure_quanta q_cap *
  page255_i25
#CELL
  pure_quanta q_res *
  page255_i26
#ISCELL
  logical_power vcc15 *
  page255_i27
#ISCELL
  logical_power universal_gnd *
  page255_i28
#CELL
  pure_quanta q_cap *
  page255_i29
#ISCELL
  logical_power universal_gnd *
  page255_i3
#ISCELL
  logical_power universal_gnd *
  page255_i30
#ISCELL
  standard offpage *
  page255_i31
#CELL
  pure_quanta q_inductor4p_14 *
  page255_i32
#CELL
  pure_quanta q_cap *
  page255_i33
#CELL
  pure_quanta q_cap *
  page255_i34
#CELL
  pure_quanta q_res *
  page255_i35
#ISCELL
  logical_power universal_gnd *
  page255_i36
#CELL
  pure_quanta q_cap *
  page255_i37
#CELL
  pure_quanta q_cap *
  page255_i38
#CELL
  pure_quanta q_cap *
  page255_i39
#CELL
  pure_quanta q_res *
  page255_i4
#CELL
  pure_quanta q_res *
  page255_i40
#ISCELL
  standard offpage *
  page255_i41
#CELL
  pure_quanta q_cap *
  page255_i42
#CELL
  pure_quanta q_cap *
  page255_i43
#ISCELL
  logical_power universal_gnd *
  page255_i44
#ISCELL
  logical_power vcc15 *
  page255_i45
#CELL
  pure_quanta q_res *
  page255_i46
#ISCELL
  standard offpage *
  page255_i47
#CELL
  pure_quanta q_cap *
  page255_i48
#CELL
  pure_quanta q_res *
  page255_i49
#ISCELL
  logical_power universal_gnd *
  page255_i5
#CELL
  pure_quanta q_inductor4p_14 *
  page255_i50
#CELL
  pure_quanta q_cap *
  page255_i51
#CELL
  pure_quanta q_cap *
  page255_i52
#CELL
  pure_quanta q_cap *
  page255_i53
#CELL
  pure_quanta q_cap *
  page255_i54
#ISCELL
  logical_power universal_gnd *
  page255_i55
#CELL
  pure_quanta q_cap *
  page255_i56
#ISCELL
  logical_power vcc15 *
  page255_i57
#ISCELL
  standard offpage *
  page255_i58
#CELL
  pure_quanta q_cap *
  page255_i59
#ISCELL
  standard offpage *
  page255_i6
#ISCELL
  logical_power universal_gnd *
  page255_i60
#ISCELL
  logical_power vcc15 *
  page255_i61
#ISCELL
  logical_power universal_gnd *
  page255_i62
#CELL
  pure_quanta q_cap *
  page255_i63
#CELL
  pure_quanta q_cap *
  page255_i64
#ISCELL
  logical_power vcc15 *
  page255_i65
#CELL
  pure_quanta isl99390frztr5935 *
  page255_i66
#ISCELL
  standard offpage *
  page255_i7
#ISCELL
  standard offpage *
  page255_i8
#ISCELL
  standard offpage *
  page255_i9
#ISCELL
  mstr_misc dns *
  *
#ISCELL
  pure_quanta quanta_title_block_c *
  *
#ISCELL
  logical_power universal_gnd *
  page256_i1
#ISCELL
  logical_power universal_gnd *
  page256_i10
#CELL
  pure_quanta q_cap *
  page256_i11
#CELL
  pure_quanta q_res *
  page256_i12
#ISCELL
  logical_power vcc15 *
  page256_i13
#ISCELL
  logical_power universal_gnd *
  page256_i14
#CELL
  pure_quanta q_cap *
  page256_i15
#ISCELL
  logical_power universal_gnd *
  page256_i16
#CELL
  pure_quanta q_cap *
  page256_i17
#ISCELL
  standard offpage *
  page256_i18
#CELL
  pure_quanta q_res *
  page256_i19
#CELL
  pure_quanta isl99390frztr5935 *
  page256_i2
#CELL
  pure_quanta q_cap *
  page256_i20
#CELL
  pure_quanta q_cap *
  page256_i21
#ISCELL
  logical_power universal_gnd *
  page256_i22
#CELL
  pure_quanta q_res *
  page256_i23
#ISCELL
  standard offpage *
  page256_i24
#ISCELL
  standard offpage *
  page256_i25
#ISCELL
  logical_power universal_gnd *
  page256_i26
#ISCELL
  standard offpage *
  page256_i27
#ISCELL
  standard offpage *
  page256_i28
#CELL
  pure_quanta q_cap *
  page256_i29
#ISCELL
  logical_power universal_gnd *
  page256_i3
#ISCELL
  logical_power universal_gnd *
  page256_i30
#CELL
  pure_quanta q_cap *
  page256_i31
#CELL
  pure_quanta isl99390frztr5935 *
  page256_i32
#CELL
  pure_quanta q_res *
  page256_i33
#ISCELL
  logical_power vcc15 *
  page256_i34
#ISCELL
  logical_power universal_gnd *
  page256_i35
#CELL
  pure_quanta q_cap *
  page256_i36
#ISCELL
  logical_power universal_gnd *
  page256_i37
#ISCELL
  logical_power universal_gnd *
  page256_i38
#CELL
  pure_quanta q_inductor *
  page256_i39
#CELL
  pure_quanta q_res *
  page256_i4
#CELL
  pure_quanta q_res *
  page256_i40
#CELL
  pure_quanta q_cap *
  page256_i41
#CELL
  pure_quanta q_cap *
  page256_i42
#CELL
  pure_quanta q_cap *
  page256_i43
#CELL
  pure_quanta q_inductor4p_14 *
  page256_i44
#CELL
  pure_quanta q_cap *
  page256_i45
#CELL
  pure_quanta q_res *
  page256_i46
#CELL
  pure_quanta q_cap *
  page256_i47
#CELL
  pure_quanta q_cap *
  page256_i48
#ISCELL
  logical_power universal_gnd *
  page256_i49
#ISCELL
  standard offpage *
  page256_i5
#ISCELL
  logical_power vcc15 *
  page256_i50
#ISCELL
  logical_power universal_gnd *
  page256_i51
#CELL
  pure_quanta q_cap *
  page256_i52
#CELL
  pure_quanta q_cap *
  page256_i53
#CELL
  pure_quanta q_cap *
  page256_i54
#ISCELL
  logical_power universal_gnd *
  page256_i55
#ISCELL
  logical_power vcc15 *
  page256_i56
#CELL
  pure_quanta q_res *
  page256_i57
#CELL
  pure_quanta q_inductor4p_14 *
  page256_i58
#CELL
  pure_quanta q_cap *
  page256_i59
#ISCELL
  standard offpage *
  page256_i6
#ISCELL
  logical_power universal_gnd *
  page256_i60
#ISCELL
  standard offpage *
  page256_i61
#CELL
  pure_quanta q_cap *
  page256_i62
#CELL
  pure_quanta q_cap *
  page256_i63
#CELL
  pure_quanta q_cap *
  page256_i64
#ISCELL
  logical_power vcc15 *
  page256_i65
#CELL
  pure_quanta q_cap *
  page256_i66
#CELL
  pure_quanta q_cap *
  page256_i67
#ISCELL
  logical_power universal_gnd *
  page256_i68
#ISCELL
  logical_power vcc15 *
  page256_i69
#CELL
  pure_quanta q_cap *
  page256_i7
#ISCELL
  standard offpage *
  page256_i8
#ISCELL
  standard offpage *
  page256_i9
#ISCELL
  mstr_misc dns *
  *
#ISCELL
  pure_quanta quanta_title_block_c *
  *
#ISCELL
  logical_power universal_gnd *
  page257_i1
#ISCELL
  logical_power vcc15 *
  page257_i10
#ISCELL
  standard offpage *
  page257_i11
#ISCELL
  standard offpage *
  page257_i12
#ISCELL
  standard offpage *
  page257_i13
#ISCELL
  standard offpage *
  page257_i14
#CELL
  pure_quanta q_cap *
  page257_i15
#CELL
  pure_quanta isl99390frztr5935 *
  page257_i16
#ISCELL
  logical_power universal_gnd *
  page257_i17
#CELL
  pure_quanta q_cap *
  page257_i18
#CELL
  pure_quanta q_res *
  page257_i19
#CELL
  pure_quanta q_res *
  page257_i2
#ISCELL
  logical_power universal_gnd *
  page257_i20
#CELL
  pure_quanta q_cap *
  page257_i21
#CELL
  pure_quanta q_res *
  page257_i22
#ISCELL
  logical_power vcc15 *
  page257_i23
#ISCELL
  standard offpage *
  page257_i24
#CELL
  pure_quanta isl99390frztr5935 *
  page257_i25
#ISCELL
  logical_power universal_gnd *
  page257_i26
#CELL
  pure_quanta q_cap *
  page257_i27
#CELL
  pure_quanta q_cap *
  page257_i28
#ISCELL
  logical_power universal_gnd *
  page257_i29
#ISCELL
  logical_power universal_gnd *
  page257_i3
#CELL
  pure_quanta q_res *
  page257_i30
#CELL
  pure_quanta q_cap *
  page257_i31
#CELL
  pure_quanta q_cap *
  page257_i32
#ISCELL
  standard offpage *
  page257_i33
#ISCELL
  standard offpage *
  page257_i34
#CELL
  pure_quanta q_cap *
  page257_i35
#ISCELL
  standard offpage *
  page257_i36
#CELL
  pure_quanta q_cap *
  page257_i37
#ISCELL
  logical_power universal_gnd *
  page257_i38
#CELL
  pure_quanta q_res *
  page257_i39
#CELL
  pure_quanta q_res *
  page257_i4
#CELL
  pure_quanta q_res *
  page257_i40
#ISCELL
  logical_power universal_gnd *
  page257_i41
#CELL
  pure_quanta q_cap *
  page257_i42
#ISCELL
  logical_power vcc15 *
  page257_i43
#CELL
  pure_quanta q_cap *
  page257_i44
#CELL
  pure_quanta q_cap *
  page257_i45
#CELL
  pure_quanta q_res *
  page257_i46
#CELL
  pure_quanta q_cap *
  page257_i47
#CELL
  pure_quanta q_cap *
  page257_i48
#CELL
  pure_quanta q_inductor *
  page257_i49
#ISCELL
  logical_power vcc15 *
  page257_i5
#CELL
  pure_quanta q_res *
  page257_i50
#CELL
  pure_quanta q_cap *
  page257_i51
#CELL
  pure_quanta q_cap *
  page257_i52
#CELL
  pure_quanta q_cap *
  page257_i53
#ISCELL
  logical_power universal_gnd *
  page257_i54
#CELL
  pure_quanta q_cap *
  page257_i55
#ISCELL
  logical_power vcc15 *
  page257_i56
#CELL
  pure_quanta q_capp *
  page257_i57
#CELL
  pure_quanta q_capp *
  page257_i58
#CELL
  pure_quanta q_cap *
  page257_i59
#ISCELL
  logical_power universal_gnd *
  page257_i6
#CELL
  pure_quanta q_res *
  page257_i60
#ISCELL
  logical_power universal_gnd *
  page257_i61
#CELL
  pure_quanta q_capp *
  page257_i62
#CELL
  pure_quanta q_capp *
  page257_i63
#ISCELL
  logical_power universal_gnd *
  page257_i64
#ISCELL
  logical_power vcc15 *
  page257_i65
#ISCELL
  logical_power universal_gnd *
  page257_i66
#CELL
  pure_quanta q_capp *
  page257_i67
#ISCELL
  logical_power vcc15 *
  page257_i68
#CELL
  pure_quanta q_res *
  page257_i69
#ISCELL
  logical_power universal_gnd *
  page257_i7
#CELL
  pure_quanta q_inductor *
  page257_i70
#CELL
  pure_quanta q_cap *
  page257_i71
#ISCELL
  logical_power universal_gnd *
  page257_i72
#CELL
  pure_quanta q_cap *
  page257_i73
#ISCELL
  logical_power vcc15 *
  page257_i74
#CELL
  pure_quanta q_cap *
  page257_i75
#ISCELL
  logical_power gnd *
  page257_i76
#CELL
  pure_quanta q_cap *
  page257_i77
#CELL
  pure_quanta q_cap *
  page257_i78
#ISCELL
  logical_power vcc15 *
  page257_i79
#CELL
  pure_quanta q_res *
  page257_i8
#CELL
  pure_quanta q_inductor *
  page257_i80
#CELL
  pure_quanta q_cap *
  page257_i81
#ISCELL
  logical_power vcc15 *
  page257_i82
#CELL
  pure_quanta q_cap *
  page257_i83
#CELL
  pure_quanta q_cap *
  page257_i84
#CELL
  pure_quanta q_cap *
  page257_i85
#CELL
  pure_quanta q_cap *
  page257_i86
#ISCELL
  logical_power universal_gnd *
  page257_i87
#CELL
  pure_quanta q_capp *
  page257_i88
#ISCELL
  logical_power vcc15 *
  page257_i89
#CELL
  pure_quanta q_res *
  page257_i9
#ISCELL
  mstr_misc dns *
  *
#ISCELL
  pure_quanta quanta_title_block_c *
  *
#ISCELL
  logical_power universal_gnd *
  page258_i1
#CELL
  pure_quanta isl99390frztr5935 *
  page258_i10
#CELL
  pure_quanta q_res *
  page258_i11
#ISCELL
  logical_power vcc15 *
  page258_i12
#CELL
  pure_quanta q_cap *
  page258_i13
#ISCELL
  logical_power universal_gnd *
  page258_i14
#CELL
  pure_quanta q_res *
  page258_i15
#ISCELL
  standard offpage *
  page258_i16
#ISCELL
  standard offpage *
  page258_i17
#CELL
  pure_quanta q_cap *
  page258_i18
#ISCELL
  logical_power universal_gnd *
  page258_i19
#ISCELL
  logical_power universal_gnd *
  page258_i2
#ISCELL
  logical_power universal_gnd *
  page258_i20
#ISCELL
  standard offpage *
  page258_i21
#ISCELL
  standard offpage *
  page258_i22
#CELL
  pure_quanta q_cap *
  page258_i23
#ISCELL
  logical_power universal_gnd *
  page258_i24
#CELL
  pure_quanta q_cap *
  page258_i25
#CELL
  pure_quanta q_res *
  page258_i26
#ISCELL
  logical_power vcc15 *
  page258_i27
#CELL
  pure_quanta q_cap *
  page258_i28
#ISCELL
  logical_power universal_gnd *
  page258_i29
#CELL
  pure_quanta q_res *
  page258_i3
#ISCELL
  logical_power universal_gnd *
  page258_i30
#CELL
  pure_quanta q_cap *
  page258_i31
#ISCELL
  logical_power universal_gnd *
  page258_i32
#CELL
  pure_quanta q_res *
  page258_i33
#CELL
  pure_quanta q_cap *
  page258_i34
#CELL
  pure_quanta q_cap *
  page258_i35
#CELL
  pure_quanta q_cap *
  page258_i36
#CELL
  pure_quanta q_cap *
  page258_i37
#CELL
  pure_quanta q_res *
  page258_i38
#CELL
  pure_quanta q_inductor *
  page258_i39
#ISCELL
  standard offpage *
  page258_i4
#CELL
  pure_quanta q_cap *
  page258_i40
#CELL
  pure_quanta q_cap *
  page258_i41
#ISCELL
  logical_power universal_gnd *
  page258_i42
#ISCELL
  logical_power vcc15 *
  page258_i43
#CELL
  pure_quanta q_cap *
  page258_i44
#CELL
  pure_quanta q_res *
  page258_i45
#CELL
  pure_quanta q_cap *
  page258_i46
#CELL
  pure_quanta q_cap *
  page258_i47
#CELL
  pure_quanta q_cap *
  page258_i48
#CELL
  pure_quanta q_cap *
  page258_i49
#ISCELL
  standard offpage *
  page258_i5
#CELL
  pure_quanta q_res *
  page258_i50
#CELL
  pure_quanta q_inductor *
  page258_i51
#ISCELL
  logical_power universal_gnd *
  page258_i52
#CELL
  pure_quanta q_cap *
  page258_i53
#ISCELL
  logical_power vcc15 *
  page258_i54
#CELL
  pure_quanta q_cap *
  page258_i55
#ISCELL
  logical_power gnd *
  page258_i56
#CELL
  pure_quanta q_cap *
  page258_i57
#ISCELL
  logical_power vcc15 *
  page258_i58
#CELL
  pure_quanta q_inductor *
  page258_i59
#ISCELL
  standard offpage *
  page258_i6
#CELL
  pure_quanta q_cap *
  page258_i60
#CELL
  pure_quanta q_cap *
  page258_i61
#ISCELL
  logical_power universal_gnd *
  page258_i62
#ISCELL
  logical_power vcc15 *
  page258_i63
#CELL
  pure_quanta q_capp *
  page258_i64
#CELL
  pure_quanta q_capp *
  page258_i65
#ISCELL
  logical_power universal_gnd *
  page258_i66
#ISCELL
  logical_power universal_gnd *
  page258_i67
#CELL
  pure_quanta q_capp *
  page258_i68
#CELL
  pure_quanta q_capp *
  page258_i69
#ISCELL
  standard offpage *
  page258_i7
#CELL
  pure_quanta q_capp *
  page258_i70
#ISCELL
  logical_power vcc15 *
  page258_i71
#CELL
  pure_quanta q_cap *
  page258_i72
#CELL
  pure_quanta q_cap *
  page258_i73
#ISCELL
  logical_power vcc15 *
  page258_i74
#CELL
  pure_quanta q_cap *
  page258_i75
#CELL
  pure_quanta q_cap *
  page258_i76
#CELL
  pure_quanta q_cap *
  page258_i77
#ISCELL
  logical_power universal_gnd *
  page258_i78
#CELL
  pure_quanta q_cap *
  page258_i79
#ISCELL
  logical_power universal_gnd *
  page258_i8
#CELL
  pure_quanta q_capp *
  page258_i80
#ISCELL
  logical_power vcc15 *
  page258_i81
#CELL
  pure_quanta isl99390frztr5935 *
  page258_i82
#CELL
  pure_quanta q_cap *
  page258_i9
#ISCELL
  pure_quanta quanta_title_block_c *
  *
#ISCELL
  mstr_misc dns *
  *
#ISCELL
  pure_quanta quanta_title_block_c *
  *
#ISCELL
  standard offpage *
  page260_i1
#CELL
  pure_quanta q_res *
  page260_i10
#CELL
  pure_quanta q_res *
  page260_i100
#ISCELL
  logical_power universal_gnd *
  page260_i101
#ISCELL
  standard offpage *
  page260_i102
#ISCELL
  logical_power universal_gnd *
  page260_i103
#ISCELL
  logical_power vcc15 *
  page260_i104
#ISCELL
  logical_power universal_gnd *
  page260_i105
#CELL
  pure_quanta q_res *
  page260_i106
#ISCELL
  standard offpage *
  page260_i107
#ISCELL
  standard offpage *
  page260_i108
#CELL
  pure_quanta q_res *
  page260_i109
#CELL
  pure_quanta q_res *
  page260_i11
#CELL
  pure_quanta q_cap *
  page260_i110
#ISCELL
  logical_power vcc15 *
  page260_i12
#CELL
  pure_quanta q_res *
  page260_i13
#CELL
  pure_quanta q_res *
  page260_i14
#ISCELL
  logical_power universal_gnd *
  page260_i15
#ISCELL
  logical_power vcc15 *
  page260_i16
#CELL
  pure_quanta q_res *
  page260_i17
#CELL
  pure_quanta q_res *
  page260_i18
#CELL
  pure_quanta q_res *
  page260_i19
#ISCELL
  standard offpage *
  page260_i2
#CELL
  pure_quanta q_cap *
  page260_i20
#CELL
  pure_quanta q_res *
  page260_i21
#CELL
  pure_quanta q_cap *
  page260_i22
#CELL
  pure_quanta q_cap *
  page260_i23
#ISCELL
  standard offpage *
  page260_i24
#ISCELL
  standard offpage *
  page260_i25
#ISCELL
  standard offpage *
  page260_i26
#ISCELL
  standard offpage *
  page260_i27
#ISCELL
  logical_power vcc15 *
  page260_i28
#ISCELL
  standard offpage *
  page260_i29
#ISCELL
  standard offpage *
  page260_i3
#ISCELL
  standard offpage *
  page260_i30
#ISCELL
  standard offpage *
  page260_i31
#ISCELL
  standard offpage *
  page260_i32
#ISCELL
  standard offpage *
  page260_i33
#ISCELL
  standard offpage *
  page260_i34
#ISCELL
  standard offpage *
  page260_i35
#CELL
  pure_quanta q_res *
  page260_i36
#CELL
  pure_quanta q_res *
  page260_i37
#CELL
  pure_quanta q_res *
  page260_i38
#CELL
  pure_quanta q_short *
  page260_i39
#ISCELL
  logical_power universal_gnd *
  page260_i4
#CELL
  pure_quanta q_res *
  page260_i40
#ISCELL
  logical_power vcc15 *
  page260_i41
#CELL
  pure_quanta q_res *
  page260_i42
#CELL
  pure_quanta q_short *
  page260_i43
#CELL
  pure_quanta q_res *
  page260_i44
#ISCELL
  logical_power universal_gnd *
  page260_i45
#ISCELL
  logical_power vcc15 *
  page260_i46
#CELL
  pure_quanta q_res *
  page260_i47
#CELL
  pure_quanta q_cap *
  page260_i48
#CELL
  pure_quanta q_res *
  page260_i49
#ISCELL
  logical_power universal_gnd *
  page260_i5
#CELL
  pure_quanta q_cap *
  page260_i50
#CELL
  pure_quanta q_res *
  page260_i51
#CELL
  pure_quanta q_res *
  page260_i52
#CELL
  pure_quanta q_res *
  page260_i53
#ISCELL
  logical_power vcc15 *
  page260_i54
#CELL
  pure_quanta q_res *
  page260_i55
#CELL
  pure_quanta q_res *
  page260_i56
#CELL
  pure_quanta q_res *
  page260_i57
#CELL
  pure_quanta q_res *
  page260_i58
#CELL
  pure_quanta q_res *
  page260_i59
#CELL
  pure_quanta q_cap *
  page260_i60
#CELL
  pure_quanta q_cap *
  page260_i61
#ISCELL
  logical_power universal_gnd *
  page260_i62
#CELL
  pure_quanta q_cap *
  page260_i63
#ISCELL
  logical_power universal_gnd *
  page260_i64
#CELL
  pure_quanta isl69260irazt *
  page260_i65
#ISCELL
  logical_power universal_gnd *
  page260_i66
#ISCELL
  logical_power universal_gnd *
  page260_i67
#ISCELL
  logical_power universal_gnd *
  page260_i68
#CELL
  pure_quanta q_cap *
  page260_i69
#CELL
  pure_quanta q_res *
  page260_i7
#ISCELL
  logical_power universal_gnd *
  page260_i70
#CELL
  pure_quanta q_res *
  page260_i71
#ISCELL
  logical_power universal_gnd *
  page260_i72
#CELL
  pure_quanta q_cap *
  page260_i73
#ISCELL
  standard offpage *
  page260_i74
#ISCELL
  standard offpage *
  page260_i75
#CELL
  pure_quanta q_res *
  page260_i76
#ISCELL
  standard offpage *
  page260_i77
#CELL
  pure_quanta q_res *
  page260_i78
#CELL
  pure_quanta q_res *
  page260_i79
#ISCELL
  logical_power vcc15 *
  page260_i8
#ISCELL
  logical_power universal_gnd *
  page260_i80
#ISCELL
  logical_power vcc15 *
  page260_i81
#ISCELL
  logical_power universal_gnd *
  page260_i82
#ISCELL
  logical_power universal_gnd *
  page260_i83
#CELL
  pure_quanta q_res *
  page260_i84
#CELL
  pure_quanta q_res *
  page260_i85
#CELL
  pure_quanta q_res *
  page260_i86
#CELL
  pure_quanta q_res *
  page260_i87
#ISCELL
  logical_power universal_gnd *
  page260_i88
#ISCELL
  logical_power universal_gnd *
  page260_i89
#CELL
  pure_quanta q_res *
  page260_i9
#ISCELL
  logical_power universal_gnd *
  page260_i90
#ISCELL
  logical_power universal_gnd *
  page260_i91
#CELL
  pure_quanta q_cap *
  page260_i92
#ISCELL
  standard offpage *
  page260_i93
#ISCELL
  standard offpage *
  page260_i94
#CELL
  pure_quanta q_cap *
  page260_i95
#ISCELL
  standard offpage *
  page260_i96
#ISCELL
  standard offpage *
  page260_i97
#CELL
  pure_quanta q_cap *
  page260_i98
#CELL
  pure_quanta q_cap *
  page260_i99
#ISCELL
  mstr_misc dns *
  *
#ISCELL
  pure_quanta quanta_title_block_c *
  *
#ISCELL
  logical_power universal_gnd *
  page261_i1
#ISCELL
  logical_power universal_gnd *
  page261_i10
#CELL
  pure_quanta q_cap *
  page261_i11
#CELL
  pure_quanta isl99390frztr5935 *
  page261_i12
#CELL
  pure_quanta q_cap *
  page261_i13
#CELL
  pure_quanta q_res *
  page261_i14
#ISCELL
  logical_power universal_gnd *
  page261_i15
#CELL
  pure_quanta q_cap *
  page261_i16
#ISCELL
  logical_power vcc15 *
  page261_i17
#ISCELL
  standard offpage *
  page261_i18
#ISCELL
  standard offpage *
  page261_i19
#CELL
  pure_quanta q_res *
  page261_i2
#ISCELL
  logical_power universal_gnd *
  page261_i20
#ISCELL
  standard offpage *
  page261_i21
#ISCELL
  standard offpage *
  page261_i22
#ISCELL
  logical_power universal_gnd *
  page261_i23
#CELL
  pure_quanta q_cap *
  page261_i24
#CELL
  pure_quanta q_cap *
  page261_i25
#CELL
  pure_quanta q_res *
  page261_i26
#ISCELL
  logical_power vcc15 *
  page261_i27
#ISCELL
  logical_power universal_gnd *
  page261_i28
#CELL
  pure_quanta q_cap *
  page261_i29
#ISCELL
  logical_power universal_gnd *
  page261_i3
#ISCELL
  logical_power universal_gnd *
  page261_i30
#CELL
  pure_quanta q_res *
  page261_i31
#CELL
  pure_quanta q_cap *
  page261_i32
#ISCELL
  logical_power universal_gnd *
  page261_i33
#CELL
  pure_quanta q_res *
  page261_i34
#CELL
  pure_quanta q_cap *
  page261_i35
#CELL
  pure_quanta q_cap *
  page261_i36
#CELL
  pure_quanta q_cap *
  page261_i37
#CELL
  pure_quanta q_cap *
  page261_i38
#CELL
  pure_quanta q_inductor *
  page261_i39
#ISCELL
  logical_power universal_gnd *
  page261_i4
#CELL
  pure_quanta q_cap *
  page261_i40
#CELL
  pure_quanta q_cap *
  page261_i41
#ISCELL
  logical_power universal_gnd *
  page261_i42
#ISCELL
  logical_power vcc15 *
  page261_i43
#ISCELL
  logical_power universal_gnd *
  page261_i44
#CELL
  pure_quanta q_cap *
  page261_i45
#CELL
  pure_quanta q_res *
  page261_i46
#CELL
  pure_quanta q_res *
  page261_i47
#CELL
  pure_quanta q_cap *
  page261_i48
#CELL
  pure_quanta q_cap *
  page261_i49
#CELL
  pure_quanta q_res *
  page261_i5
#CELL
  pure_quanta q_cap *
  page261_i50
#CELL
  pure_quanta q_cap *
  page261_i51
#CELL
  pure_quanta q_inductor *
  page261_i52
#ISCELL
  logical_power universal_gnd *
  page261_i53
#CELL
  pure_quanta q_cap *
  page261_i54
#ISCELL
  logical_power vcc15 *
  page261_i55
#CELL
  pure_quanta q_cap *
  page261_i56
#CELL
  pure_quanta q_cap *
  page261_i57
#ISCELL
  logical_power vcc15 *
  page261_i58
#ISCELL
  logical_power gnd *
  page261_i59
#ISCELL
  standard offpage *
  page261_i6
#CELL
  pure_quanta q_cap *
  page261_i60
#ISCELL
  logical_power vcc15 *
  page261_i61
#CELL
  pure_quanta q_inductor *
  page261_i62
#CELL
  pure_quanta q_res *
  page261_i63
#ISCELL
  logical_power universal_gnd *
  page261_i64
#ISCELL
  logical_power vcc15 *
  page261_i65
#CELL
  pure_quanta q_capp *
  page261_i66
#CELL
  pure_quanta q_capp *
  page261_i67
#CELL
  pure_quanta q_capp *
  page261_i68
#CELL
  pure_quanta q_capp *
  page261_i69
#ISCELL
  standard offpage *
  page261_i7
#CELL
  pure_quanta q_capp *
  page261_i70
#ISCELL
  logical_power universal_gnd *
  page261_i71
#ISCELL
  logical_power vcc15 *
  page261_i72
#ISCELL
  logical_power universal_gnd *
  page261_i73
#CELL
  pure_quanta q_capp *
  page261_i74
#CELL
  pure_quanta q_capp *
  page261_i75
#ISCELL
  logical_power universal_gnd *
  page261_i76
#ISCELL
  logical_power vcc15 *
  page261_i77
#ISCELL
  logical_power vcc15 *
  page261_i78
#CELL
  pure_quanta isl99390frztr5935 *
  page261_i79
#ISCELL
  standard offpage *
  page261_i8
#ISCELL
  standard offpage *
  page261_i9
#ISCELL
  mstr_misc dns *
  *
#ISCELL
  pure_quanta quanta_title_block_c *
  *
#ISCELL
  logical_power universal_gnd *
  page262_i1
#CELL
  pure_quanta q_cap *
  page262_i10
#ISCELL
  logical_power universal_gnd *
  page262_i11
#CELL
  pure_quanta q_cap *
  page262_i12
#CELL
  pure_quanta q_res *
  page262_i13
#CELL
  pure_quanta raa2213404gnphb0 *
  page262_i14
#CELL
  pure_quanta q_res *
  page262_i15
#CELL
  pure_quanta q_res *
  page262_i16
#CELL
  pure_quanta q_res *
  page262_i17
#ISCELL
  logical_power universal_gnd *
  page262_i18
#ISCELL
  logical_power vcc15 *
  page262_i19
#CELL
  pure_quanta q_res *
  page262_i2
#CELL
  pure_quanta q_cap *
  page262_i20
#CELL
  pure_quanta q_res *
  page262_i21
#CELL
  pure_quanta q_res *
  page262_i22
#ISCELL
  logical_power vcc15 *
  page262_i23
#CELL
  pure_quanta q_cap *
  page262_i24
#CELL
  pure_quanta q_cap *
  page262_i25
#CELL
  pure_quanta q_cap *
  page262_i26
#CELL
  pure_quanta q_cap *
  page262_i27
#CELL
  pure_quanta q_cap *
  page262_i28
#CELL
  pure_quanta q_inductor *
  page262_i29
#ISCELL
  standard offpage *
  page262_i3
#ISCELL
  logical_power universal_gnd *
  page262_i30
#CELL
  pure_quanta q_cap *
  page262_i31
#CELL
  pure_quanta q_cap *
  page262_i32
#CELL
  pure_quanta q_capp *
  page262_i33
#CELL
  pure_quanta q_capp *
  page262_i34
#ISCELL
  logical_power universal_gnd *
  page262_i35
#CELL
  pure_quanta q_res *
  page262_i36
#ISCELL
  logical_power vcc15 *
  page262_i37
#ISCELL
  logical_power vcc15 *
  page262_i38
#ISCELL
  standard offpage *
  page262_i4
#ISCELL
  logical_power universal_gnd *
  page262_i5
#ISCELL
  standard offpage *
  page262_i6
#ISCELL
  standard offpage *
  page262_i7
#CELL
  pure_quanta q_res *
  page262_i8
#ISCELL
  logical_power vcc15 *
  page262_i9
#ISCELL
  pure_quanta quanta_title_block_c *
  *
#ISCELL
  mstr_misc dns *
  *
#ISCELL
  pure_quanta quanta_title_block_c *
  *
#ISCELL
  standard offpage *
  page264_i1
#CELL
  pure_quanta q_res *
  page264_i10
#CELL
  pure_quanta q_res *
  page264_i11
#ISCELL
  standard offpage *
  page264_i12
#CELL
  pure_quanta q_res *
  page264_i13
#CELL
  pure_quanta q_res *
  page264_i14
#ISCELL
  standard offpage *
  page264_i15
#ISCELL
  standard offpage *
  page264_i16
#ISCELL
  logical_power universal_gnd *
  page264_i17
#CELL
  pure_quanta q_cap *
  page264_i18
#CELL
  pure_quanta q_cap *
  page264_i19
#ISCELL
  standard offpage *
  page264_i2
#ISCELL
  logical_power vcc15 *
  page264_i20
#ISCELL
  standard offpage *
  page264_i21
#ISCELL
  standard offpage *
  page264_i22
#ISCELL
  standard offpage *
  page264_i23
#CELL
  pure_quanta q_res *
  page264_i24
#CELL
  pure_quanta q_res *
  page264_i25
#ISCELL
  standard offpage *
  page264_i26
#ISCELL
  standard offpage *
  page264_i27
#ISCELL
  standard offpage *
  page264_i28
#ISCELL
  standard offpage *
  page264_i29
#ISCELL
  standard offpage *
  page264_i3
#CELL
  pure_quanta q_res *
  page264_i30
#CELL
  pure_quanta q_res *
  page264_i31
#CELL
  pure_quanta q_short *
  page264_i32
#ISCELL
  logical_power universal_gnd *
  page264_i33
#ISCELL
  logical_power vcc15 *
  page264_i34
#ISCELL
  logical_power vcc15 *
  page264_i35
#CELL
  pure_quanta q_res *
  page264_i36
#CELL
  pure_quanta q_cap *
  page264_i37
#CELL
  pure_quanta q_res *
  page264_i38
#CELL
  pure_quanta q_res *
  page264_i39
#ISCELL
  logical_power universal_gnd *
  page264_i4
#CELL
  pure_quanta q_res *
  page264_i40
#ISCELL
  logical_power vcc15 *
  page264_i41
#CELL
  pure_quanta q_res *
  page264_i42
#CELL
  pure_quanta q_res *
  page264_i43
#CELL
  pure_quanta q_res *
  page264_i44
#CELL
  pure_quanta q_res *
  page264_i45
#CELL
  pure_quanta q_res *
  page264_i46
#CELL
  pure_quanta q_cap *
  page264_i47
#CELL
  pure_quanta q_res *
  page264_i48
#ISCELL
  logical_power universal_gnd *
  page264_i49
#CELL
  pure_quanta q_res *
  page264_i5
#CELL
  pure_quanta q_cap *
  page264_i50
#CELL
  pure_quanta q_cap *
  page264_i51
#ISCELL
  logical_power universal_gnd *
  page264_i52
#CELL
  pure_quanta isl69260irazt *
  page264_i53
#ISCELL
  logical_power universal_gnd *
  page264_i54
#ISCELL
  logical_power universal_gnd *
  page264_i55
#CELL
  pure_quanta q_cap *
  page264_i56
#CELL
  pure_quanta q_res *
  page264_i57
#ISCELL
  logical_power universal_gnd *
  page264_i58
#CELL
  pure_quanta q_res *
  page264_i59
#CELL
  pure_quanta q_res *
  page264_i60
#CELL
  pure_quanta q_res *
  page264_i61
#CELL
  pure_quanta q_res *
  page264_i62
#CELL
  pure_quanta q_res *
  page264_i63
#ISCELL
  logical_power universal_gnd *
  page264_i64
#ISCELL
  logical_power universal_gnd *
  page264_i65
#CELL
  pure_quanta q_res *
  page264_i66
#CELL
  pure_quanta q_res *
  page264_i67
#CELL
  pure_quanta q_res *
  page264_i68
#CELL
  pure_quanta q_res *
  page264_i69
#CELL
  pure_quanta q_res *
  page264_i7
#CELL
  pure_quanta q_cap *
  page264_i70
#CELL
  pure_quanta q_cap *
  page264_i71
#CELL
  pure_quanta q_cap *
  page264_i72
#CELL
  pure_quanta q_cap *
  page264_i73
#CELL
  pure_quanta q_res *
  page264_i74
#ISCELL
  standard offpage *
  page264_i75
#ISCELL
  standard offpage *
  page264_i76
#ISCELL
  logical_power universal_gnd *
  page264_i77
#ISCELL
  logical_power universal_gnd *
  page264_i78
#ISCELL
  standard offpage *
  page264_i79
#ISCELL
  logical_power universal_gnd *
  page264_i8
#CELL
  pure_quanta q_res *
  page264_i80
#ISCELL
  logical_power vcc15 *
  page264_i81
#ISCELL
  standard offpage *
  page264_i82
#ISCELL
  logical_power universal_gnd *
  page264_i83
#ISCELL
  logical_power universal_gnd *
  page264_i84
#CELL
  pure_quanta q_res *
  page264_i85
#ISCELL
  logical_power vcc15 *
  page264_i86
#ISCELL
  logical_power universal_gnd *
  page264_i87
#ISCELL
  standard offpage *
  page264_i88
#ISCELL
  standard offpage *
  page264_i89
#CELL
  pure_quanta q_cap *
  page264_i9
#ISCELL
  logical_power universal_gnd *
  page264_i90
#ISCELL
  logical_power universal_gnd *
  page264_i91
#ISCELL
  logical_power universal_gnd *
  page264_i92
#ISCELL
  logical_power universal_gnd *
  page264_i93
#ISCELL
  logical_power universal_gnd *
  page264_i94
#CELL
  pure_quanta q_res *
  page264_i95
#CELL
  pure_quanta q_cap *
  page264_i96
#ISCELL
  mstr_misc dns *
  *
#ISCELL
  pure_quanta quanta_title_block_c *
  *
#ISCELL
  logical_power universal_gnd *
  page265_i1
#ISCELL
  logical_power universal_gnd *
  page265_i10
#CELL
  pure_quanta q_cap *
  page265_i11
#CELL
  pure_quanta q_res *
  page265_i12
#ISCELL
  logical_power universal_gnd *
  page265_i13
#CELL
  pure_quanta q_cap *
  page265_i14
#ISCELL
  logical_power vcc15 *
  page265_i15
#ISCELL
  logical_power universal_gnd *
  page265_i16
#CELL
  pure_quanta q_res *
  page265_i17
#CELL
  pure_quanta q_cap *
  page265_i18
#CELL
  pure_quanta q_res *
  page265_i19
#ISCELL
  logical_power universal_gnd *
  page265_i2
#CELL
  pure_quanta q_cap *
  page265_i20
#CELL
  pure_quanta q_cap *
  page265_i21
#CELL
  pure_quanta q_cap *
  page265_i22
#CELL
  pure_quanta q_cap *
  page265_i23
#CELL
  pure_quanta q_cap *
  page265_i24
#CELL
  pure_quanta q_cap *
  page265_i25
#CELL
  pure_quanta q_capp *
  page265_i26
#CELL
  pure_quanta q_capp *
  page265_i27
#CELL
  pure_quanta q_cap *
  page265_i28
#CELL
  pure_quanta q_cap *
  page265_i29
#CELL
  pure_quanta q_res *
  page265_i3
#CELL
  pure_quanta q_inductor *
  page265_i30
#ISCELL
  logical_power universal_gnd *
  page265_i31
#ISCELL
  logical_power vcc15 *
  page265_i32
#ISCELL
  logical_power universal_gnd *
  page265_i33
#CELL
  pure_quanta q_capp *
  page265_i34
#ISCELL
  logical_power vcc15 *
  page265_i35
#ISCELL
  logical_power universal_gnd *
  page265_i36
#CELL
  pure_quanta q_res *
  page265_i37
#ISCELL
  logical_power vcc15 *
  page265_i38
#ISCELL
  standard offpage *
  page265_i4
#ISCELL
  standard offpage *
  page265_i5
#ISCELL
  standard offpage *
  page265_i6
#CELL
  pure_quanta q_cap *
  page265_i7
#CELL
  pure_quanta isl99390frztr5935 *
  page265_i8
#ISCELL
  standard offpage *
  page265_i9
#ISCELL
  pure_quanta quanta_title_block_c *
  *
#ISCELL
  mstr_misc dns *
  *
#ISCELL
  pure_quanta quanta_title_block_c *
  *
#ISCELL
  logical_power universal_gnd *
  page267_i1
#CELL
  pure_quanta q_cap *
  page267_i10
#ISCELL
  logical_power universal_gnd *
  page267_i11
#CELL
  pure_quanta q_cap *
  page267_i12
#ISCELL
  logical_power universal_gnd *
  page267_i13
#CELL
  pure_quanta q_res *
  page267_i14
#CELL
  pure_quanta q_res *
  page267_i15
#CELL
  pure_quanta q_cap *
  page267_i16
#CELL
  pure_quanta q_cap *
  page267_i17
#CELL
  pure_quanta q_res *
  page267_i18
#CELL
  pure_quanta rs53318lr *
  page267_i19
#ISCELL
  standard offpage *
  page267_i2
#ISCELL
  logical_power universal_gnd *
  page267_i20
#ISCELL
  logical_power vccaux15 *
  page267_i21
#ISCELL
  logical_power universal_gnd *
  page267_i22
#CELL
  pure_quanta q_cap *
  page267_i23
#ISCELL
  logical_power universal_gnd *
  page267_i24
#CELL
  pure_quanta q_cap *
  page267_i25
#CELL
  pure_quanta q_res *
  page267_i26
#CELL
  pure_quanta q_cap *
  page267_i27
#CELL
  pure_quanta q_inductor *
  page267_i28
#CELL
  pure_quanta q_res *
  page267_i29
#ISCELL
  logical_power vccaux15 *
  page267_i3
#CELL
  pure_quanta q_cap *
  page267_i30
#CELL
  pure_quanta mosfet_n *
  page267_i31
#ISCELL
  standard offpage *
  page267_i32
#CELL
  pure_quanta q_short *
  page267_i33
#CELL
  pure_quanta q_res *
  page267_i34
#CELL
  pure_quanta q_cap *
  page267_i35
#CELL
  pure_quanta q_res *
  page267_i36
#ISCELL
  logical_power universal_gnd *
  page267_i37
#CELL
  pure_quanta q_cap *
  page267_i38
#ISCELL
  standard offpage *
  page267_i39
#CELL
  pure_quanta q_cap *
  page267_i4
#CELL
  pure_quanta q_cap *
  page267_i40
#CELL
  pure_quanta q_short *
  page267_i41
#CELL
  pure_quanta q_cap *
  page267_i42
#CELL
  pure_quanta q_cap *
  page267_i43
#CELL
  pure_quanta q_cap *
  page267_i44
#CELL
  pure_quanta q_res *
  page267_i45
#ISCELL
  logical_power universal_power *
  page267_i46
#ISCELL
  logical_power universal_gnd *
  page267_i47
#ISCELL
  logical_power universal_gnd *
  page267_i48
#CELL
  pure_quanta q_capp *
  page267_i49
#CELL
  pure_quanta q_res *
  page267_i5
#ISCELL
  logical_power universal_power *
  page267_i50
#ISCELL
  logical_power universal_power *
  page267_i6
#CELL
  pure_quanta q_cap *
  page267_i7
#ISCELL
  logical_power universal_gnd *
  page267_i8
#CELL
  pure_quanta q_res *
  page267_i9
#ISCELL
  mstr_misc dns *
  *
#ISCELL
  pure_quanta quanta_title_block_c *
  *
#ISCELL
  logical_power universal_gnd *
  page268_i1
#CELL
  pure_quanta q_res *
  page268_i10
#CELL
  pure_quanta q_res *
  page268_i11
#ISCELL
  logical_power universal_gnd *
  page268_i12
#CELL
  pure_quanta q_cap *
  page268_i13
#ISCELL
  logical_power vccaux15 *
  page268_i14
#CELL
  pure_quanta q_cap *
  page268_i15
#ISCELL
  logical_power vccaux15 *
  page268_i16
#ISCELL
  logical_power universal_gnd *
  page268_i17
#ISCELL
  logical_power universal_gnd *
  page268_i18
#CELL
  pure_quanta q_res *
  page268_i19
#ISCELL
  standard offpage *
  page268_i2
#ISCELL
  logical_power universal_gnd *
  page268_i20
#CELL
  pure_quanta q_res *
  page268_i21
#CELL
  pure_quanta rs53317lr *
  page268_i22
#CELL
  pure_quanta q_cap *
  page268_i23
#ISCELL
  logical_power universal_gnd *
  page268_i24
#CELL
  pure_quanta q_cap *
  page268_i25
#CELL
  pure_quanta q_cap *
  page268_i26
#CELL
  pure_quanta q_res *
  page268_i27
#CELL
  pure_quanta q_res *
  page268_i28
#CELL
  pure_quanta q_inductor *
  page268_i29
#ISCELL
  logical_power vccaux15 *
  page268_i3
#ISCELL
  logical_power universal_gnd *
  page268_i30
#CELL
  pure_quanta q_cap *
  page268_i31
#CELL
  pure_quanta q_res *
  page268_i32
#CELL
  pure_quanta q_res *
  page268_i33
#ISCELL
  logical_power vccaux15 *
  page268_i34
#CELL
  pure_quanta q_cap *
  page268_i35
#CELL
  pure_quanta q_res *
  page268_i36
#CELL
  pure_quanta q_cap *
  page268_i37
#CELL
  pure_quanta q_cap *
  page268_i38
#CELL
  pure_quanta q_cap *
  page268_i39
#CELL
  pure_quanta q_cap *
  page268_i4
#CELL
  pure_quanta q_res *
  page268_i40
#CELL
  pure_quanta q_res *
  page268_i41
#CELL
  pure_quanta q_cap *
  page268_i42
#CELL
  pure_quanta q_cap *
  page268_i43
#ISCELL
  standard offpage *
  page268_i44
#ISCELL
  logical_power universal_gnd *
  page268_i45
#ISCELL
  logical_power vccaux15 *
  page268_i46
#CELL
  pure_quanta q_cap *
  page268_i47
#ISCELL
  logical_power vccaux15 *
  page268_i48
#CELL
  pure_quanta q_res *
  page268_i5
#ISCELL
  logical_power universal_gnd *
  page268_i6
#CELL
  pure_quanta q_cap *
  page268_i7
#ISCELL
  logical_power universal_gnd *
  page268_i8
#CELL
  pure_quanta q_res *
  page268_i9
#ISCELL
  pure_quanta quanta_title_block_c *
  *
#ISCELL
  mstr_misc dns *
  *
#ISCELL
  pure_quanta quanta_title_block_c *
  *
#ISCELL
  standard offpage *
  page270_i1
#ISCELL
  standard offpage *
  page270_i10
#CELL
  pure_quanta q_res *
  page270_i100
#CELL
  pure_quanta q_res *
  page270_i101
#ISCELL
  logical_power universal_gnd *
  page270_i102
#CELL
  pure_quanta q_cap *
  page270_i103
#CELL
  pure_quanta q_cap *
  page270_i104
#ISCELL
  logical_power vcc15 *
  page270_i105
#ISCELL
  standard offpage *
  page270_i106
#ISCELL
  standard offpage *
  page270_i107
#ISCELL
  standard offpage *
  page270_i108
#ISCELL
  standard offpage *
  page270_i109
#ISCELL
  standard offpage *
  page270_i11
#ISCELL
  standard offpage *
  page270_i110
#ISCELL
  standard offpage *
  page270_i111
#ISCELL
  standard offpage *
  page270_i112
#ISCELL
  standard offpage *
  page270_i113
#ISCELL
  standard offpage *
  page270_i114
#ISCELL
  standard offpage *
  page270_i115
#ISCELL
  standard offpage *
  page270_i116
#ISCELL
  standard offpage *
  page270_i117
#ISCELL
  standard offpage *
  page270_i118
#CELL
  pure_quanta q_cap *
  page270_i119
#CELL
  pure_quanta q_res *
  page270_i12
#CELL
  pure_quanta q_cap *
  page270_i120
#CELL
  pure_quanta q_cap *
  page270_i121
#CELL
  pure_quanta q_cap *
  page270_i122
#ISCELL
  logical_power universal_gnd *
  page270_i123
#ISCELL
  standard offpage *
  page270_i124
#ISCELL
  logical_power universal_gnd *
  page270_i125
#CELL
  pure_quanta q_res *
  page270_i126
#ISCELL
  logical_power vcc15 *
  page270_i127
#CELL
  pure_quanta q_cap *
  page270_i128
#ISCELL
  logical_power vcc15 *
  page270_i13
#ISCELL
  logical_power vcc15 *
  page270_i14
#CELL
  pure_quanta q_res *
  page270_i15
#CELL
  pure_quanta q_res *
  page270_i16
#CELL
  pure_quanta q_res *
  page270_i17
#CELL
  pure_quanta q_res *
  page270_i18
#CELL
  pure_quanta q_res *
  page270_i19
#ISCELL
  standard offpage *
  page270_i2
#ISCELL
  standard offpage *
  page270_i20
#ISCELL
  logical_power universal_gnd *
  page270_i21
#CELL
  pure_quanta q_short *
  page270_i22
#CELL
  pure_quanta q_res *
  page270_i23
#ISCELL
  logical_power vcc15 *
  page270_i24
#CELL
  pure_quanta q_res *
  page270_i25
#ISCELL
  logical_power universal_gnd *
  page270_i26
#CELL
  pure_quanta q_res *
  page270_i27
#CELL
  pure_quanta q_cap *
  page270_i28
#CELL
  pure_quanta q_res *
  page270_i29
#ISCELL
  standard offpage *
  page270_i3
#ISCELL
  logical_power universal_gnd *
  page270_i30
#CELL
  pure_quanta q_cap *
  page270_i31
#ISCELL
  logical_power universal_gnd *
  page270_i32
#CELL
  pure_quanta raa229126gnpha0 *
  page270_i33
#CELL
  pure_quanta q_cap *
  page270_i34
#CELL
  pure_quanta q_cap *
  page270_i35
#CELL
  pure_quanta q_res *
  page270_i36
#CELL
  pure_quanta q_res *
  page270_i37
#CELL
  pure_quanta q_cap *
  page270_i38
#ISCELL
  logical_power universal_gnd *
  page270_i39
#CELL
  pure_quanta q_res *
  page270_i4
#ISCELL
  logical_power universal_gnd *
  page270_i40
#ISCELL
  standard offpage *
  page270_i41
#ISCELL
  standard offpage *
  page270_i42
#ISCELL
  standard offpage *
  page270_i43
#ISCELL
  standard offpage *
  page270_i44
#CELL
  pure_quanta q_res *
  page270_i45
#CELL
  pure_quanta q_short *
  page270_i46
#ISCELL
  logical_power universal_gnd *
  page270_i47
#ISCELL
  logical_power vcc15 *
  page270_i48
#CELL
  pure_quanta q_res *
  page270_i49
#ISCELL
  logical_power universal_gnd *
  page270_i5
#ISCELL
  logical_power vcc15 *
  page270_i50
#ISCELL
  standard offpage *
  page270_i51
#ISCELL
  standard offpage *
  page270_i52
#ISCELL
  standard offpage *
  page270_i53
#ISCELL
  standard offpage *
  page270_i54
#ISCELL
  standard offpage *
  page270_i55
#CELL
  pure_quanta q_res *
  page270_i56
#CELL
  pure_quanta q_res *
  page270_i57
#CELL
  pure_quanta q_res *
  page270_i58
#CELL
  pure_quanta q_res *
  page270_i59
#CELL
  pure_quanta q_res *
  page270_i6
#CELL
  pure_quanta q_res *
  page270_i60
#CELL
  pure_quanta q_res *
  page270_i61
#ISCELL
  logical_power vcc15 *
  page270_i62
#CELL
  pure_quanta q_res *
  page270_i63
#CELL
  pure_quanta q_cap *
  page270_i64
#CELL
  pure_quanta q_res *
  page270_i65
#CELL
  pure_quanta q_res *
  page270_i66
#CELL
  pure_quanta q_cap *
  page270_i67
#CELL
  pure_quanta q_cap *
  page270_i68
#ISCELL
  logical_power universal_gnd *
  page270_i69
#CELL
  pure_quanta q_res *
  page270_i7
#ISCELL
  logical_power universal_gnd *
  page270_i70
#ISCELL
  logical_power universal_gnd *
  page270_i71
#CELL
  pure_quanta q_cap *
  page270_i72
#ISCELL
  logical_power universal_gnd *
  page270_i73
#CELL
  pure_quanta q_res *
  page270_i74
#ISCELL
  standard offpage *
  page270_i75
#ISCELL
  standard offpage *
  page270_i76
#ISCELL
  logical_power universal_gnd *
  page270_i77
#ISCELL
  standard offpage *
  page270_i78
#ISCELL
  standard offpage *
  page270_i79
#ISCELL
  logical_power vcc15 *
  page270_i8
#CELL
  pure_quanta q_res *
  page270_i80
#CELL
  pure_quanta q_res *
  page270_i81
#ISCELL
  logical_power universal_gnd *
  page270_i82
#ISCELL
  standard offpage *
  page270_i83
#ISCELL
  standard offpage *
  page270_i84
#ISCELL
  standard offpage *
  page270_i85
#ISCELL
  standard offpage *
  page270_i86
#ISCELL
  standard offpage *
  page270_i87
#ISCELL
  standard offpage *
  page270_i88
#ISCELL
  standard offpage *
  page270_i89
#CELL
  pure_quanta q_res *
  page270_i9
#ISCELL
  standard offpage *
  page270_i90
#ISCELL
  logical_power universal_gnd *
  page270_i91
#CELL
  pure_quanta q_cap *
  page270_i92
#ISCELL
  logical_power universal_gnd *
  page270_i93
#CELL
  pure_quanta q_res *
  page270_i94
#ISCELL
  standard offpage *
  page270_i95
#ISCELL
  standard offpage *
  page270_i96
#ISCELL
  standard offpage *
  page270_i97
#ISCELL
  standard offpage *
  page270_i98
#CELL
  pure_quanta q_res *
  page270_i99
#ISCELL
  mstr_misc dns *
  *
#ISCELL
  pure_quanta quanta_title_block_c *
  *
#ISCELL
  logical_power universal_gnd *
  page271_i1
#ISCELL
  logical_power universal_gnd *
  page271_i10
#CELL
  pure_quanta q_cap *
  page271_i11
#ISCELL
  logical_power universal_gnd *
  page271_i12
#CELL
  pure_quanta q_res *
  page271_i13
#ISCELL
  logical_power vcc15 *
  page271_i14
#CELL
  pure_quanta q_cap *
  page271_i15
#ISCELL
  logical_power universal_gnd *
  page271_i16
#ISCELL
  standard offpage *
  page271_i17
#CELL
  pure_quanta q_inductor4p_14 *
  page271_i18
#CELL
  pure_quanta q_cap *
  page271_i19
#ISCELL
  logical_power universal_gnd *
  page271_i2
#CELL
  pure_quanta q_res *
  page271_i20
#CELL
  pure_quanta q_cap *
  page271_i21
#CELL
  pure_quanta q_cap *
  page271_i22
#CELL
  pure_quanta q_cap *
  page271_i23
#CELL
  pure_quanta q_cap *
  page271_i24
#ISCELL
  logical_power universal_gnd *
  page271_i25
#CELL
  pure_quanta q_res *
  page271_i26
#ISCELL
  logical_power vcc15 *
  page271_i27
#ISCELL
  logical_power universal_gnd *
  page271_i28
#CELL
  pure_quanta q_res *
  page271_i29
#CELL
  pure_quanta q_res *
  page271_i3
#ISCELL
  standard offpage *
  page271_i30
#ISCELL
  standard offpage *
  page271_i31
#ISCELL
  standard offpage *
  page271_i32
#ISCELL
  standard offpage *
  page271_i33
#CELL
  pure_quanta q_cap *
  page271_i34
#ISCELL
  logical_power universal_gnd *
  page271_i35
#CELL
  pure_quanta q_cap *
  page271_i36
#CELL
  pure_quanta q_res *
  page271_i37
#ISCELL
  logical_power universal_gnd *
  page271_i38
#CELL
  pure_quanta q_cap *
  page271_i39
#ISCELL
  standard offpage *
  page271_i4
#CELL
  pure_quanta isl99390frztr5935 *
  page271_i40
#CELL
  pure_quanta q_res *
  page271_i41
#ISCELL
  logical_power vcc15 *
  page271_i42
#ISCELL
  logical_power universal_gnd *
  page271_i43
#CELL
  pure_quanta q_cap *
  page271_i44
#ISCELL
  standard offpage *
  page271_i45
#CELL
  pure_quanta q_res *
  page271_i46
#CELL
  pure_quanta q_cap *
  page271_i47
#CELL
  pure_quanta q_cap *
  page271_i48
#CELL
  pure_quanta q_cap *
  page271_i49
#ISCELL
  standard offpage *
  page271_i5
#CELL
  pure_quanta q_cap *
  page271_i50
#CELL
  pure_quanta q_res *
  page271_i51
#ISCELL
  standard offpage *
  page271_i52
#CELL
  pure_quanta q_cap *
  page271_i53
#ISCELL
  logical_power universal_gnd *
  page271_i54
#ISCELL
  logical_power vcc15 *
  page271_i55
#CELL
  pure_quanta q_capp *
  page271_i56
#CELL
  pure_quanta q_cap *
  page271_i57
#CELL
  pure_quanta q_cap *
  page271_i58
#CELL
  pure_quanta q_res *
  page271_i59
#CELL
  pure_quanta q_cap *
  page271_i6
#ISCELL
  logical_power universal_gnd *
  page271_i60
#CELL
  pure_quanta q_capp *
  page271_i61
#CELL
  pure_quanta q_capp *
  page271_i62
#CELL
  pure_quanta q_capp *
  page271_i63
#CELL
  pure_quanta q_capp *
  page271_i64
#CELL
  pure_quanta q_capp *
  page271_i65
#ISCELL
  logical_power vcc15 *
  page271_i66
#ISCELL
  logical_power universal_gnd *
  page271_i67
#CELL
  pure_quanta q_capp *
  page271_i68
#CELL
  pure_quanta q_capp *
  page271_i69
#CELL
  pure_quanta isl99390frztr5935 *
  page271_i7
#ISCELL
  logical_power vcc15 *
  page271_i70
#ISCELL
  logical_power universal_gnd *
  page271_i71
#CELL
  pure_quanta q_capp *
  page271_i72
#CELL
  pure_quanta q_res *
  page271_i73
#CELL
  pure_quanta q_inductor4p_14 *
  page271_i74
#ISCELL
  logical_power universal_gnd *
  page271_i75
#CELL
  pure_quanta q_cap *
  page271_i76
#ISCELL
  standard offpage *
  page271_i77
#ISCELL
  logical_power gnd *
  page271_i78
#CELL
  pure_quanta q_cap *
  page271_i79
#ISCELL
  standard offpage *
  page271_i8
#ISCELL
  logical_power vcc15 *
  page271_i80
#ISCELL
  logical_power vcc15 *
  page271_i81
#CELL
  pure_quanta q_res *
  page271_i82
#CELL
  pure_quanta q_inductor *
  page271_i83
#CELL
  pure_quanta q_cap *
  page271_i84
#CELL
  pure_quanta q_cap *
  page271_i85
#CELL
  pure_quanta q_capp *
  page271_i86
#CELL
  pure_quanta q_capp *
  page271_i87
#CELL
  pure_quanta q_cap *
  page271_i88
#ISCELL
  logical_power vcc15 *
  page271_i89
#ISCELL
  standard offpage *
  page271_i9
#ISCELL
  logical_power universal_gnd *
  page271_i90
#CELL
  pure_quanta q_cap *
  page271_i91
#CELL
  pure_quanta q_capp *
  page271_i92
#ISCELL
  logical_power vcc15 *
  page271_i93
#CELL
  pure_quanta q_capp *
  page271_i94
#ISCELL
  logical_power universal_gnd *
  page271_i95
#CELL
  pure_quanta q_capp *
  page271_i96
#ISCELL
  logical_power vcc15 *
  page271_i97
#ISCELL
  mstr_misc dns *
  *
#ISCELL
  pure_quanta quanta_title_block_c *
  *
#ISCELL
  logical_power universal_gnd *
  page272_i1
#CELL
  pure_quanta isl99390frztr5935 *
  page272_i10
#CELL
  pure_quanta q_cap *
  page272_i11
#CELL
  pure_quanta q_res *
  page272_i12
#ISCELL
  logical_power vcc15 *
  page272_i13
#ISCELL
  logical_power universal_gnd *
  page272_i14
#CELL
  pure_quanta q_res *
  page272_i15
#ISCELL
  standard offpage *
  page272_i16
#ISCELL
  standard offpage *
  page272_i17
#ISCELL
  logical_power universal_gnd *
  page272_i18
#CELL
  pure_quanta q_cap *
  page272_i19
#ISCELL
  logical_power universal_gnd *
  page272_i2
#ISCELL
  logical_power universal_gnd *
  page272_i20
#ISCELL
  standard offpage *
  page272_i21
#ISCELL
  standard offpage *
  page272_i22
#ISCELL
  logical_power universal_gnd *
  page272_i23
#CELL
  pure_quanta q_cap *
  page272_i24
#CELL
  pure_quanta q_res *
  page272_i25
#ISCELL
  logical_power vcc15 *
  page272_i26
#CELL
  pure_quanta q_cap *
  page272_i27
#ISCELL
  logical_power universal_gnd *
  page272_i28
#CELL
  pure_quanta q_cap *
  page272_i29
#CELL
  pure_quanta q_res *
  page272_i3
#ISCELL
  logical_power universal_gnd *
  page272_i30
#ISCELL
  standard offpage *
  page272_i31
#ISCELL
  logical_power universal_gnd *
  page272_i32
#CELL
  pure_quanta q_cap *
  page272_i33
#CELL
  pure_quanta q_res *
  page272_i34
#CELL
  pure_quanta q_cap *
  page272_i35
#CELL
  pure_quanta q_cap *
  page272_i36
#CELL
  pure_quanta q_inductor4p_14 *
  page272_i37
#CELL
  pure_quanta q_res *
  page272_i38
#CELL
  pure_quanta q_cap *
  page272_i39
#ISCELL
  standard offpage *
  page272_i4
#ISCELL
  standard offpage *
  page272_i40
#CELL
  pure_quanta q_cap *
  page272_i41
#CELL
  pure_quanta q_cap *
  page272_i42
#ISCELL
  logical_power universal_gnd *
  page272_i43
#ISCELL
  logical_power vcc15 *
  page272_i44
#CELL
  pure_quanta q_res *
  page272_i45
#CELL
  pure_quanta q_res *
  page272_i46
#ISCELL
  standard offpage *
  page272_i47
#CELL
  pure_quanta q_cap *
  page272_i48
#CELL
  pure_quanta q_cap *
  page272_i49
#ISCELL
  standard offpage *
  page272_i5
#CELL
  pure_quanta q_cap *
  page272_i50
#CELL
  pure_quanta q_inductor4p_14 *
  page272_i51
#CELL
  pure_quanta q_cap *
  page272_i52
#ISCELL
  logical_power universal_gnd *
  page272_i53
#CELL
  pure_quanta q_cap *
  page272_i54
#CELL
  pure_quanta q_cap *
  page272_i55
#ISCELL
  logical_power vcc15 *
  page272_i56
#ISCELL
  standard offpage *
  page272_i57
#CELL
  pure_quanta q_cap *
  page272_i58
#CELL
  pure_quanta q_cap *
  page272_i59
#CELL
  pure_quanta q_cap *
  page272_i6
#ISCELL
  logical_power universal_gnd *
  page272_i60
#ISCELL
  logical_power vcc15 *
  page272_i61
#ISCELL
  logical_power universal_gnd *
  page272_i62
#CELL
  pure_quanta q_cap *
  page272_i63
#CELL
  pure_quanta q_cap *
  page272_i64
#ISCELL
  logical_power vcc15 *
  page272_i65
#CELL
  pure_quanta isl99390frztr5935 *
  page272_i66
#ISCELL
  standard offpage *
  page272_i7
#ISCELL
  standard offpage *
  page272_i8
#ISCELL
  logical_power universal_gnd *
  page272_i9
#ISCELL
  mstr_misc dns *
  *
#ISCELL
  pure_quanta quanta_title_block_c *
  *
#ISCELL
  logical_power universal_gnd *
  page273_i1
#ISCELL
  standard offpage *
  page273_i10
#ISCELL
  standard offpage *
  page273_i11
#ISCELL
  standard offpage *
  page273_i12
#ISCELL
  standard offpage *
  page273_i13
#ISCELL
  standard offpage *
  page273_i14
#CELL
  pure_quanta q_cap *
  page273_i15
#CELL
  pure_quanta isl99390frztr5935 *
  page273_i16
#CELL
  pure_quanta q_cap *
  page273_i17
#ISCELL
  logical_power universal_gnd *
  page273_i18
#CELL
  pure_quanta q_res *
  page273_i19
#CELL
  pure_quanta q_res *
  page273_i2
#ISCELL
  logical_power universal_gnd *
  page273_i20
#CELL
  pure_quanta q_cap *
  page273_i21
#ISCELL
  logical_power vcc15 *
  page273_i22
#CELL
  pure_quanta isl99390frztr5935 *
  page273_i23
#ISCELL
  logical_power universal_gnd *
  page273_i24
#ISCELL
  standard offpage *
  page273_i25
#CELL
  pure_quanta q_cap *
  page273_i26
#CELL
  pure_quanta q_res *
  page273_i27
#CELL
  pure_quanta q_inductor4p_14 *
  page273_i28
#CELL
  pure_quanta q_cap *
  page273_i29
#ISCELL
  standard offpage *
  page273_i3
#CELL
  pure_quanta q_res *
  page273_i30
#CELL
  pure_quanta q_cap *
  page273_i31
#ISCELL
  logical_power universal_gnd *
  page273_i32
#CELL
  pure_quanta q_cap *
  page273_i33
#CELL
  pure_quanta q_cap *
  page273_i34
#CELL
  pure_quanta q_cap *
  page273_i35
#CELL
  pure_quanta q_cap *
  page273_i36
#CELL
  pure_quanta q_cap *
  page273_i37
#ISCELL
  logical_power universal_gnd *
  page273_i38
#CELL
  pure_quanta q_res *
  page273_i39
#ISCELL
  logical_power universal_gnd *
  page273_i4
#ISCELL
  logical_power universal_gnd *
  page273_i40
#CELL
  pure_quanta q_cap *
  page273_i41
#ISCELL
  logical_power vcc15 *
  page273_i42
#ISCELL
  standard offpage *
  page273_i43
#CELL
  pure_quanta q_res *
  page273_i44
#CELL
  pure_quanta q_cap *
  page273_i45
#CELL
  pure_quanta q_cap *
  page273_i46
#CELL
  pure_quanta q_cap *
  page273_i47
#CELL
  pure_quanta q_inductor4p_14 *
  page273_i48
#CELL
  pure_quanta q_res *
  page273_i49
#ISCELL
  standard offpage *
  page273_i5
#CELL
  pure_quanta q_cap *
  page273_i50
#CELL
  pure_quanta q_cap *
  page273_i51
#CELL
  pure_quanta q_cap *
  page273_i52
#ISCELL
  standard offpage *
  page273_i53
#CELL
  pure_quanta q_cap *
  page273_i54
#ISCELL
  logical_power universal_gnd *
  page273_i55
#ISCELL
  logical_power vcc15 *
  page273_i56
#CELL
  pure_quanta q_cap *
  page273_i57
#ISCELL
  logical_power universal_gnd *
  page273_i58
#ISCELL
  logical_power vcc15 *
  page273_i59
#ISCELL
  logical_power universal_gnd *
  page273_i6
#ISCELL
  logical_power universal_gnd *
  page273_i60
#ISCELL
  logical_power universal_gnd *
  page273_i61
#ISCELL
  standard offpage *
  page273_i62
#ISCELL
  logical_power vcc15 *
  page273_i63
#CELL
  pure_quanta q_cap *
  page273_i64
#CELL
  pure_quanta q_cap *
  page273_i65
#ISCELL
  logical_power vcc15 *
  page273_i66
#CELL
  pure_quanta q_res *
  page273_i7
#ISCELL
  standard offpage *
  page273_i8
#ISCELL
  logical_power universal_gnd *
  page273_i9
#ISCELL
  mstr_misc dns *
  *
#ISCELL
  pure_quanta quanta_title_block_c *
  *
#ISCELL
  logical_power universal_gnd *
  page274_i1
#ISCELL
  logical_power universal_gnd *
  page274_i10
#CELL
  pure_quanta isl99390frztr5935 *
  page274_i11
#CELL
  pure_quanta q_res *
  page274_i12
#ISCELL
  logical_power vcc15 *
  page274_i13
#ISCELL
  logical_power universal_gnd *
  page274_i14
#CELL
  pure_quanta q_res *
  page274_i15
#ISCELL
  standard offpage *
  page274_i16
#ISCELL
  standard offpage *
  page274_i17
#CELL
  pure_quanta q_cap *
  page274_i18
#ISCELL
  logical_power universal_gnd *
  page274_i19
#ISCELL
  standard offpage *
  page274_i2
#CELL
  pure_quanta isl99390frztr5935 *
  page274_i20
#ISCELL
  logical_power universal_gnd *
  page274_i21
#ISCELL
  logical_power universal_gnd *
  page274_i22
#CELL
  pure_quanta q_inductor *
  page274_i23
#CELL
  pure_quanta q_cap *
  page274_i24
#ISCELL
  logical_power universal_gnd *
  page274_i25
#CELL
  pure_quanta q_res *
  page274_i26
#CELL
  pure_quanta q_cap *
  page274_i27
#CELL
  pure_quanta q_cap *
  page274_i28
#ISCELL
  logical_power universal_gnd *
  page274_i29
#CELL
  pure_quanta q_res *
  page274_i3
#ISCELL
  standard offpage *
  page274_i30
#ISCELL
  standard offpage *
  page274_i31
#CELL
  pure_quanta q_cap *
  page274_i32
#ISCELL
  logical_power universal_gnd *
  page274_i33
#CELL
  pure_quanta q_cap *
  page274_i34
#ISCELL
  logical_power vcc15 *
  page274_i35
#ISCELL
  logical_power universal_gnd *
  page274_i36
#CELL
  pure_quanta q_cap *
  page274_i37
#ISCELL
  standard offpage *
  page274_i38
#CELL
  pure_quanta q_res *
  page274_i39
#ISCELL
  logical_power universal_gnd *
  page274_i4
#CELL
  pure_quanta q_cap *
  page274_i40
#CELL
  pure_quanta q_cap *
  page274_i41
#CELL
  pure_quanta q_cap *
  page274_i42
#CELL
  pure_quanta q_inductor4p_14 *
  page274_i43
#CELL
  pure_quanta q_res *
  page274_i44
#ISCELL
  standard offpage *
  page274_i45
#CELL
  pure_quanta q_cap *
  page274_i46
#CELL
  pure_quanta q_cap *
  page274_i47
#ISCELL
  logical_power universal_gnd *
  page274_i48
#ISCELL
  logical_power vcc15 *
  page274_i49
#ISCELL
  standard offpage *
  page274_i5
#CELL
  pure_quanta q_res *
  page274_i50
#ISCELL
  logical_power universal_gnd *
  page274_i51
#CELL
  pure_quanta q_cap *
  page274_i52
#CELL
  pure_quanta q_cap *
  page274_i53
#CELL
  pure_quanta q_cap *
  page274_i54
#ISCELL
  logical_power universal_gnd *
  page274_i55
#ISCELL
  logical_power vcc15 *
  page274_i56
#ISCELL
  logical_power universal_gnd *
  page274_i57
#CELL
  pure_quanta q_inductor4p_14 *
  page274_i58
#CELL
  pure_quanta q_cap *
  page274_i59
#ISCELL
  standard offpage *
  page274_i6
#ISCELL
  logical_power universal_gnd *
  page274_i60
#CELL
  pure_quanta q_cap *
  page274_i61
#CELL
  pure_quanta q_cap *
  page274_i62
#ISCELL
  logical_power vcc15 *
  page274_i63
#CELL
  pure_quanta q_cap *
  page274_i64
#CELL
  pure_quanta q_cap *
  page274_i65
#CELL
  pure_quanta q_cap *
  page274_i66
#ISCELL
  logical_power vcc15 *
  page274_i67
#CELL
  pure_quanta q_res *
  page274_i68
#CELL
  pure_quanta q_cap *
  page274_i69
#CELL
  pure_quanta q_cap *
  page274_i7
#ISCELL
  standard offpage *
  page274_i8
#CELL
  pure_quanta q_cap *
  page274_i9
#ISCELL
  mstr_misc dns *
  *
#ISCELL
  pure_quanta quanta_title_block_c *
  *
#ISCELL
  logical_power universal_gnd *
  page275_i1
#ISCELL
  logical_power universal_gnd *
  page275_i10
#CELL
  pure_quanta q_cap *
  page275_i11
#CELL
  pure_quanta q_res *
  page275_i12
#CELL
  pure_quanta q_res *
  page275_i13
#ISCELL
  logical_power vcc15 *
  page275_i14
#ISCELL
  logical_power universal_gnd *
  page275_i15
#CELL
  pure_quanta q_cap *
  page275_i16
#CELL
  pure_quanta q_res *
  page275_i17
#ISCELL
  logical_power vcc15 *
  page275_i18
#ISCELL
  logical_power universal_gnd *
  page275_i19
#CELL
  pure_quanta q_res *
  page275_i2
#CELL
  pure_quanta q_res *
  page275_i20
#ISCELL
  logical_power universal_gnd *
  page275_i21
#ISCELL
  standard offpage *
  page275_i22
#ISCELL
  standard offpage *
  page275_i23
#ISCELL
  standard offpage *
  page275_i24
#ISCELL
  standard offpage *
  page275_i25
#ISCELL
  logical_power universal_gnd *
  page275_i26
#CELL
  pure_quanta q_cap *
  page275_i27
#CELL
  pure_quanta q_res *
  page275_i28
#CELL
  pure_quanta q_cap *
  page275_i29
#ISCELL
  logical_power universal_gnd *
  page275_i3
#ISCELL
  logical_power universal_gnd *
  page275_i30
#CELL
  pure_quanta q_cap *
  page275_i31
#CELL
  pure_quanta q_res *
  page275_i32
#ISCELL
  logical_power vcc15 *
  page275_i33
#CELL
  pure_quanta q_res *
  page275_i34
#ISCELL
  logical_power vcc15 *
  page275_i35
#ISCELL
  logical_power universal_gnd *
  page275_i36
#CELL
  pure_quanta q_cap *
  page275_i37
#CELL
  pure_quanta q_res *
  page275_i38
#CELL
  pure_quanta q_cap *
  page275_i39
#ISCELL
  standard offpage *
  page275_i4
#CELL
  pure_quanta q_cap *
  page275_i40
#CELL
  pure_quanta q_res *
  page275_i41
#CELL
  pure_quanta q_cap *
  page275_i42
#CELL
  pure_quanta q_cap *
  page275_i43
#CELL
  pure_quanta q_inductor *
  page275_i44
#ISCELL
  logical_power universal_gnd *
  page275_i45
#CELL
  pure_quanta q_cap *
  page275_i46
#ISCELL
  logical_power vcc15 *
  page275_i47
#ISCELL
  logical_power universal_gnd *
  page275_i48
#CELL
  pure_quanta q_cap *
  page275_i49
#ISCELL
  standard offpage *
  page275_i5
#CELL
  pure_quanta q_res *
  page275_i50
#CELL
  pure_quanta q_cap *
  page275_i51
#CELL
  pure_quanta q_cap *
  page275_i52
#CELL
  pure_quanta q_res *
  page275_i53
#CELL
  pure_quanta q_cap *
  page275_i54
#CELL
  pure_quanta q_inductor *
  page275_i55
#CELL
  pure_quanta q_cap *
  page275_i56
#ISCELL
  logical_power universal_gnd *
  page275_i57
#CELL
  pure_quanta q_cap *
  page275_i58
#ISCELL
  logical_power vcc15 *
  page275_i59
#ISCELL
  standard offpage *
  page275_i6
#CELL
  pure_quanta q_cap *
  page275_i60
#CELL
  pure_quanta q_cap *
  page275_i61
#CELL
  pure_quanta q_cap *
  page275_i62
#CELL
  pure_quanta q_cap *
  page275_i63
#CELL
  pure_quanta q_res *
  page275_i64
#ISCELL
  logical_power universal_gnd *
  page275_i65
#CELL
  pure_quanta q_capp *
  page275_i66
#CELL
  pure_quanta q_capp *
  page275_i67
#CELL
  pure_quanta q_capp *
  page275_i68
#ISCELL
  logical_power vcc15 *
  page275_i69
#ISCELL
  standard offpage *
  page275_i7
#CELL
  pure_quanta q_capp *
  page275_i70
#ISCELL
  logical_power universal_gnd *
  page275_i71
#CELL
  pure_quanta q_capp *
  page275_i72
#ISCELL
  logical_power vcc15 *
  page275_i73
#CELL
  pure_quanta q_cap *
  page275_i74
#CELL
  pure_quanta q_cap *
  page275_i75
#ISCELL
  logical_power gnd *
  page275_i76
#CELL
  pure_quanta q_cap *
  page275_i77
#ISCELL
  logical_power vcc15 *
  page275_i78
#CELL
  pure_quanta q_inductor *
  page275_i79
#CELL
  pure_quanta q_cap *
  page275_i8
#CELL
  pure_quanta q_cap *
  page275_i80
#ISCELL
  logical_power universal_gnd *
  page275_i81
#ISCELL
  logical_power vcc15 *
  page275_i82
#CELL
  pure_quanta q_cap *
  page275_i83
#CELL
  pure_quanta q_cap *
  page275_i84
#CELL
  pure_quanta q_cap *
  page275_i85
#ISCELL
  logical_power universal_gnd *
  page275_i86
#CELL
  pure_quanta q_capp *
  page275_i87
#ISCELL
  logical_power vcc15 *
  page275_i88
#CELL
  pure_quanta isl99390frztr5935 *
  page275_i89
#CELL
  pure_quanta isl99390frztr5935 *
  page275_i9
#ISCELL
  mstr_misc dns *
  *
#ISCELL
  pure_quanta quanta_title_block_c *
  *
#ISCELL
  logical_power universal_gnd *
  page276_i1
#ISCELL
  standard offpage *
  page276_i10
#ISCELL
  logical_power universal_gnd *
  page276_i11
#CELL
  pure_quanta q_cap *
  page276_i12
#CELL
  pure_quanta q_cap *
  page276_i13
#ISCELL
  logical_power universal_gnd *
  page276_i14
#CELL
  pure_quanta isl99390frztr5935 *
  page276_i15
#ISCELL
  logical_power universal_gnd *
  page276_i16
#CELL
  pure_quanta q_res *
  page276_i17
#CELL
  pure_quanta q_res *
  page276_i18
#ISCELL
  logical_power vcc15 *
  page276_i19
#CELL
  pure_quanta q_res *
  page276_i2
#CELL
  pure_quanta q_cap *
  page276_i20
#ISCELL
  standard offpage *
  page276_i21
#ISCELL
  standard offpage *
  page276_i22
#CELL
  pure_quanta q_cap *
  page276_i23
#CELL
  pure_quanta isl99390frztr5935 *
  page276_i24
#ISCELL
  standard offpage *
  page276_i25
#ISCELL
  standard offpage *
  page276_i26
#CELL
  pure_quanta q_cap *
  page276_i27
#ISCELL
  logical_power universal_gnd *
  page276_i28
#CELL
  pure_quanta q_res *
  page276_i29
#ISCELL
  logical_power universal_gnd *
  page276_i3
#ISCELL
  logical_power universal_gnd *
  page276_i30
#CELL
  pure_quanta q_cap *
  page276_i31
#ISCELL
  logical_power vcc15 *
  page276_i32
#CELL
  pure_quanta q_cap *
  page276_i33
#ISCELL
  logical_power universal_gnd *
  page276_i34
#CELL
  pure_quanta q_cap *
  page276_i35
#CELL
  pure_quanta q_cap *
  page276_i36
#CELL
  pure_quanta q_cap *
  page276_i37
#CELL
  pure_quanta q_cap *
  page276_i38
#CELL
  pure_quanta q_cap *
  page276_i39
#ISCELL
  logical_power universal_gnd *
  page276_i4
#CELL
  pure_quanta q_res *
  page276_i40
#CELL
  pure_quanta q_cap *
  page276_i41
#CELL
  pure_quanta q_cap *
  page276_i42
#CELL
  pure_quanta q_res *
  page276_i43
#CELL
  pure_quanta q_inductor *
  page276_i44
#CELL
  pure_quanta q_cap *
  page276_i45
#ISCELL
  logical_power universal_gnd *
  page276_i46
#CELL
  pure_quanta q_cap *
  page276_i47
#CELL
  pure_quanta q_cap *
  page276_i48
#ISCELL
  logical_power universal_gnd *
  page276_i49
#CELL
  pure_quanta q_res *
  page276_i5
#CELL
  pure_quanta q_cap *
  page276_i50
#ISCELL
  logical_power vcc15 *
  page276_i51
#CELL
  pure_quanta q_cap *
  page276_i52
#ISCELL
  logical_power vcc15 *
  page276_i53
#CELL
  pure_quanta q_res *
  page276_i54
#CELL
  pure_quanta q_capp *
  page276_i55
#CELL
  pure_quanta q_cap *
  page276_i56
#CELL
  pure_quanta q_inductor *
  page276_i57
#CELL
  pure_quanta q_cap *
  page276_i58
#ISCELL
  logical_power universal_gnd *
  page276_i59
#ISCELL
  logical_power universal_gnd *
  page276_i6
#CELL
  pure_quanta q_cap *
  page276_i60
#ISCELL
  logical_power vcc15 *
  page276_i61
#CELL
  pure_quanta q_cap *
  page276_i62
#ISCELL
  logical_power gnd *
  page276_i63
#CELL
  pure_quanta q_inductor *
  page276_i64
#ISCELL
  logical_power vcc15 *
  page276_i65
#CELL
  pure_quanta q_cap *
  page276_i66
#CELL
  pure_quanta q_capp *
  page276_i67
#CELL
  pure_quanta q_cap *
  page276_i68
#ISCELL
  logical_power universal_gnd *
  page276_i69
#ISCELL
  standard offpage *
  page276_i7
#CELL
  pure_quanta q_capp *
  page276_i70
#ISCELL
  logical_power universal_gnd *
  page276_i71
#CELL
  pure_quanta q_capp *
  page276_i72
#CELL
  pure_quanta q_capp *
  page276_i73
#ISCELL
  logical_power vcc15 *
  page276_i74
#CELL
  pure_quanta q_cap *
  page276_i75
#ISCELL
  logical_power vcc15 *
  page276_i76
#CELL
  pure_quanta q_cap *
  page276_i77
#CELL
  pure_quanta q_cap *
  page276_i78
#ISCELL
  logical_power universal_gnd *
  page276_i79
#ISCELL
  standard offpage *
  page276_i8
#CELL
  pure_quanta q_cap *
  page276_i80
#CELL
  pure_quanta q_capp *
  page276_i81
#ISCELL
  logical_power vcc15 *
  page276_i82
#ISCELL
  standard offpage *
  page276_i9
#ISCELL
  pure_quanta quanta_title_block_c *
  *
#ISCELL
  mstr_misc dns *
  *
#ISCELL
  pure_quanta quanta_title_block_c *
  *
#ISCELL
  standard offpage *
  page278_i1
#ISCELL
  standard offpage *
  page278_i10
#ISCELL
  logical_power universal_gnd *
  page278_i100
#ISCELL
  standard offpage *
  page278_i101
#ISCELL
  logical_power vcc15 *
  page278_i102
#CELL
  pure_quanta q_res *
  page278_i103
#CELL
  pure_quanta q_res *
  page278_i104
#CELL
  pure_quanta q_res *
  page278_i105
#CELL
  pure_quanta q_cap *
  page278_i106
#ISCELL
  logical_power universal_gnd *
  page278_i107
#CELL
  pure_quanta q_res *
  page278_i108
#ISCELL
  logical_power vcc15 *
  page278_i109
#ISCELL
  standard offpage *
  page278_i11
#CELL
  pure_quanta q_res *
  page278_i110
#CELL
  pure_quanta q_cap *
  page278_i111
#ISCELL
  standard offpage *
  page278_i12
#ISCELL
  standard offpage *
  page278_i13
#CELL
  pure_quanta q_res *
  page278_i14
#CELL
  pure_quanta q_res *
  page278_i15
#ISCELL
  logical_power vcc15 *
  page278_i16
#ISCELL
  standard offpage *
  page278_i17
#ISCELL
  standard offpage *
  page278_i18
#ISCELL
  logical_power universal_gnd *
  page278_i19
#ISCELL
  standard offpage *
  page278_i2
#CELL
  pure_quanta q_res *
  page278_i21
#CELL
  pure_quanta q_res *
  page278_i22
#CELL
  pure_quanta q_res *
  page278_i23
#ISCELL
  logical_power vcc15 *
  page278_i24
#ISCELL
  logical_power vcc15 *
  page278_i25
#CELL
  pure_quanta q_res *
  page278_i26
#ISCELL
  logical_power universal_gnd *
  page278_i27
#CELL
  pure_quanta q_cap *
  page278_i28
#CELL
  pure_quanta q_res *
  page278_i29
#ISCELL
  standard offpage *
  page278_i3
#CELL
  pure_quanta q_res *
  page278_i30
#CELL
  pure_quanta q_res *
  page278_i31
#CELL
  pure_quanta q_cap *
  page278_i32
#CELL
  pure_quanta q_cap *
  page278_i33
#ISCELL
  logical_power universal_gnd *
  page278_i34
#CELL
  pure_quanta q_res *
  page278_i35
#CELL
  pure_quanta q_cap *
  page278_i36
#ISCELL
  logical_power universal_gnd *
  page278_i37
#CELL
  pure_quanta isl69260irazt *
  page278_i38
#ISCELL
  logical_power universal_gnd *
  page278_i39
#ISCELL
  standard offpage *
  page278_i4
#ISCELL
  logical_power universal_gnd *
  page278_i40
#CELL
  pure_quanta q_res *
  page278_i41
#ISCELL
  logical_power vcc15 *
  page278_i42
#ISCELL
  logical_power universal_gnd *
  page278_i43
#CELL
  pure_quanta q_short *
  page278_i44
#CELL
  pure_quanta q_res *
  page278_i45
#CELL
  pure_quanta q_res *
  page278_i46
#ISCELL
  logical_power vcc15 *
  page278_i47
#ISCELL
  logical_power universal_gnd *
  page278_i48
#CELL
  pure_quanta q_res *
  page278_i49
#ISCELL
  standard offpage *
  page278_i5
#CELL
  pure_quanta q_res *
  page278_i50
#CELL
  pure_quanta q_cap *
  page278_i51
#CELL
  pure_quanta q_res *
  page278_i52
#CELL
  pure_quanta q_cap *
  page278_i53
#CELL
  pure_quanta q_short *
  page278_i54
#CELL
  pure_quanta q_res *
  page278_i55
#ISCELL
  logical_power vcc15 *
  page278_i56
#CELL
  pure_quanta q_res *
  page278_i57
#CELL
  pure_quanta q_res *
  page278_i58
#CELL
  pure_quanta q_res *
  page278_i59
#ISCELL
  standard offpage *
  page278_i6
#CELL
  pure_quanta q_res *
  page278_i60
#CELL
  pure_quanta q_res *
  page278_i61
#CELL
  pure_quanta q_res *
  page278_i62
#CELL
  pure_quanta q_cap *
  page278_i63
#ISCELL
  logical_power universal_gnd *
  page278_i64
#ISCELL
  logical_power universal_gnd *
  page278_i65
#CELL
  pure_quanta q_cap *
  page278_i66
#CELL
  pure_quanta q_res *
  page278_i67
#ISCELL
  logical_power universal_gnd *
  page278_i68
#CELL
  pure_quanta q_cap *
  page278_i69
#ISCELL
  standard offpage *
  page278_i7
#CELL
  pure_quanta q_res *
  page278_i70
#ISCELL
  logical_power universal_gnd *
  page278_i71
#ISCELL
  standard offpage *
  page278_i72
#CELL
  pure_quanta q_res *
  page278_i73
#ISCELL
  logical_power universal_gnd *
  page278_i74
#CELL
  pure_quanta q_res *
  page278_i75
#ISCELL
  standard offpage *
  page278_i76
#ISCELL
  standard offpage *
  page278_i77
#CELL
  pure_quanta q_res *
  page278_i78
#CELL
  pure_quanta q_res *
  page278_i79
#ISCELL
  standard offpage *
  page278_i8
#CELL
  pure_quanta q_res *
  page278_i80
#CELL
  pure_quanta q_res *
  page278_i81
#ISCELL
  standard offpage *
  page278_i82
#ISCELL
  standard offpage *
  page278_i83
#ISCELL
  logical_power universal_gnd *
  page278_i84
#ISCELL
  logical_power vcc15 *
  page278_i85
#ISCELL
  logical_power universal_gnd *
  page278_i86
#ISCELL
  logical_power universal_gnd *
  page278_i87
#ISCELL
  logical_power universal_gnd *
  page278_i88
#CELL
  pure_quanta q_res *
  page278_i89
#ISCELL
  standard offpage *
  page278_i9
#ISCELL
  standard offpage *
  page278_i90
#ISCELL
  standard offpage *
  page278_i91
#CELL
  pure_quanta q_cap *
  page278_i92
#CELL
  pure_quanta q_cap *
  page278_i93
#ISCELL
  standard offpage *
  page278_i94
#ISCELL
  standard offpage *
  page278_i95
#CELL
  pure_quanta q_cap *
  page278_i96
#CELL
  pure_quanta q_cap *
  page278_i97
#ISCELL
  logical_power universal_gnd *
  page278_i98
#ISCELL
  logical_power universal_gnd *
  page278_i99
#ISCELL
  mstr_misc dns *
  *
#ISCELL
  pure_quanta quanta_title_block_c *
  *
#ISCELL
  logical_power universal_gnd *
  page279_i1
#CELL
  pure_quanta q_cap *
  page279_i10
#CELL
  pure_quanta q_res *
  page279_i11
#ISCELL
  logical_power universal_gnd *
  page279_i12
#CELL
  pure_quanta q_cap *
  page279_i13
#ISCELL
  logical_power vcc15 *
  page279_i14
#ISCELL
  logical_power universal_gnd *
  page279_i15
#CELL
  pure_quanta q_res *
  page279_i16
#ISCELL
  logical_power universal_gnd *
  page279_i17
#ISCELL
  standard offpage *
  page279_i18
#ISCELL
  standard offpage *
  page279_i19
#ISCELL
  logical_power universal_gnd *
  page279_i2
#CELL
  pure_quanta q_cap *
  page279_i20
#ISCELL
  standard offpage *
  page279_i21
#ISCELL
  standard offpage *
  page279_i22
#ISCELL
  logical_power universal_gnd *
  page279_i23
#CELL
  pure_quanta q_cap *
  page279_i24
#CELL
  pure_quanta q_res *
  page279_i25
#CELL
  pure_quanta q_cap *
  page279_i26
#ISCELL
  logical_power universal_gnd *
  page279_i27
#ISCELL
  logical_power vcc15 *
  page279_i28
#CELL
  pure_quanta isl99390frztr5935 *
  page279_i29
#CELL
  pure_quanta q_res *
  page279_i3
#ISCELL
  logical_power universal_gnd *
  page279_i30
#CELL
  pure_quanta q_res *
  page279_i31
#CELL
  pure_quanta q_cap *
  page279_i32
#CELL
  pure_quanta q_cap *
  page279_i33
#CELL
  pure_quanta q_res *
  page279_i34
#ISCELL
  logical_power universal_gnd *
  page279_i35
#CELL
  pure_quanta q_cap *
  page279_i36
#CELL
  pure_quanta q_cap *
  page279_i37
#CELL
  pure_quanta isl99390frztr5935 *
  page279_i38
#ISCELL
  logical_power universal_gnd *
  page279_i39
#ISCELL
  standard offpage *
  page279_i4
#CELL
  pure_quanta q_cap *
  page279_i40
#CELL
  pure_quanta q_cap *
  page279_i41
#CELL
  pure_quanta q_res *
  page279_i42
#CELL
  pure_quanta q_cap *
  page279_i43
#CELL
  pure_quanta q_cap *
  page279_i44
#CELL
  pure_quanta q_cap *
  page279_i45
#CELL
  pure_quanta q_inductor *
  page279_i46
#ISCELL
  logical_power universal_gnd *
  page279_i47
#ISCELL
  logical_power vcc15 *
  page279_i48
#CELL
  pure_quanta q_res *
  page279_i49
#ISCELL
  standard offpage *
  page279_i5
#CELL
  pure_quanta q_res *
  page279_i50
#CELL
  pure_quanta q_cap *
  page279_i51
#CELL
  pure_quanta q_cap *
  page279_i52
#CELL
  pure_quanta q_cap *
  page279_i53
#CELL
  pure_quanta q_inductor *
  page279_i54
#CELL
  pure_quanta q_cap *
  page279_i55
#ISCELL
  logical_power universal_gnd *
  page279_i56
#ISCELL
  logical_power vcc15 *
  page279_i57
#ISCELL
  logical_power vcc15 *
  page279_i58
#CELL
  pure_quanta q_capp *
  page279_i59
#CELL
  pure_quanta q_cap *
  page279_i6
#CELL
  pure_quanta q_capp *
  page279_i60
#CELL
  pure_quanta q_capp *
  page279_i61
#CELL
  pure_quanta q_capp *
  page279_i62
#CELL
  pure_quanta q_cap *
  page279_i63
#ISCELL
  logical_power universal_gnd *
  page279_i64
#CELL
  pure_quanta q_cap *
  page279_i65
#ISCELL
  logical_power vcc15 *
  page279_i66
#ISCELL
  logical_power gnd *
  page279_i67
#CELL
  pure_quanta q_cap *
  page279_i68
#CELL
  pure_quanta q_capp *
  page279_i69
#ISCELL
  standard offpage *
  page279_i7
#CELL
  pure_quanta q_capp *
  page279_i70
#CELL
  pure_quanta q_capp *
  page279_i71
#ISCELL
  logical_power universal_gnd *
  page279_i72
#ISCELL
  logical_power vcc15 *
  page279_i73
#ISCELL
  logical_power universal_gnd *
  page279_i74
#ISCELL
  logical_power vcc15 *
  page279_i75
#ISCELL
  logical_power universal_gnd *
  page279_i76
#ISCELL
  logical_power vcc15 *
  page279_i77
#CELL
  pure_quanta q_inductor *
  page279_i78
#ISCELL
  logical_power vcc15 *
  page279_i79
#ISCELL
  standard offpage *
  page279_i8
#ISCELL
  logical_power universal_gnd *
  page279_i9
#ISCELL
  mstr_misc dns *
  *
#ISCELL
  pure_quanta quanta_title_block_c *
  *
#CELL
  pure_quanta q_res *
  page280_i1
#ISCELL
  standard offpage *
  page280_i10
#CELL
  pure_quanta q_cap *
  page280_i11
#ISCELL
  logical_power universal_gnd *
  page280_i12
#CELL
  pure_quanta q_res *
  page280_i13
#CELL
  pure_quanta raa2213404gnphb0 *
  page280_i14
#CELL
  pure_quanta q_res *
  page280_i15
#CELL
  pure_quanta q_res *
  page280_i16
#ISCELL
  logical_power vcc15 *
  page280_i17
#CELL
  pure_quanta q_res *
  page280_i18
#ISCELL
  logical_power universal_gnd *
  page280_i19
#ISCELL
  logical_power universal_gnd *
  page280_i2
#CELL
  pure_quanta q_res *
  page280_i20
#ISCELL
  logical_power vcc15 *
  page280_i21
#CELL
  pure_quanta q_cap *
  page280_i22
#CELL
  pure_quanta q_inductor *
  page280_i23
#CELL
  pure_quanta q_cap *
  page280_i24
#CELL
  pure_quanta q_res *
  page280_i25
#CELL
  pure_quanta q_cap *
  page280_i26
#CELL
  pure_quanta q_cap *
  page280_i27
#CELL
  pure_quanta q_cap *
  page280_i28
#CELL
  pure_quanta q_cap *
  page280_i29
#ISCELL
  logical_power universal_gnd *
  page280_i3
#CELL
  pure_quanta q_cap *
  page280_i30
#CELL
  pure_quanta q_cap *
  page280_i31
#CELL
  pure_quanta q_capp *
  page280_i32
#CELL
  pure_quanta q_capp *
  page280_i33
#ISCELL
  logical_power universal_gnd *
  page280_i34
#ISCELL
  logical_power vcc15 *
  page280_i35
#ISCELL
  logical_power universal_gnd *
  page280_i36
#CELL
  pure_quanta q_res *
  page280_i37
#ISCELL
  logical_power vcc15 *
  page280_i38
#CELL
  pure_quanta q_res *
  page280_i4
#ISCELL
  logical_power vcc15 *
  page280_i5
#ISCELL
  standard offpage *
  page280_i6
#ISCELL
  standard offpage *
  page280_i7
#ISCELL
  standard offpage *
  page280_i8
#CELL
  pure_quanta q_cap *
  page280_i9
#ISCELL
  pure_quanta quanta_title_block_c *
  *
#ISCELL
  mstr_misc dns *
  *
#ISCELL
  pure_quanta quanta_title_block_c *
  *
#ISCELL
  standard offpage *
  page282_i1
#CELL
  pure_quanta q_res *
  page282_i10
#CELL
  pure_quanta q_res *
  page282_i11
#ISCELL
  logical_power universal_gnd *
  page282_i12
#CELL
  pure_quanta q_cap *
  page282_i13
#ISCELL
  standard offpage *
  page282_i14
#CELL
  pure_quanta q_res *
  page282_i15
#CELL
  pure_quanta q_short *
  page282_i16
#ISCELL
  logical_power universal_gnd *
  page282_i17
#CELL
  pure_quanta q_res *
  page282_i18
#ISCELL
  logical_power vcc15 *
  page282_i19
#ISCELL
  standard offpage *
  page282_i2
#CELL
  pure_quanta q_res *
  page282_i20
#CELL
  pure_quanta q_res *
  page282_i21
#CELL
  pure_quanta q_cap *
  page282_i22
#ISCELL
  logical_power universal_gnd *
  page282_i23
#CELL
  pure_quanta q_cap *
  page282_i24
#ISCELL
  logical_power vcc15 *
  page282_i25
#ISCELL
  standard offpage *
  page282_i26
#ISCELL
  standard offpage *
  page282_i27
#CELL
  pure_quanta q_cap *
  page282_i28
#CELL
  pure_quanta q_res *
  page282_i29
#ISCELL
  standard offpage *
  page282_i3
#ISCELL
  standard offpage *
  page282_i30
#ISCELL
  standard offpage *
  page282_i31
#ISCELL
  standard offpage *
  page282_i32
#CELL
  pure_quanta q_res *
  page282_i33
#ISCELL
  standard offpage *
  page282_i34
#ISCELL
  standard offpage *
  page282_i35
#CELL
  pure_quanta q_res *
  page282_i36
#ISCELL
  logical_power vcc15 *
  page282_i37
#CELL
  pure_quanta q_res *
  page282_i38
#CELL
  pure_quanta q_res *
  page282_i39
#ISCELL
  logical_power universal_gnd *
  page282_i4
#CELL
  pure_quanta q_res *
  page282_i40
#CELL
  pure_quanta q_res *
  page282_i41
#CELL
  pure_quanta q_res *
  page282_i42
#CELL
  pure_quanta q_res *
  page282_i43
#CELL
  pure_quanta q_res *
  page282_i44
#CELL
  pure_quanta q_cap *
  page282_i45
#CELL
  pure_quanta q_res *
  page282_i46
#ISCELL
  logical_power vcc15 *
  page282_i47
#CELL
  pure_quanta q_res *
  page282_i48
#ISCELL
  logical_power universal_gnd *
  page282_i49
#ISCELL
  standard offpage *
  page282_i5
#CELL
  pure_quanta q_cap *
  page282_i50
#CELL
  pure_quanta q_cap *
  page282_i51
#ISCELL
  logical_power universal_gnd *
  page282_i52
#CELL
  pure_quanta isl69260irazt *
  page282_i53
#ISCELL
  logical_power universal_gnd *
  page282_i54
#ISCELL
  logical_power universal_gnd *
  page282_i55
#ISCELL
  logical_power universal_gnd *
  page282_i56
#CELL
  pure_quanta q_cap *
  page282_i57
#CELL
  pure_quanta q_res *
  page282_i58
#CELL
  pure_quanta q_res *
  page282_i59
#ISCELL
  standard offpage *
  page282_i6
#CELL
  pure_quanta q_res *
  page282_i60
#CELL
  pure_quanta q_res *
  page282_i61
#CELL
  pure_quanta q_res *
  page282_i62
#CELL
  pure_quanta q_res *
  page282_i63
#CELL
  pure_quanta q_res *
  page282_i64
#CELL
  pure_quanta q_res *
  page282_i65
#CELL
  pure_quanta q_res *
  page282_i66
#ISCELL
  logical_power universal_gnd *
  page282_i67
#CELL
  pure_quanta q_cap *
  page282_i68
#CELL
  pure_quanta q_cap *
  page282_i69
#CELL
  pure_quanta q_res *
  page282_i70
#ISCELL
  standard offpage *
  page282_i71
#ISCELL
  standard offpage *
  page282_i72
#ISCELL
  logical_power universal_gnd *
  page282_i73
#CELL
  pure_quanta q_cap *
  page282_i74
#ISCELL
  logical_power universal_gnd *
  page282_i75
#ISCELL
  standard offpage *
  page282_i76
#CELL
  pure_quanta q_cap *
  page282_i77
#CELL
  pure_quanta q_res *
  page282_i78
#ISCELL
  logical_power vcc15 *
  page282_i79
#CELL
  pure_quanta q_res *
  page282_i8
#ISCELL
  logical_power universal_gnd *
  page282_i80
#CELL
  pure_quanta q_res *
  page282_i81
#ISCELL
  logical_power universal_gnd *
  page282_i82
#ISCELL
  standard offpage *
  page282_i83
#ISCELL
  logical_power universal_gnd *
  page282_i84
#CELL
  pure_quanta q_res *
  page282_i85
#ISCELL
  logical_power vcc15 *
  page282_i86
#ISCELL
  standard offpage *
  page282_i87
#ISCELL
  standard offpage *
  page282_i88
#ISCELL
  logical_power universal_gnd *
  page282_i89
#CELL
  pure_quanta q_res *
  page282_i9
#ISCELL
  logical_power universal_gnd *
  page282_i90
#ISCELL
  logical_power universal_gnd *
  page282_i91
#ISCELL
  logical_power universal_gnd *
  page282_i92
#ISCELL
  logical_power universal_gnd *
  page282_i93
#ISCELL
  logical_power universal_gnd *
  page282_i94
#CELL
  pure_quanta q_res *
  page282_i95
#CELL
  pure_quanta q_cap *
  page282_i96
#ISCELL
  mstr_misc dns *
  *
#ISCELL
  pure_quanta quanta_title_block_c *
  *
#ISCELL
  logical_power universal_gnd *
  page283_i1
#CELL
  pure_quanta isl99390frztr5935 *
  page283_i10
#ISCELL
  logical_power universal_gnd *
  page283_i11
#CELL
  pure_quanta q_res *
  page283_i12
#CELL
  pure_quanta q_cap *
  page283_i13
#CELL
  pure_quanta q_inductor *
  page283_i14
#CELL
  pure_quanta q_cap *
  page283_i15
#CELL
  pure_quanta q_res *
  page283_i16
#ISCELL
  logical_power vcc15 *
  page283_i17
#CELL
  pure_quanta q_cap *
  page283_i18
#ISCELL
  logical_power universal_gnd *
  page283_i19
#ISCELL
  logical_power universal_gnd *
  page283_i2
#CELL
  pure_quanta q_cap *
  page283_i20
#CELL
  pure_quanta q_res *
  page283_i21
#CELL
  pure_quanta q_cap *
  page283_i22
#CELL
  pure_quanta q_cap *
  page283_i23
#CELL
  pure_quanta q_cap *
  page283_i24
#CELL
  pure_quanta q_capp *
  page283_i25
#CELL
  pure_quanta q_capp *
  page283_i26
#CELL
  pure_quanta q_cap *
  page283_i27
#CELL
  pure_quanta q_cap *
  page283_i28
#CELL
  pure_quanta q_cap *
  page283_i29
#CELL
  pure_quanta q_res *
  page283_i3
#CELL
  pure_quanta q_cap *
  page283_i30
#ISCELL
  logical_power universal_gnd *
  page283_i31
#CELL
  pure_quanta q_capp *
  page283_i32
#ISCELL
  logical_power vcc15 *
  page283_i33
#ISCELL
  logical_power universal_gnd *
  page283_i34
#CELL
  pure_quanta q_res *
  page283_i35
#ISCELL
  logical_power vcc15 *
  page283_i36
#ISCELL
  logical_power universal_gnd *
  page283_i37
#ISCELL
  logical_power vcc15 *
  page283_i38
#ISCELL
  standard offpage *
  page283_i4
#ISCELL
  standard offpage *
  page283_i5
#ISCELL
  standard offpage *
  page283_i6
#ISCELL
  standard offpage *
  page283_i7
#CELL
  pure_quanta q_cap *
  page283_i8
#ISCELL
  logical_power universal_gnd *
  page283_i9
#ISCELL
  pure_quanta quanta_title_block_c *
  *
#ISCELL
  mstr_misc dns *
  *
#ISCELL
  pure_quanta quanta_title_block_c *
  *
#CELL
  pure_quanta q_cap *
  page285_i1
#CELL
  pure_quanta q_res *
  page285_i10
#CELL
  pure_quanta q_cap *
  page285_i11
#ISCELL
  logical_power universal_gnd *
  page285_i12
#CELL
  pure_quanta q_res *
  page285_i13
#CELL
  pure_quanta q_res *
  page285_i14
#CELL
  pure_quanta q_cap *
  page285_i15
#CELL
  pure_quanta q_cap *
  page285_i16
#CELL
  pure_quanta q_cap *
  page285_i17
#CELL
  pure_quanta q_res *
  page285_i18
#ISCELL
  logical_power universal_gnd *
  page285_i19
#ISCELL
  logical_power universal_gnd *
  page285_i2
#ISCELL
  logical_power vccaux15 *
  page285_i20
#ISCELL
  logical_power universal_gnd *
  page285_i21
#ISCELL
  logical_power universal_gnd *
  page285_i22
#CELL
  pure_quanta q_cap *
  page285_i23
#CELL
  pure_quanta q_cap *
  page285_i24
#CELL
  pure_quanta rs53318lr *
  page285_i25
#CELL
  pure_quanta q_cap *
  page285_i26
#CELL
  pure_quanta q_res *
  page285_i27
#CELL
  pure_quanta q_res *
  page285_i28
#CELL
  pure_quanta mosfet_n *
  page285_i29
#CELL
  pure_quanta q_res *
  page285_i3
#CELL
  pure_quanta q_res *
  page285_i30
#ISCELL
  standard offpage *
  page285_i31
#CELL
  pure_quanta q_cap *
  page285_i32
#CELL
  pure_quanta q_inductor *
  page285_i33
#CELL
  pure_quanta q_res *
  page285_i34
#CELL
  pure_quanta q_cap *
  page285_i35
#CELL
  pure_quanta q_cap *
  page285_i36
#CELL
  pure_quanta q_res *
  page285_i37
#ISCELL
  logical_power universal_gnd *
  page285_i38
#CELL
  pure_quanta q_cap *
  page285_i39
#ISCELL
  standard offpage *
  page285_i4
#CELL
  pure_quanta q_cap *
  page285_i40
#CELL
  pure_quanta q_cap *
  page285_i41
#ISCELL
  standard offpage *
  page285_i42
#ISCELL
  logical_power universal_power *
  page285_i43
#CELL
  pure_quanta q_short *
  page285_i44
#ISCELL
  logical_power universal_gnd *
  page285_i45
#CELL
  pure_quanta q_short *
  page285_i46
#CELL
  pure_quanta q_cap *
  page285_i47
#ISCELL
  logical_power universal_gnd *
  page285_i48
#CELL
  pure_quanta q_capp *
  page285_i49
#ISCELL
  logical_power universal_power *
  page285_i5
#ISCELL
  logical_power universal_power *
  page285_i50
#ISCELL
  logical_power vccaux15 *
  page285_i6
#ISCELL
  logical_power universal_gnd *
  page285_i7
#CELL
  pure_quanta q_cap *
  page285_i8
#ISCELL
  logical_power universal_gnd *
  page285_i9
#ISCELL
  mstr_misc dns *
  *
#ISCELL
  pure_quanta quanta_title_block_c *
  *
#ISCELL
  standard offpage *
  page286_i1
#CELL
  pure_quanta q_cap *
  page286_i10
#ISCELL
  logical_power universal_gnd *
  page286_i11
#CELL
  pure_quanta q_res *
  page286_i12
#CELL
  pure_quanta q_res *
  page286_i13
#CELL
  pure_quanta q_cap *
  page286_i14
#ISCELL
  logical_power universal_power *
  page286_i15
#CELL
  pure_quanta q_cap *
  page286_i16
#ISCELL
  logical_power universal_gnd *
  page286_i17
#ISCELL
  logical_power universal_gnd *
  page286_i18
#CELL
  pure_quanta q_res *
  page286_i19
#ISCELL
  logical_power vccaux15 *
  page286_i2
#CELL
  pure_quanta rs53317lr *
  page286_i20
#ISCELL
  logical_power universal_gnd *
  page286_i21
#CELL
  pure_quanta q_res *
  page286_i22
#CELL
  pure_quanta q_cap *
  page286_i23
#CELL
  pure_quanta q_cap *
  page286_i24
#CELL
  pure_quanta q_res *
  page286_i25
#CELL
  pure_quanta q_res *
  page286_i26
#CELL
  pure_quanta q_inductor *
  page286_i27
#CELL
  pure_quanta q_cap *
  page286_i28
#CELL
  pure_quanta q_res *
  page286_i29
#ISCELL
  logical_power universal_gnd *
  page286_i3
#ISCELL
  logical_power vccaux15 *
  page286_i30
#CELL
  pure_quanta q_res *
  page286_i31
#ISCELL
  logical_power universal_power *
  page286_i32
#CELL
  pure_quanta q_cap *
  page286_i33
#CELL
  pure_quanta q_res *
  page286_i34
#ISCELL
  logical_power universal_gnd *
  page286_i35
#CELL
  pure_quanta q_cap *
  page286_i36
#CELL
  pure_quanta q_cap *
  page286_i37
#CELL
  pure_quanta q_cap *
  page286_i38
#ISCELL
  standard offpage *
  page286_i39
#ISCELL
  logical_power universal_gnd *
  page286_i4
#CELL
  pure_quanta q_cap *
  page286_i40
#ISCELL
  logical_power universal_gnd *
  page286_i41
#CELL
  pure_quanta q_res *
  page286_i42
#CELL
  pure_quanta q_res *
  page286_i43
#CELL
  pure_quanta q_cap *
  page286_i44
#CELL
  pure_quanta q_cap *
  page286_i45
#ISCELL
  logical_power universal_gnd *
  page286_i46
#ISCELL
  logical_power universal_power *
  page286_i47
#ISCELL
  logical_power universal_power *
  page286_i48
#CELL
  pure_quanta q_res *
  page286_i5
#CELL
  pure_quanta q_cap *
  page286_i6
#CELL
  pure_quanta q_res *
  page286_i7
#ISCELL
  logical_power universal_gnd *
  page286_i8
#CELL
  pure_quanta q_cap *
  page286_i9
#ISCELL
  mstr_misc dns *
  *
#ISCELL
  pure_quanta quanta_title_block_c *
  *
#ISCELL
  logical_power universal_gnd *
  page303_i1
#CELL
  pure_quanta q_res *
  page303_i10
#ISCELL
  logical_power gnd *
  page303_i11
#CELL
  pure_quanta conn3_210hp1030br1 *
  page303_i12
#ISCELL
  standard offpage *
  page303_i13
#CELL
  pure_quanta q_cap *
  page303_i14
#ISCELL
  standard offpage *
  page303_i15
#CELL
  pure_quanta q_res *
  page303_i17
#ISCELL
  standard offpage *
  page303_i18
#ISCELL
  standard offpage *
  page303_i19
#ISCELL
  standard offpage *
  page303_i2
#ISCELL
  standard offpage *
  page303_i21
#ISCELL
  logical_power universal_gnd *
  page303_i22
#CELL
  pure_quanta q_cap *
  page303_i23
#CELL
  pure_quanta q_res *
  page303_i24
#CELL
  pure_quanta q_res *
  page303_i26
#ISCELL
  standard offpage *
  page303_i27
#ISCELL
  logical_power universal_gnd *
  page303_i28
#CELL
  pure_quanta q_cap *
  page303_i29
#CELL
  pure_quanta q_cap *
  page303_i3
#ISCELL
  standard offpage *
  page303_i30
#ISCELL
  logical_power universal_gnd *
  page303_i31
#CELL
  pure_quanta q_res *
  page303_i32
#CELL
  pure_quanta q_res *
  page303_i33
#ISCELL
  logical_power universal_power *
  page303_i34
#CELL
  pure_quanta q_cap *
  page303_i35
#ISCELL
  logical_power universal_power *
  page303_i36
#CELL
  pure_quanta q_res *
  page303_i37
#CELL
  pure_quanta q_res *
  page303_i38
#ISCELL
  logical_power universal_gnd *
  page303_i39
#CELL
  pure_quanta q_res *
  page303_i4
#CELL
  pure_quanta q_res *
  page303_i40
#CELL
  pure_quanta q_res *
  page303_i41
#CELL
  pure_quanta q_res *
  page303_i42
#CELL
  pure_quanta q_res *
  page303_i43
#CELL
  pure_quanta q_res *
  page303_i44
#CELL
  pure_quanta q_cap *
  page303_i45
#ISCELL
  logical_power universal_power *
  page303_i47
#CELL
  pure_quanta mosfet_nch_gds_esd_protected *
  page303_i5
#ISCELL
  logical_power universal_power *
  page303_i50
#CELL
  pure_quanta q_cap *
  page303_i51
#CELL
  pure_quanta q_res *
  page303_i52
#ISCELL
  logical_power gnd *
  page303_i53
#CELL
  pure_quanta q_res *
  page303_i54
#ISCELL
  logical_power universal_gnd *
  page303_i55
#CELL
  pure_quanta mp5990gma1111z *
  page303_i56
#ISCELL
  logical_power universal_gnd *
  page303_i57
#CELL
  pure_quanta q_res *
  page303_i58
#CELL
  pure_quanta q_res *
  page303_i59
#ISCELL
  logical_power gnd *
  page303_i6
#ISCELL
  logical_power universal_gnd *
  page303_i60
#CELL
  pure_quanta q_res *
  page303_i61
#CELL
  pure_quanta q_res *
  page303_i62
#ISCELL
  standard offpage *
  page303_i63
#ISCELL
  logical_power universal_gnd *
  page303_i64
#ISCELL
  standard offpage *
  page303_i65
#ISCELL
  standard offpage *
  page303_i66
#ISCELL
  standard offpage *
  page303_i67
#ISCELL
  logical_power universal_power *
  page303_i68
#CELL
  pure_quanta q_cap *
  page303_i69
#CELL
  pure_quanta q_res *
  page303_i7
#ISCELL
  standard offpage *
  page303_i70
#ISCELL
  logical_power universal_gnd *
  page303_i71
#ISCELL
  standard offpage *
  page303_i72
#ISCELL
  standard offpage *
  page303_i73
#ISCELL
  logical_power universal_gnd *
  page303_i74
#CELL
  pure_quanta q_cap *
  page303_i75
#CELL
  pure_quanta q_cap *
  page303_i77
#ISCELL
  logical_power universal_gnd *
  page303_i78
#CELL
  pure_quanta q_res *
  page303_i79
#ISCELL
  logical_power gnd *
  page303_i8
#ISCELL
  standard offpage *
  page303_i80
#CELL
  pure_quanta q_res *
  page303_i81
#CELL
  pure_quanta q_res *
  page303_i82
#CELL
  pure_quanta q_res *
  page303_i84
#CELL
  pure_quanta q_res *
  page303_i85
#CELL
  pure_quanta q_res *
  page303_i86
#ISCELL
  logical_power universal_power *
  page303_i87
#ISCELL
  logical_power universal_power *
  page303_i88
#CELL
  pure_quanta q_cap *
  page303_i89
#ISCELL
  logical_power universal_gnd *
  page303_i9
#ISCELL
  logical_power universal_gnd *
  page303_i90
#CELL
  pure_quanta q_res *
  page303_i91
#ISCELL
  standard offpage *
  page303_i92
#CELL
  pure_quanta q_res *
  page303_i93
#ISCELL
  logical_power universal_gnd *
  page303_i94
#ISCELL
  standard offpage *
  page303_i95
#ISCELL
  standard offpage *
  page303_i96
#ISCELL
  logical_power gnd *
  page303_i97
#ISCELL
  mstr_misc dns *
  *
#ISCELL
  pure_quanta quanta_title_block_c *
  *
#ISCELL
  logical_power universal_gnd *
  page301_i1
#ISCELL
  standard offpage *
  page301_i10
#CELL
  pure_quanta q_cap *
  page301_i11
#CELL
  pure_quanta q_res *
  page301_i12
#CELL
  pure_quanta q_res *
  page301_i13
#CELL
  pure_quanta mp5991gluz *
  page301_i14
#CELL
  pure_quanta q_res *
  page301_i15
#ISCELL
  standard offpage *
  page301_i16
#CELL
  pure_quanta q_res *
  page301_i17
#ISCELL
  logical_power universal_power *
  page301_i18
#ISCELL
  logical_power universal_gnd *
  page301_i19
#CELL
  pure_quanta q_cap *
  page301_i2
#CELL
  pure_quanta q_cap *
  page301_i20
#CELL
  pure_quanta q_res *
  page301_i21
#ISCELL
  logical_power universal_gnd *
  page301_i22
#CELL
  pure_quanta q_cap *
  page301_i23
#ISCELL
  standard offpage *
  page301_i24
#ISCELL
  logical_power universal_gnd *
  page301_i25
#ISCELL
  standard offpage *
  page301_i26
#ISCELL
  standard offpage *
  page301_i27
#ISCELL
  logical_power universal_power *
  page301_i28
#CELL
  pure_quanta q_cap *
  page301_i29
#ISCELL
  logical_power universal_gnd *
  page301_i3
#CELL
  pure_quanta q_res *
  page301_i30
#ISCELL
  standard offpage *
  page301_i31
#CELL
  pure_quanta q_res *
  page301_i32
#CELL
  pure_quanta q_res *
  page301_i33
#CELL
  pure_quanta q_res *
  page301_i34
#CELL
  pure_quanta mp5991gluz *
  page301_i35
#ISCELL
  logical_power universal_power *
  page301_i36
#CELL
  pure_quanta q_cap *
  page301_i37
#ISCELL
  logical_power universal_gnd *
  page301_i38
#CELL
  pure_quanta q_res *
  page301_i39
#CELL
  pure_quanta q_cap *
  page301_i4
#CELL
  pure_quanta q_res *
  page301_i40
#ISCELL
  logical_power universal_power *
  page301_i41
#ISCELL
  standard offpage *
  page301_i42
#ISCELL
  standard offpage *
  page301_i43
#ISCELL
  standard offpage *
  page301_i44
#ISCELL
  standard offpage *
  page301_i45
#ISCELL
  standard offpage *
  page301_i46
#CELL
  pure_quanta q_cap *
  page301_i47
#ISCELL
  logical_power universal_gnd *
  page301_i48
#CELL
  pure_quanta q_res *
  page301_i49
#CELL
  pure_quanta q_res *
  page301_i5
#CELL
  pure_quanta q_res *
  page301_i50
#ISCELL
  logical_power universal_power *
  page301_i51
#ISCELL
  standard offpage *
  page301_i52
#ISCELL
  standard offpage *
  page301_i53
#ISCELL
  standard offpage *
  page301_i54
#ISCELL
  standard offpage *
  page301_i55
#ISCELL
  standard offpage *
  page301_i56
#ISCELL
  logical_power universal_power *
  page301_i6
#ISCELL
  standard offpage *
  page301_i7
#ISCELL
  logical_power universal_gnd *
  page301_i8
#ISCELL
  standard offpage *
  page301_i9
#ISCELL
  mstr_misc dns *
  *
#ISCELL
  pure_quanta quanta_title_block_c *
  *
#ISCELL
  logical_power universal_gnd *
  page325_i1
#ISCELL
  standard offpage *
  page325_i10
#CELL
  pure_quanta q_cap *
  page325_i11
#CELL
  pure_quanta q_res *
  page325_i12
#CELL
  pure_quanta q_res *
  page325_i13
#CELL
  pure_quanta q_res *
  page325_i14
#ISCELL
  standard offpage *
  page325_i15
#CELL
  pure_quanta q_res *
  page325_i16
#CELL
  pure_quanta mp5991gluz *
  page325_i17
#ISCELL
  logical_power universal_power *
  page325_i18
#CELL
  pure_quanta q_cap *
  page325_i19
#CELL
  pure_quanta q_cap *
  page325_i2
#ISCELL
  logical_power universal_gnd *
  page325_i20
#CELL
  pure_quanta q_res *
  page325_i21
#ISCELL
  logical_power universal_gnd *
  page325_i22
#CELL
  pure_quanta q_cap *
  page325_i23
#ISCELL
  standard offpage *
  page325_i24
#ISCELL
  logical_power universal_gnd *
  page325_i25
#ISCELL
  standard offpage *
  page325_i26
#ISCELL
  standard offpage *
  page325_i27
#ISCELL
  logical_power universal_power *
  page325_i28
#CELL
  pure_quanta q_cap *
  page325_i29
#ISCELL
  logical_power universal_gnd *
  page325_i3
#CELL
  pure_quanta q_res *
  page325_i30
#ISCELL
  standard offpage *
  page325_i31
#CELL
  pure_quanta q_res *
  page325_i32
#CELL
  pure_quanta q_res *
  page325_i33
#CELL
  pure_quanta q_res *
  page325_i34
#CELL
  pure_quanta mp5991gluz *
  page325_i35
#ISCELL
  logical_power universal_power *
  page325_i36
#ISCELL
  logical_power universal_gnd *
  page325_i37
#CELL
  pure_quanta q_cap *
  page325_i38
#CELL
  pure_quanta q_res *
  page325_i39
#CELL
  pure_quanta q_cap *
  page325_i4
#CELL
  pure_quanta q_res *
  page325_i40
#ISCELL
  logical_power universal_power *
  page325_i41
#ISCELL
  standard offpage *
  page325_i42
#ISCELL
  standard offpage *
  page325_i43
#ISCELL
  standard offpage *
  page325_i44
#ISCELL
  standard offpage *
  page325_i45
#ISCELL
  standard offpage *
  page325_i46
#ISCELL
  logical_power universal_gnd *
  page325_i47
#CELL
  pure_quanta q_cap *
  page325_i48
#CELL
  pure_quanta q_res *
  page325_i49
#CELL
  pure_quanta q_res *
  page325_i5
#CELL
  pure_quanta q_res *
  page325_i50
#ISCELL
  logical_power universal_power *
  page325_i51
#ISCELL
  standard offpage *
  page325_i52
#ISCELL
  standard offpage *
  page325_i53
#ISCELL
  standard offpage *
  page325_i54
#ISCELL
  standard offpage *
  page325_i55
#ISCELL
  standard offpage *
  page325_i56
#ISCELL
  logical_power universal_power *
  page325_i6
#ISCELL
  standard offpage *
  page325_i7
#ISCELL
  logical_power universal_gnd *
  page325_i8
#ISCELL
  standard offpage *
  page325_i9
#ISCELL
  mstr_misc dns *
  *
#ISCELL
  pure_quanta quanta_title_block_c *
  *
#ISCELL
  standard offpage *
  page328_i100
#ISCELL
  standard offpage *
  page328_i101
#ISCELL
  standard offpage *
  page328_i102
#ISCELL
  standard offpage *
  page328_i103
#ISCELL
  standard offpage *
  page328_i104
#ISCELL
  standard offpage *
  page328_i105
#ISCELL
  standard offpage *
  page328_i106
#ISCELL
  standard offpage *
  page328_i107
#ISCELL
  standard offpage *
  page328_i108
#ISCELL
  standard offpage *
  page328_i109
#ISCELL
  standard offpage *
  page328_i110
#ISCELL
  standard offpage *
  page328_i111
#ISCELL
  standard offpage *
  page328_i112
#ISCELL
  standard offpage *
  page328_i113
#ISCELL
  standard offpage *
  page328_i114
#ISCELL
  standard offpage *
  page328_i115
#ISCELL
  standard offpage *
  page328_i116
#CELL
  pure_quanta q_res *
  page328_i117
#CELL
  pure_quanta q_res *
  page328_i118
#CELL
  pure_quanta q_res *
  page328_i119
#CELL
  pure_quanta q_res *
  page328_i120
#ISCELL
  standard offpage *
  page328_i121
#ISCELL
  standard offpage *
  page328_i122
#ISCELL
  standard offpage *
  page328_i123
#ISCELL
  standard offpage *
  page328_i124
#ISCELL
  standard offpage *
  page328_i125
#CELL
  pure_quanta q_res_4p_12 *
  page328_i126
#ISCELL
  standard offpage *
  page328_i15
#CELL
  pure_quanta q_res *
  page328_i16
#CELL
  pure_quanta mosfet_nch_1d3s *
  page328_i35
#CELL
  pure_quanta q_res *
  page328_i38
#CELL
  pure_quanta q_res *
  page328_i39
#CELL
  pure_quanta mosfet_nch_1d3s *
  page328_i40
#CELL
  pure_quanta mosfet_nch_1d3s *
  page328_i41
#ISCELL
  standard offpage *
  page328_i42
#ISCELL
  standard offpage *
  page328_i43
#ISCELL
  standard offpage *
  page328_i50
#CELL
  pure_quanta zener_ac *
  page328_i51
#ISCELL
  logical_power gnd *
  page328_i52
#CELL
  pure_quanta zener_ac *
  page328_i53
#CELL
  pure_quanta q_fuse *
  page328_i54
#ISCELL
  logical_power universal_power *
  page328_i55
#ISCELL
  standard offpage *
  page328_i56
#ISCELL
  standard offpage *
  page328_i57
#ISCELL
  standard offpage *
  page328_i58
#CELL
  pure_quanta q_res *
  page328_i59
#CELL
  pure_quanta q_res *
  page328_i60
#CELL
  pure_quanta q_res *
  page328_i61
#CELL
  pure_quanta mosfet_nch_1d3s *
  page328_i62
#CELL
  pure_quanta q_sp_res4p *
  page328_i63
#CELL
  pure_quanta q_sp_res4p *
  page328_i64
#CELL
  pure_quanta mosfet_nch_1d3s *
  page328_i65
#ISCELL
  standard offpage *
  page328_i66
#ISCELL
  standard offpage *
  page328_i67
#CELL
  pure_quanta q_cap *
  page328_i68
#CELL
  pure_quanta q_cap *
  page328_i69
#CELL
  pure_quanta q_res *
  page328_i70
#ISCELL
  logical_power gnd *
  page328_i71
#CELL
  pure_quanta ss15p3sm386a *
  page328_i72
#CELL
  pure_quanta mosfet_nch_1d3s *
  page328_i73
#ISCELL
  standard offpage *
  page328_i74
#ISCELL
  logical_power universal_power *
  page328_i75
#CELL
  pure_quanta q_res *
  page328_i76
#CELL
  pure_quanta mosfet_nch_1d3s *
  page328_i77
#CELL
  pure_quanta q_sp_res4p *
  page328_i78
#CELL
  pure_quanta q_sp_res4p *
  page328_i79
#ISCELL
  standard offpage *
  page328_i81
#ISCELL
  standard offpage *
  page328_i82
#ISCELL
  standard offpage *
  page328_i83
#ISCELL
  logical_power universal_power *
  page328_i84
#ISCELL
  logical_power universal_power *
  page328_i85
#CELL
  pure_quanta q_res *
  page328_i86
#CELL
  pure_quanta q_res *
  page328_i87
#CELL
  pure_quanta q_res *
  page328_i88
#CELL
  pure_quanta q_res *
  page328_i89
#CELL
  pure_quanta q_res *
  page328_i90
#CELL
  pure_quanta q_res *
  page328_i91
#CELL
  pure_quanta q_res *
  page328_i92
#CELL
  pure_quanta q_res *
  page328_i93
#CELL
  pure_quanta q_res *
  page328_i94
#CELL
  pure_quanta q_res *
  page328_i95
#CELL
  pure_quanta q_res *
  page328_i96
#CELL
  pure_quanta q_res *
  page328_i97
#CELL
  pure_quanta q_res *
  page328_i98
#CELL
  pure_quanta q_res *
  page328_i99
#ISCELL
  mstr_misc dns *
  *
#ISCELL
  pure_quanta quanta_title_block_c *
  *
#CELL
  pure_quanta nct7718w *
  page327_i10
#CELL
  pure_quanta q_res *
  page327_i11
#ISCELL
  logical_power universal_gnd *
  page327_i13
#CELL
  pure_quanta q_res *
  page327_i14
#CELL
  pure_quanta q_res *
  page327_i15
#CELL
  pure_quanta q_res *
  page327_i16
#CELL
  pure_quanta q_res *
  page327_i17
#ISCELL
  logical_power universal_power *
  page327_i18
#ISCELL
  standard offpage *
  page327_i19
#ISCELL
  standard offpage *
  page327_i2
#ISCELL
  standard offpage *
  page327_i20
#ISCELL
  standard offpage *
  page327_i21
#ISCELL
  standard offpage *
  page327_i22
#CELL
  pure_quanta q_res *
  page327_i23
#ISCELL
  logical_power universal_power *
  page327_i24
#CELL
  pure_quanta q_res *
  page327_i25
#CELL
  pure_quanta q_res *
  page327_i26
#ISCELL
  standard offpage *
  page327_i27
#ISCELL
  standard offpage *
  page327_i28
#ISCELL
  standard offpage *
  page327_i29
#ISCELL
  standard offpage *
  page327_i3
#ISCELL
  standard offpage *
  page327_i30
#ISCELL
  standard offpage *
  page327_i31
#ISCELL
  standard offpage *
  page327_i32
#ISCELL
  logical_power universal_gnd *
  page327_i33
#CELL
  pure_quanta sconn21_9193031121lf *
  page327_i34
#ISCELL
  logical_power universal_power *
  page327_i35
#ISCELL
  logical_power universal_gnd *
  page327_i36
#ISCELL
  logical_power universal_gnd *
  page327_i37
#CELL
  pure_quanta q_cap *
  page327_i38
#ISCELL
  standard offpage *
  page327_i39
#CELL
  pure_quanta q_res *
  page327_i4
#ISCELL
  standard offpage *
  page327_i40
#ISCELL
  standard offpage *
  page327_i41
#ISCELL
  standard offpage *
  page327_i42
#ISCELL
  standard offpage *
  page327_i43
#ISCELL
  standard offpage *
  page327_i44
#ISCELL
  standard offpage *
  page327_i45
#ISCELL
  logical_power universal_power *
  page327_i46
#ISCELL
  standard offpage *
  page327_i47
#ISCELL
  logical_power universal_power *
  page327_i48
#CELL
  pure_quanta mmbt3904 *
  page327_i49
#CELL
  pure_quanta q_res *
  page327_i5
#ISCELL
  logical_power gnd *
  page327_i50
#CELL
  pure_quanta conn3_210hp1030br1 *
  page327_i51
#CELL
  pure_quanta q_cap *
  page327_i6
#ISCELL
  logical_power universal_gnd *
  page327_i7
#CELL
  pure_quanta q_cap *
  page327_i8
#ISCELL
  logical_power universal_power *
  page327_i9
#ISCELL
  mstr_misc dns *
  *
#ISCELL
  pure_quanta quanta_title_block_c *
  *
#ISCELL
  logical_power universal_gnd *
  page326_i1
#CELL
  pure_quanta q_res *
  page326_i100
#CELL
  pure_quanta q_res *
  page326_i101
#CELL
  pure_quanta lt6700cs61trpbf *
  page326_i102
#ISCELL
  logical_power universal_power *
  page326_i12
#CELL
  pure_quanta q_res *
  page326_i13
#CELL
  pure_quanta q_res *
  page326_i14
#ISCELL
  logical_power universal_gnd *
  page326_i15
#CELL
  pure_quanta q_res *
  page326_i17
#ISCELL
  logical_power universal_gnd *
  page326_i18
#CELL
  pure_quanta q_res *
  page326_i2
#CELL
  pure_quanta q_res *
  page326_i20
#ISCELL
  logical_power universal_power *
  page326_i21
#ISCELL
  logical_power universal_gnd *
  page326_i23
#CELL
  pure_quanta q_res *
  page326_i24
#CELL
  pure_quanta q_res *
  page326_i25
#ISCELL
  logical_power universal_gnd *
  page326_i26
#CELL
  pure_quanta q_res *
  page326_i29
#ISCELL
  logical_power universal_gnd *
  page326_i3
#CELL
  pure_quanta tps3700ddcr *
  page326_i30
#ISCELL
  standard offpage *
  page326_i31
#CELL
  pure_quanta q_res *
  page326_i33
#ISCELL
  standard offpage *
  page326_i34
#ISCELL
  logical_power universal_gnd *
  page326_i35
#ISCELL
  standard offpage *
  page326_i36
#ISCELL
  logical_power universal_gnd *
  page326_i37
#CELL
  pure_quanta mosfet_n *
  page326_i38
#CELL
  pure_quanta q_res *
  page326_i39
#ISCELL
  logical_power universal_power *
  page326_i40
#CELL
  pure_quanta q_res *
  page326_i41
#ISCELL
  logical_power universal_gnd *
  page326_i42
#ISCELL
  logical_power universal_gnd *
  page326_i43
#CELL
  pure_quanta q_res *
  page326_i44
#CELL
  pure_quanta q_res *
  page326_i45
#CELL
  pure_quanta mosfet_nch_gds_esd_protected *
  page326_i46
#ISCELL
  logical_power universal_gnd *
  page326_i47
#CELL
  pure_quanta q_res *
  page326_i48
#ISCELL
  standard offpage *
  page326_i49
#CELL
  pure_quanta tps3700ddcr *
  page326_i5
#ISCELL
  standard offpage *
  page326_i50
#CELL
  pure_quanta q_res *
  page326_i51
#ISCELL
  logical_power universal_power *
  page326_i52
#CELL
  pure_quanta q_res *
  page326_i53
#ISCELL
  logical_power universal_power *
  page326_i54
#ISCELL
  logical_power universal_gnd *
  page326_i55
#CELL
  pure_quanta lm4040aim3x25nopb *
  page326_i56
#CELL
  pure_quanta q_res *
  page326_i57
#ISCELL
  logical_power universal_power *
  page326_i58
#ISCELL
  logical_power universal_gnd *
  page326_i59
#ISCELL
  logical_power universal_gnd *
  page326_i6
#ISCELL
  logical_power universal_gnd *
  page326_i63
#CELL
  pure_quanta q_cap *
  page326_i64
#ISCELL
  logical_power universal_gnd *
  page326_i65
#CELL
  pure_quanta ap331awg7 *
  page326_i66
#ISCELL
  logical_power universal_gnd *
  page326_i67
#CELL
  pure_quanta q_res *
  page326_i68
#ISCELL
  logical_power universal_power *
  page326_i69
#CELL
  pure_quanta q_res *
  page326_i7
#ISCELL
  logical_power universal_gnd *
  page326_i70
#CELL
  pure_quanta q_cap *
  page326_i71
#CELL
  pure_quanta q_res *
  page326_i72
#ISCELL
  standard offpage *
  page326_i73
#CELL
  pure_quanta q_cap *
  page326_i76
#CELL
  pure_quanta q_res *
  page326_i77
#CELL
  pure_quanta q_res *
  page326_i78
#ISCELL
  standard offpage *
  page326_i79
#ISCELL
  logical_power universal_power *
  page326_i8
#CELL
  pure_quanta q_res *
  page326_i80
#ISCELL
  logical_power universal_power *
  page326_i81
#ISCELL
  standard offpage *
  page326_i82
#ISCELL
  logical_power universal_power *
  page326_i84
#ISCELL
  logical_power universal_power *
  page326_i86
#ISCELL
  logical_power universal_power *
  page326_i87
#CELL
  pure_quanta q_cap *
  page326_i89
#ISCELL
  logical_power universal_gnd *
  page326_i9
#CELL
  pure_quanta q_cap *
  page326_i90
#CELL
  pure_quanta q_cap *
  page326_i91
#CELL
  pure_quanta q_cap *
  page326_i92
#CELL
  pure_quanta q_cap *
  page326_i93
#ISCELL
  logical_power universal_gnd *
  page326_i94
#CELL
  pure_quanta q_cap *
  page326_i95
#ISCELL
  logical_power universal_gnd *
  page326_i96
#CELL
  pure_quanta q_res *
  page326_i97
#CELL
  pure_quanta q_res *
  page326_i98
#CELL
  pure_quanta q_res *
  page326_i99
#ISCELL
  mstr_misc dns *
  *
#ISCELL
  pure_quanta quanta_title_block_c *
  *
#CELL
  pure_quanta q_cap *
  page329_i1
#ISCELL
  logical_power universal_gnd *
  page329_i10
#CELL
  pure_quanta q_cap *
  page329_i11
#CELL
  pure_quanta ap331awg7 *
  page329_i12
#ISCELL
  logical_power universal_gnd *
  page329_i13
#CELL
  pure_quanta q_cap *
  page329_i14
#ISCELL
  logical_power universal_gnd *
  page329_i15
#ISCELL
  logical_power universal_power *
  page329_i16
#CELL
  pure_quanta q_res *
  page329_i17
#ISCELL
  logical_power universal_gnd *
  page329_i18
#ISCELL
  logical_power universal_gnd *
  page329_i19
#CELL
  pure_quanta q_res *
  page329_i2
#ISCELL
  logical_power universal_power *
  page329_i20
#CELL
  pure_quanta q_res *
  page329_i21
#ISCELL
  logical_power universal_gnd *
  page329_i22
#CELL
  pure_quanta ap331awg7 *
  page329_i23
#ISCELL
  logical_power universal_power *
  page329_i24
#CELL
  pure_quanta q_res *
  page329_i25
#ISCELL
  standard offpage *
  page329_i26
#CELL
  pure_quanta q_res *
  page329_i27
#ISCELL
  logical_power universal_gnd *
  page329_i28
#CELL
  pure_quanta q_cap *
  page329_i29
#CELL
  pure_quanta lm4040aim3x25nopb *
  page329_i3
#ISCELL
  logical_power universal_power *
  page329_i30
#CELL
  pure_quanta q_res *
  page329_i31
#ISCELL
  logical_power universal_gnd *
  page329_i32
#CELL
  pure_quanta q_cap *
  page329_i33
#ISCELL
  logical_power universal_gnd *
  page329_i34
#CELL
  pure_quanta q_cap *
  page329_i35
#ISCELL
  logical_power universal_gnd *
  page329_i36
#ISCELL
  logical_power universal_power *
  page329_i37
#CELL
  pure_quanta q_res *
  page329_i38
#CELL
  pure_quanta q_res *
  page329_i39
#ISCELL
  logical_power universal_power *
  page329_i4
#ISCELL
  logical_power universal_gnd *
  page329_i40
#ISCELL
  logical_power universal_power *
  page329_i41
#CELL
  pure_quanta q_res *
  page329_i42
#CELL
  pure_quanta lm4040aim3x25nopb *
  page329_i43
#ISCELL
  logical_power universal_gnd *
  page329_i44
#CELL
  pure_quanta ap331awg7 *
  page329_i45
#CELL
  pure_quanta q_res *
  page329_i46
#ISCELL
  logical_power universal_power *
  page329_i47
#ISCELL
  standard offpage *
  page329_i48
#CELL
  pure_quanta q_res *
  page329_i49
#ISCELL
  standard offpage *
  page329_i5
#CELL
  pure_quanta q_res *
  page329_i50
#CELL
  pure_quanta q_cap *
  page329_i51
#ISCELL
  logical_power universal_power *
  page329_i52
#ISCELL
  logical_power universal_gnd *
  page329_i53
#ISCELL
  logical_power universal_gnd *
  page329_i54
#CELL
  pure_quanta q_cap *
  page329_i55
#ISCELL
  logical_power universal_gnd *
  page329_i56
#CELL
  pure_quanta q_cap *
  page329_i57
#ISCELL
  logical_power universal_gnd *
  page329_i58
#ISCELL
  logical_power universal_power *
  page329_i59
#CELL
  pure_quanta q_res *
  page329_i6
#ISCELL
  logical_power universal_gnd *
  page329_i62
#CELL
  pure_quanta lm4040aim3x25nopb *
  page329_i63
#ISCELL
  logical_power universal_power *
  page329_i64
#CELL
  pure_quanta q_res *
  page329_i65
#ISCELL
  logical_power universal_gnd *
  page329_i66
#CELL
  pure_quanta q_res *
  page329_i67
#CELL
  pure_quanta q_res *
  page329_i68
#CELL
  pure_quanta q_res *
  page329_i7
#ISCELL
  logical_power universal_power *
  page329_i8
#CELL
  pure_quanta q_res *
  page329_i9
#ISCELL
  pure_quanta quanta_title_block_c *
  *
#ISCELL
  logical_power universal_gnd *
  page287_i1
#ISCELL
  logical_power universal_gnd *
  page287_i10
#CELL
  pure_quanta picoprobe_bxa *
  page287_i11
#CELL
  pure_quanta picoprobe_bxa *
  page287_i12
#ISCELL
  logical_power universal_gnd *
  page287_i13
#CELL
  pure_quanta picoprobe_bxa *
  page287_i14
#ISCELL
  logical_power universal_gnd *
  page287_i15
#ISCELL
  logical_power universal_gnd *
  page287_i16
#CELL
  pure_quanta picoprobe_bxa *
  page287_i17
#CELL
  pure_quanta picoprobe_bxa *
  page287_i18
#CELL
  pure_quanta picoprobe_bxa *
  page287_i19
#ISCELL
  logical_power universal_gnd *
  page287_i2
#CELL
  pure_quanta picoprobe_bxa *
  page287_i20
#CELL
  pure_quanta picoprobe_bxa *
  page287_i21
#CELL
  pure_quanta picoprobe_bxa *
  page287_i22
#CELL
  pure_quanta picoprobe_bxa *
  page287_i23
#CELL
  pure_quanta picoprobe_bxa *
  page287_i24
#ISCELL
  logical_power universal_gnd *
  page287_i25
#ISCELL
  logical_power universal_gnd *
  page287_i26
#ISCELL
  logical_power universal_gnd *
  page287_i27
#CELL
  pure_quanta picoprobe_bxa *
  page287_i28
#ISCELL
  logical_power universal_gnd *
  page287_i29
#CELL
  pure_quanta picoprobe_bxa *
  page287_i3
#CELL
  pure_quanta picoprobe_bxa *
  page287_i30
#CELL
  pure_quanta picoprobe_bxa *
  page287_i31
#CELL
  pure_quanta picoprobe_bxa *
  page287_i32
#ISCELL
  logical_power universal_gnd *
  page287_i33
#ISCELL
  logical_power universal_gnd *
  page287_i34
#ISCELL
  logical_power universal_gnd *
  page287_i35
#ISCELL
  logical_power universal_gnd *
  page287_i36
#ISCELL
  logical_power universal_gnd *
  page287_i37
#ISCELL
  logical_power universal_gnd *
  page287_i38
#CELL
  pure_quanta picoprobe_bxa *
  page287_i39
#CELL
  pure_quanta picoprobe_bxa *
  page287_i4
#ISCELL
  logical_power universal_gnd *
  page287_i40
#ISCELL
  logical_power universal_gnd *
  page287_i41
#CELL
  pure_quanta picoprobe_bxa *
  page287_i42
#CELL
  pure_quanta picoprobe_bxa *
  page287_i43
#ISCELL
  logical_power universal_gnd *
  page287_i44
#ISCELL
  logical_power universal_gnd *
  page287_i45
#ISCELL
  logical_power universal_gnd *
  page287_i46
#ISCELL
  logical_power universal_gnd *
  page287_i47
#CELL
  pure_quanta picoprobe_bxa *
  page287_i48
#ISCELL
  logical_power universal_gnd *
  page287_i49
#CELL
  pure_quanta picoprobe_bxa *
  page287_i5
#ISCELL
  logical_power universal_gnd *
  page287_i50
#CELL
  pure_quanta picoprobe_bxa *
  page287_i51
#CELL
  pure_quanta picoprobe_bxa *
  page287_i52
#CELL
  pure_quanta picoprobe_bxa *
  page287_i53
#CELL
  pure_quanta picoprobe_bxa *
  page287_i54
#CELL
  pure_quanta picoprobe_bxa *
  page287_i55
#CELL
  pure_quanta picoprobe_bxa *
  page287_i56
#CELL
  pure_quanta picoprobe_bxa *
  page287_i57
#CELL
  pure_quanta picoprobe_bxa *
  page287_i58
#ISCELL
  logical_power universal_gnd *
  page287_i59
#CELL
  pure_quanta picoprobe_bxa *
  page287_i6
#ISCELL
  logical_power universal_gnd *
  page287_i60
#ISCELL
  logical_power universal_gnd *
  page287_i61
#ISCELL
  logical_power universal_gnd *
  page287_i62
#ISCELL
  logical_power universal_gnd *
  page287_i63
#ISCELL
  logical_power universal_gnd *
  page287_i64
#ISCELL
  logical_power universal_gnd *
  page287_i7
#CELL
  pure_quanta picoprobe_bxa *
  page287_i8
#ISCELL
  logical_power universal_gnd *
  page287_i9
#ISCELL
  pure_quanta quanta_title_block_c *
  *
#CELL
  pure_quanta tp_tdr_4p_fts *
  page288_i10
#ISCELL
  logical_power universal_gnd *
  page288_i100
#CELL
  pure_quanta tdr_3p *
  page288_i101
#ISCELL
  logical_power universal_gnd *
  page288_i102
#ISCELL
  logical_power universal_gnd *
  page288_i103
#ISCELL
  logical_power universal_gnd *
  page288_i104
#ISCELL
  logical_power universal_gnd *
  page288_i105
#CELL
  pure_quanta tp_tdr_4p_fts *
  page288_i106
#CELL
  pure_quanta tp_tdr_4p_fts *
  page288_i107
#CELL
  pure_quanta tp_tdr_4p_fts *
  page288_i108
#ISCELL
  logical_power universal_gnd *
  page288_i109
#CELL
  pure_quanta tp_tdr_4p_fts *
  page288_i11
#CELL
  pure_quanta tp_tdr_4p_fts *
  page288_i110
#ISCELL
  logical_power universal_gnd *
  page288_i111
#CELL
  pure_quanta tp_tdr_4p_fts *
  page288_i112
#ISCELL
  logical_power universal_gnd *
  page288_i113
#ISCELL
  logical_power universal_gnd *
  page288_i114
#CELL
  pure_quanta tp_tdr_4p_fts *
  page288_i115
#CELL
  pure_quanta tp_tdr_4p_fts *
  page288_i116
#CELL
  pure_quanta tp_tdr_4p_fts *
  page288_i117
#ISCELL
  logical_power universal_gnd *
  page288_i118
#ISCELL
  logical_power universal_gnd *
  page288_i119
#CELL
  pure_quanta tp_tdr_4p_fts *
  page288_i12
#ISCELL
  logical_power universal_gnd *
  page288_i13
#CELL
  pure_quanta tp_tdr_4p_fts *
  page288_i17
#CELL
  pure_quanta tp_tdr_4p_fts *
  page288_i18
#CELL
  pure_quanta tp_tdr_4p_fts *
  page288_i19
#CELL
  pure_quanta tp_tdr_4p_fts *
  page288_i26
#CELL
  pure_quanta tp_tdr_4p_fts *
  page288_i27
#CELL
  pure_quanta tp_tdr_4p_fts *
  page288_i28
#CELL
  pure_quanta tp_tdr_4p_fts *
  page288_i3
#CELL
  pure_quanta tp_tdr_4p_fts *
  page288_i30
#CELL
  pure_quanta tp_tdr_4p_fts *
  page288_i32
#CELL
  pure_quanta tp_tdr_4p_fts *
  page288_i33
#CELL
  pure_quanta tp_tdr_4p_fts *
  page288_i34
#CELL
  pure_quanta tp_tdr_4p_fts *
  page288_i35
#CELL
  pure_quanta tp_tdr_4p_fts *
  page288_i37
#CELL
  pure_quanta tp_tdr_4p_fts *
  page288_i39
#CELL
  pure_quanta tp_tdr_4p_fts *
  page288_i4
#CELL
  pure_quanta tp_tdr_4p_fts *
  page288_i42
#CELL
  pure_quanta tp_tdr_4p_fts *
  page288_i43
#CELL
  pure_quanta tp_tdr_4p_fts *
  page288_i46
#CELL
  pure_quanta tp_tdr_4p_fts *
  page288_i47
#CELL
  pure_quanta tdr_3p *
  page288_i49
#ISCELL
  logical_power universal_gnd *
  page288_i50
#CELL
  pure_quanta tdr_3p *
  page288_i51
#ISCELL
  logical_power universal_gnd *
  page288_i52
#CELL
  pure_quanta tdr_3p *
  page288_i53
#ISCELL
  logical_power universal_gnd *
  page288_i54
#CELL
  pure_quanta tdr_3p *
  page288_i55
#ISCELL
  logical_power universal_gnd *
  page288_i56
#CELL
  pure_quanta tdr_3p *
  page288_i57
#ISCELL
  logical_power universal_gnd *
  page288_i58
#ISCELL
  logical_power universal_gnd *
  page288_i59
#CELL
  pure_quanta tdr_3p *
  page288_i60
#CELL
  pure_quanta tdr_3p *
  page288_i61
#CELL
  pure_quanta tdr_3p *
  page288_i62
#CELL
  pure_quanta tdr_3p *
  page288_i63
#ISCELL
  logical_power universal_gnd *
  page288_i64
#ISCELL
  logical_power universal_gnd *
  page288_i65
#ISCELL
  logical_power universal_gnd *
  page288_i66
#CELL
  pure_quanta tdr_3p *
  page288_i67
#CELL
  pure_quanta tdr_3p *
  page288_i68
#CELL
  pure_quanta tdr_3p *
  page288_i69
#ISCELL
  logical_power universal_gnd *
  page288_i70
#ISCELL
  logical_power universal_gnd *
  page288_i71
#ISCELL
  logical_power universal_gnd *
  page288_i72
#ISCELL
  logical_power universal_gnd *
  page288_i73
#ISCELL
  logical_power universal_gnd *
  page288_i74
#ISCELL
  logical_power universal_gnd *
  page288_i75
#ISCELL
  logical_power universal_gnd *
  page288_i76
#ISCELL
  logical_power universal_gnd *
  page288_i77
#ISCELL
  logical_power universal_gnd *
  page288_i78
#ISCELL
  logical_power universal_gnd *
  page288_i79
#CELL
  pure_quanta tp_tdr_4p_fts *
  page288_i8
#ISCELL
  logical_power universal_gnd *
  page288_i80
#ISCELL
  logical_power universal_gnd *
  page288_i81
#ISCELL
  logical_power universal_gnd *
  page288_i82
#ISCELL
  logical_power universal_gnd *
  page288_i83
#ISCELL
  logical_power universal_gnd *
  page288_i84
#ISCELL
  logical_power universal_gnd *
  page288_i85
#ISCELL
  logical_power universal_gnd *
  page288_i86
#ISCELL
  logical_power universal_gnd *
  page288_i87
#ISCELL
  logical_power universal_gnd *
  page288_i88
#ISCELL
  logical_power universal_gnd *
  page288_i89
#CELL
  pure_quanta tp_tdr_4p_fts *
  page288_i9
#ISCELL
  logical_power universal_gnd *
  page288_i90
#ISCELL
  logical_power universal_gnd *
  page288_i91
#ISCELL
  logical_power universal_gnd *
  page288_i92
#ISCELL
  logical_power universal_gnd *
  page288_i93
#ISCELL
  logical_power universal_gnd *
  page288_i94
#ISCELL
  logical_power universal_gnd *
  page288_i95
#CELL
  pure_quanta tdr_3p *
  page288_i96
#CELL
  pure_quanta tdr_3p *
  page288_i97
#ISCELL
  logical_power universal_gnd *
  page288_i98
#CELL
  pure_quanta tdr_3p *
  page288_i99
#ISCELL
  pure_quanta quanta_title_block_c *
  *
#ISCELL
  logical_power universal_gnd *
  page310_i1
#CELL
  pure_quanta tp_tdr_4p_fts *
  page310_i10
#ISCELL
  logical_power universal_gnd *
  page310_i11
#ISCELL
  logical_power universal_gnd *
  page310_i12
#ISCELL
  logical_power universal_gnd *
  page310_i13
#ISCELL
  logical_power universal_gnd *
  page310_i14
#CELL
  pure_quanta tp_tdr_4p_fts *
  page310_i15
#CELL
  pure_quanta tp_tdr_4p_fts *
  page310_i16
#ISCELL
  logical_power universal_gnd *
  page310_i17
#ISCELL
  logical_power universal_gnd *
  page310_i18
#CELL
  pure_quanta tp_tdr_4p_fts *
  page310_i19
#ISCELL
  logical_power universal_gnd *
  page310_i2
#CELL
  pure_quanta tp_tdr_4p_fts *
  page310_i20
#CELL
  pure_quanta tp_tdr_4p_fts *
  page310_i21
#CELL
  pure_quanta tp_tdr_4p_fts *
  page310_i22
#ISCELL
  logical_power universal_gnd *
  page310_i23
#ISCELL
  logical_power universal_gnd *
  page310_i24
#ISCELL
  logical_power universal_gnd *
  page310_i3
#ISCELL
  logical_power universal_gnd *
  page310_i4
#CELL
  pure_quanta tp_tdr_4p_fts *
  page310_i5
#CELL
  pure_quanta tp_tdr_4p_fts *
  page310_i6
#CELL
  pure_quanta tp_tdr_4p_fts *
  page310_i7
#CELL
  pure_quanta tp_tdr_4p_fts *
  page310_i8
#CELL
  pure_quanta tp_tdr_4p_fts *
  page310_i9
#ISCELL
  pure_quanta quanta_title_block_c *
  *
#CELL
  pure_quanta hole *
  page289_i10
#ISCELL
  logical_power universal_gnd *
  page289_i100
#ISCELL
  logical_power universal_gnd *
  page289_i101
#CELL
  pure_quanta hole *
  page289_i11
#CELL
  pure_quanta hole *
  page289_i12
#CELL
  pure_quanta hole *
  page289_i140
#ISCELL
  logical_power universal_gnd *
  page289_i141
#CELL
  pure_quanta hole *
  page289_i144
#ISCELL
  logical_power universal_gnd *
  page289_i145
#ISCELL
  logical_power universal_gnd *
  page289_i146
#CELL
  pure_quanta hole *
  page289_i147
#CELL
  pure_quanta hole *
  page289_i148
#CELL
  pure_quanta hole *
  page289_i149
#CELL
  pure_quanta hole *
  page289_i150
#ISCELL
  logical_power universal_gnd *
  page289_i151
#ISCELL
  logical_power universal_gnd *
  page289_i152
#ISCELL
  logical_power universal_gnd *
  page289_i153
#CELL
  pure_quanta hole *
  page289_i154
#CELL
  pure_quanta hole *
  page289_i155
#ISCELL
  logical_power universal_gnd *
  page289_i156
#ISCELL
  logical_power universal_gnd *
  page289_i157
#CELL
  pure_quanta hole *
  page289_i158
#CELL
  pure_quanta hole *
  page289_i159
#CELL
  pure_quanta hole *
  page289_i160
#CELL
  pure_quanta hole *
  page289_i161
#ISCELL
  logical_power universal_gnd *
  page289_i162
#ISCELL
  logical_power universal_gnd *
  page289_i163
#ISCELL
  logical_power universal_gnd *
  page289_i164
#CELL
  pure_quanta hole *
  page289_i165
#CELL
  pure_quanta hole *
  page289_i166
#CELL
  pure_quanta hole *
  page289_i167
#CELL
  pure_quanta hole *
  page289_i168
#ISCELL
  logical_power universal_gnd *
  page289_i169
#ISCELL
  logical_power universal_gnd *
  page289_i170
#ISCELL
  logical_power universal_gnd *
  page289_i171
#ISCELL
  logical_power universal_gnd *
  page289_i172
#ISCELL
  logical_power universal_gnd *
  page289_i173
#CELL
  pure_quanta hole *
  page289_i174
#CELL
  pure_quanta hole *
  page289_i175
#ISCELL
  logical_power universal_gnd *
  page289_i176
#ISCELL
  logical_power universal_gnd *
  page289_i177
#CELL
  pure_quanta hole *
  page289_i18
#CELL
  pure_quanta hole *
  page289_i19
#CELL
  pure_quanta hole *
  page289_i190
#ISCELL
  logical_power universal_gnd *
  page289_i191
#CELL
  pure_quanta hole *
  page289_i192
#ISCELL
  logical_power universal_gnd *
  page289_i193
#CELL
  pure_quanta hole *
  page289_i20
#CELL
  pure_quanta gnd_hole *
  page289_i202
#ISCELL
  logical_power universal_gnd *
  page289_i203
#CELL
  pure_quanta gnd_hole *
  page289_i204
#ISCELL
  logical_power universal_gnd *
  page289_i205
#ISCELL
  logical_power universal_gnd *
  page289_i206
#CELL
  pure_quanta gnd_hole *
  page289_i207
#CELL
  pure_quanta hole *
  page289_i21
#CELL
  pure_quanta hole *
  page289_i216
#CELL
  pure_quanta hole *
  page289_i217
#CELL
  pure_quanta hole *
  page289_i218
#CELL
  pure_quanta hole *
  page289_i219
#ISCELL
  logical_power universal_gnd *
  page289_i220
#ISCELL
  logical_power universal_gnd *
  page289_i221
#ISCELL
  logical_power universal_gnd *
  page289_i222
#ISCELL
  logical_power universal_gnd *
  page289_i223
#CELL
  pure_quanta hole *
  page289_i224
#CELL
  pure_quanta hole *
  page289_i225
#CELL
  pure_quanta hole *
  page289_i226
#CELL
  pure_quanta hole *
  page289_i227
#CELL
  pure_quanta hole *
  page289_i228
#CELL
  pure_quanta hole *
  page289_i229
#CELL
  pure_quanta hole *
  page289_i232
#ISCELL
  logical_power universal_gnd *
  page289_i233
#CELL
  pure_quanta conn1_10165288101lf *
  page289_i238
#CELL
  pure_quanta conn1_10165288101lf *
  page289_i239
#ISCELL
  logical_power universal_gnd *
  page289_i243
#ISCELL
  logical_power universal_gnd *
  page289_i244
#ISCELL
  logical_power universal_gnd *
  page289_i245
#CELL
  pure_quanta gnd_hole *
  page289_i247
#CELL
  pure_quanta gnd_hole *
  page289_i248
#CELL
  pure_quanta hole *
  page289_i249
#CELL
  pure_quanta hole *
  page289_i254
#CELL
  pure_quanta hole *
  page289_i54
#ISCELL
  logical_power universal_gnd *
  page289_i55
#CELL
  pure_quanta hole *
  page289_i56
#CELL
  pure_quanta hole *
  page289_i57
#CELL
  pure_quanta hole *
  page289_i58
#ISCELL
  logical_power universal_gnd *
  page289_i59
#CELL
  pure_quanta hole *
  page289_i60
#CELL
  pure_quanta hole *
  page289_i61
#CELL
  pure_quanta hole *
  page289_i63
#CELL
  pure_quanta hole *
  page289_i64
#CELL
  pure_quanta hole *
  page289_i7
#CELL
  pure_quanta hole *
  page289_i72
#CELL
  pure_quanta hole *
  page289_i73
#CELL
  pure_quanta hole *
  page289_i74
#CELL
  pure_quanta hole *
  page289_i75
#CELL
  pure_quanta hole *
  page289_i8
#CELL
  pure_quanta hole *
  page289_i83
#CELL
  pure_quanta hole *
  page289_i87
#CELL
  pure_quanta hole *
  page289_i9
#ISCELL
  pure_quanta quanta_title_block_c *
  *
#CELL
  pure_quanta me_dummy_symbol *
  page290_i10
#CELL
  pure_quanta me_dummy_symbol *
  page290_i11
#CELL
  pure_quanta me_dummy_symbol *
  page290_i12
#CELL
  pure_quanta me_dummy_symbol *
  page290_i13
#CELL
  pure_quanta me_dummy_symbol *
  page290_i14
#CELL
  pure_quanta me_dummy_symbol *
  page290_i15
#CELL
  pure_quanta me_dummy_symbol *
  page290_i16
#CELL
  pure_quanta dummy_symbol *
  page290_i17
#CELL
  pure_quanta me_dummy_symbol *
  page290_i18
#CELL
  pure_quanta me_dummy_symbol *
  page290_i19
#CELL
  pure_quanta dummy_symbol *
  page290_i23
#CELL
  pure_quanta tp *
  page290_i40
#CELL
  pure_quanta tp *
  page290_i41
#CELL
  pure_quanta tp *
  page290_i42
#CELL
  pure_quanta tp *
  page290_i43
#CELL
  pure_quanta tp *
  page290_i45
#CELL
  pure_quanta tp *
  page290_i47
#CELL
  pure_quanta me_dummy_symbol *
  page290_i62
#CELL
  pure_quanta me_dummy_symbol *
  page290_i63
#CELL
  pure_quanta me_dummy_symbol *
  page290_i64
#CELL
  pure_quanta me_dummy_symbol *
  page290_i65
#CELL
  pure_quanta tp *
  page290_i69
#CELL
  pure_quanta tp *
  page290_i70
#CELL
  pure_quanta tp *
  page290_i71
#CELL
  pure_quanta tp *
  page290_i72
#CELL
  pure_quanta me_dummy_symbol *
  page290_i73
#CELL
  pure_quanta me_dummy_symbol *
  page290_i74
#CELL
  pure_quanta me_dummy_symbol *
  page290_i75
#CELL
  pure_quanta me_dummy_symbol *
  page290_i76
#CELL
  pure_quanta me_dummy_symbol *
  page290_i9
